G04 ================== begin FILE IDENTIFICATION RECORD ==================*
G04 Layout Name:  D:/<user>/Wistron_project/16315-1/gbr/16315-1.brd*
G04 Film Name:    NOTICE*
G04 File Format:  Gerber RS274X*
G04 File Origin:  Cadence Allegro 16.5-S056*
G04 Origin Date:  Fri Jun 09 15:30:58 2017*
G04 *
G04 Layer:  MANUFACTURING/THERMAL*
G04 *
G04 Offset:    (0.00 0.00)*
G04 Mirror:    No*
G04 Mode:      Positive*
G04 Rotation:  0*
G04 FullContactRelief:  No*
G04 UndefLineWidth:     6.00*
G04 ================== end FILE IDENTIFICATION RECORD ====================*
%FSLAX35Y35*MOIN*%
%IR0*IPPOS*OFA0.00000B0.00000*MIA0B0*SFA1.00000B1.00000*%
%ADD10C,.004*%
%ADD11C,.006*%
%ADD12C,.0033*%
%ADD13C,.008*%
%ADD14C,.0055*%
G75*
%LPD*%
G75*
G36*
G01X415400Y302690D02*
G02X466100Y302950I25558J-40503D01*
G01X454950Y281620D01*
X426450D01*
X415400Y302690D01*
G37*
G36*
G01X412220Y363780D02*
X420900D01*
G03X455010Y363770I17058J11442D01*
G01X462560D01*
X451690Y342770D01*
X423190D01*
X412220Y363780D01*
G37*
G54D10*
G01X933609Y256689D02*
X883609D01*
G01D02*
Y266689D01*
G01Y306689D02*
X903609D01*
G01X883609Y296689D02*
Y306689D01*
G01X903609Y296689D02*
X883609D01*
G01Y266689D02*
X903609D01*
G01X883609Y346689D02*
X903609D01*
G01X883609Y336689D02*
Y346689D01*
G01X903609Y336689D02*
X883609D01*
G01Y386689D02*
X923609D01*
G01X883609Y376689D02*
Y386689D01*
G01X903609Y376689D02*
X883609D01*
G01X934194Y242668D02*
X922194Y244668D01*
G01X933609Y313540D02*
Y256689D01*
G01X934194Y250668D02*
Y230668D01*
G01X922194Y244668D02*
Y240668D01*
G01D02*
X934194Y242668D01*
G01X910194D02*
X934194D01*
G01X903609Y306689D02*
Y336689D01*
G01Y266689D02*
Y296689D01*
G01X923605Y323544D02*
X923609Y323540D01*
G01Y386689D02*
Y323540D01*
G01D02*
X933609Y313540D01*
G01X903609Y346689D02*
Y376689D01*
G01X924114Y408348D02*
Y388348D01*
G01X936114Y394348D02*
Y398348D01*
G01X924114Y396348D02*
X936114Y394348D01*
G01Y398348D02*
X924114Y396348D01*
G01D02*
X964114D01*
G01X966194Y240668D02*
Y244668D01*
G01X953609Y256689D02*
X1003609D01*
G01X953609Y314049D02*
Y256689D01*
G01X973054Y242668D02*
X954194D01*
G01X966194Y244668D02*
X954194Y242668D01*
G01Y230668D02*
Y250668D01*
G01Y242668D02*
X966194Y240668D01*
G01X983609Y306689D02*
Y336689D01*
G01X1003609Y306689D02*
X983609D01*
G01Y296689D02*
X1003609D01*
G01X983609Y266689D02*
Y296689D01*
G01X1003609Y266689D02*
X983609D01*
G01X958609Y314049D02*
X1074600D01*
G01X983609Y346689D02*
Y376689D01*
G01X1003609Y346689D02*
X983609D01*
G01Y336689D02*
X1003609D01*
G01X963609Y386689D02*
Y324049D01*
G01D02*
X953609Y314049D01*
G01X983609Y376689D02*
X1003609D01*
G01X964114Y408348D02*
Y388348D01*
G01Y396348D02*
X972974D01*
G01X952114Y398348D02*
Y394348D01*
G01X964114Y396348D02*
X952114Y398348D01*
G01Y394348D02*
X964114Y396348D01*
G01X1003609Y386689D02*
X963609D01*
G01X1003609Y256689D02*
Y266689D01*
G01X1008609Y306689D02*
X1074600D01*
G01X1003609Y296689D02*
X1003600Y306600D01*
G01X1003609Y336689D02*
Y346689D01*
G01Y376689D02*
Y386689D01*
G01X1071600Y294689D02*
X1069600Y306689D01*
X1067600Y294689D01*
X1071600D01*
G01X1069600Y282689D02*
Y306689D01*
G01X1067600Y326049D02*
X1069600Y314049D01*
X1071600Y326049D01*
X1067600D01*
G01X1069600Y338049D02*
Y314049D01*
G01X1195254Y258188D02*
X1235254D01*
G01X1195254Y268188D02*
Y258188D01*
G01X1215254Y338188D02*
Y308188D01*
G01Y298188D02*
Y268188D01*
G01X1195254Y298188D02*
X1215254D01*
G01X1195254Y308188D02*
Y298188D01*
G01X1215254Y308188D02*
X1195254D01*
G01X1215254Y268188D02*
X1195254D01*
G01X1215254Y378188D02*
Y348188D01*
G01X1195254Y338188D02*
X1215254D01*
G01X1195254Y348188D02*
Y338188D01*
G01X1215254Y348188D02*
X1195254D01*
G01X1245254Y388188D02*
X1195254D01*
G01Y378188D02*
X1215254D01*
G01X1195254Y388188D02*
Y378188D01*
G01X1221254Y408188D02*
X1245254D01*
G01X1275254Y258188D02*
Y321337D01*
G01X1315254Y258188D02*
X1275254D01*
G01X1263254Y242188D02*
Y238188D01*
G01X1275254Y240188D02*
X1263254Y242188D01*
G01Y238188D02*
X1275254Y240188D01*
G01D02*
X1284114D01*
G01X1275254Y252188D02*
Y232188D01*
G01X1235254Y258188D02*
Y320828D01*
G01X1247254Y238188D02*
Y242188D01*
G01X1235254Y240188D02*
X1247254Y238188D01*
G01Y242188D02*
X1235254Y240188D01*
G01D02*
X1275254D01*
G01X1235254Y252188D02*
Y232188D01*
G01X1275258Y321333D02*
X1275254Y321337D01*
G01X1265254Y331337D02*
Y388188D01*
G01X1275254Y321337D02*
X1265254Y331337D01*
G01X1245254Y330828D02*
Y388188D01*
G01X1235254Y320828D02*
X1245254Y330828D01*
G01X1265254Y396188D02*
Y416188D01*
G01Y388188D02*
X1315254D01*
G01X1245254Y416188D02*
Y396188D01*
G01X1277254Y406188D02*
Y410188D01*
G01X1284114Y408188D02*
X1265254D01*
G01D02*
X1277254Y406188D01*
G01Y410188D02*
X1265254Y408188D01*
G01X1233254Y410188D02*
Y406188D01*
G01X1245254Y408188D02*
X1233254Y410188D01*
G01Y406188D02*
X1245254Y408188D01*
G01X1315254Y268188D02*
Y258188D01*
G01Y308188D02*
Y298188D01*
G01D02*
X1295254D01*
G01Y308188D02*
X1315254D01*
G01X1295254Y338188D02*
Y308188D01*
G01Y268188D02*
X1315254D01*
G01X1295254Y298188D02*
Y268188D01*
G01X1315254Y348188D02*
Y338188D01*
G01D02*
X1295254D01*
G01Y348188D02*
X1315254D01*
G01X1295254Y378188D02*
Y348188D01*
G01X1315254Y388188D02*
Y378188D01*
G01D02*
X1295254D01*
G54D11*
G01X117900Y613500D02*
X117850D01*
G01X167900Y859500D02*
X167850D01*
G01X401950Y297620D02*
X396950D01*
Y271620D01*
X401950D01*
G01Y276620D02*
X421450D01*
X410450Y297620D01*
X401950D01*
Y302620D01*
X415450D01*
X426450Y281620D01*
X454950D01*
X465950Y302620D01*
X479450D01*
Y297620D01*
X470950D01*
X459950Y276620D01*
X479450D01*
G01X401950D02*
Y271620D01*
X479450D01*
Y276620D01*
G01X398690Y358770D02*
X393690D01*
Y332770D01*
X398690D01*
G01Y337770D02*
X418190D01*
X407190Y358770D01*
X398690D01*
Y363770D01*
X412190D01*
X423190Y342770D01*
X451690D01*
X462690Y363770D01*
X476190D01*
Y358770D01*
X467690D01*
X456690Y337770D01*
X476190D01*
G01X398690D02*
Y332770D01*
X476190D01*
Y337770D01*
G01X397190Y429630D02*
X392190D01*
Y403630D01*
X397190D01*
G01Y408630D02*
Y403630D01*
X474690D01*
Y408630D01*
G01X417690Y443630D02*
X405690Y441630D01*
X417690Y439630D01*
Y443630D01*
G01X424890Y441630D02*
X405690D01*
G01X397190Y408630D02*
X416690D01*
X405690Y429630D01*
X397190D01*
Y434630D01*
X410690D01*
X421690Y413630D01*
X450190D01*
X461190Y434630D01*
X474690D01*
Y429630D01*
X466190D01*
X455190Y408630D01*
X474690D01*
G01X445970Y310110D02*
X501740D01*
G01X442890Y354800D02*
X501590D01*
G01X443190Y395630D02*
X455190Y397630D01*
X443190Y399630D01*
Y395630D01*
G01X453490Y397630D02*
X455190D01*
G01X428690Y399630D02*
X416690Y397630D01*
X428690Y395630D01*
Y399630D01*
G01X419890Y397630D02*
X416690D01*
G01X453190D02*
X417690D01*
G01X454190Y439630D02*
X466190Y441630D01*
X454190Y443630D01*
Y439630D01*
G01X448490Y441630D02*
X466190D01*
G01X498740Y290930D02*
X496740Y302930D01*
X494740Y290930D01*
X498740D01*
G01X496740Y286050D02*
Y302930D01*
G01X470970D02*
X501740D01*
G01X479450Y297620D02*
X484450D01*
Y271620D01*
X479450D01*
G01X498740Y322110D02*
X496740Y310110D01*
X494740Y322110D01*
X498740D01*
G01X496740Y326650D02*
Y310110D01*
G01X498590Y342800D02*
X496590Y354800D01*
X494590Y342800D01*
X498590D01*
G01X496590Y339300D02*
Y354800D01*
G01X476190Y358770D02*
X481190D01*
Y332770D01*
X476190D01*
G01X498590Y375810D02*
X496590Y363810D01*
X494590Y375810D01*
X498590D01*
G01X496590Y363810D02*
Y378950D01*
G01X459810Y363810D02*
X501590D01*
G01X474690Y429630D02*
X479690D01*
Y403630D01*
X474690D01*
G01X963100Y76349D02*
X934600Y76300D01*
G01X941100Y728429D02*
X943600Y713429D01*
X946100Y728429D01*
X941100D01*
G01X1044940Y713429D02*
X933600D01*
G01X946100Y799629D02*
X943600Y814629D01*
X941100Y799629D01*
X946100D01*
G01X959940Y814629D02*
X933600D01*
G01X963100Y76300D02*
Y148300D01*
X1007100D01*
Y76300D01*
X963100D01*
G01X951103Y74328D02*
X963100Y76349D01*
X951097Y78328D01*
X951103Y74328D01*
G01X978100Y160800D02*
X963100Y158300D01*
X978100Y155800D01*
Y160800D01*
G01X1007100Y158300D02*
X963100D01*
G01Y153300D02*
Y168300D01*
G01X943600Y750675D02*
Y713429D01*
G01Y781925D02*
Y814629D01*
G01X1017100Y76300D02*
X1058100D01*
G01X1017100Y148300D02*
X1058100D01*
G01X992100Y155800D02*
X1007100Y158300D01*
X992100Y160800D01*
Y155800D01*
G01X1015075Y158300D02*
X1007100D01*
G01Y153300D02*
Y168300D01*
G01X1045600Y91300D02*
X1048100Y76300D01*
X1050600Y91300D01*
X1045600D01*
G01X1048100Y100675D02*
Y76300D01*
G01X1050600Y133300D02*
X1048100Y148300D01*
X1045600Y133300D01*
X1050600D01*
G01X1048100Y131925D02*
Y148300D01*
G01X1228553Y717279D02*
X1245100Y705800D01*
X1246100D01*
G01X1233516Y715661D02*
X1228553Y717279D01*
X1231806Y713197D01*
X1233516Y715661D01*
G01X1270254Y331337D02*
X1388100D01*
G01X1320254Y338188D02*
X1388100D01*
G01X1383100Y307337D02*
Y331337D01*
G01X1381100Y350188D02*
X1383100Y338188D01*
X1385100Y350188D01*
X1381100D01*
G01X1383100Y366000D02*
Y338188D01*
G01X1385100Y319337D02*
X1383100Y331337D01*
X1381100Y319337D01*
X1385100D01*
G01X113600Y64300D02*
X808100D01*
G01X113600Y804800D02*
Y19300D01*
G01D02*
X808100D01*
G01X113600Y108300D02*
X808100D01*
G01X113600Y194300D02*
X808100D01*
G01X113600Y209300D02*
X808100D01*
G01X115100Y264300D02*
X808100D01*
G01X113600Y687800D02*
X808100D01*
G01X112600Y742800D02*
X808100D01*
G01X113600Y767800D02*
X808100D01*
G01X113600Y939300D02*
Y797800D01*
X808100D01*
Y939300D01*
G01X120600Y921300D02*
Y926300D01*
X119600Y925300D01*
G01Y921300D02*
X121600D01*
G01X126200Y921133D02*
X126033Y921217D01*
Y921383D01*
X126200Y921467D01*
X126367Y921383D01*
Y921217D01*
X126200Y921133D01*
G01X130050Y921967D02*
X130717Y921550D01*
X131467Y921300D01*
X132133D01*
X132800Y921550D01*
X133300Y921967D01*
X133550Y922550D01*
X133383Y923133D01*
X132967Y923633D01*
X132217Y923967D01*
X131217Y924133D01*
X130633Y924467D01*
X130383Y925050D01*
X130550Y925633D01*
X130967Y926050D01*
X131550Y926300D01*
X132133D01*
X132717Y926133D01*
X133217Y925717D01*
G01X135900Y919633D02*
Y924633D01*
G01Y923883D02*
X136317Y924300D01*
X136733Y924550D01*
X137400Y924633D01*
X137983Y924550D01*
X138567Y924133D01*
X138817Y923550D01*
X138900Y922967D01*
X138817Y922383D01*
X138567Y921800D01*
X138067Y921467D01*
X137400Y921300D01*
X136817Y921383D01*
X136233Y921633D01*
X135900Y921967D01*
G01X141750Y923550D02*
X144417D01*
X144167Y924133D01*
X143750Y924467D01*
X143167Y924633D01*
X142583Y924550D01*
X142083Y924300D01*
X141750Y923717D01*
X141583Y923217D01*
Y922717D01*
X141750Y922217D01*
X142167Y921717D01*
X142667Y921383D01*
X143250Y921300D01*
X143833Y921467D01*
X144417Y921967D01*
G01X149933Y924217D02*
X149350Y924550D01*
X148850Y924633D01*
X148183Y924467D01*
X147683Y924133D01*
X147350Y923550D01*
X147267Y922967D01*
X147350Y922383D01*
X147683Y921883D01*
X148183Y921467D01*
X148850Y921300D01*
X149433Y921467D01*
X149933Y921800D01*
G01X154200Y924633D02*
Y921300D01*
G01Y925967D02*
X154033Y926050D01*
Y926217D01*
X154200Y926300D01*
X154367Y926217D01*
Y926050D01*
X154200Y925967D01*
G01X159300Y921300D02*
Y925550D01*
X159467Y925967D01*
X159800Y926217D01*
X160300Y926300D01*
X160800Y926133D01*
X161050Y925717D01*
G01X160050Y924300D02*
X158383D01*
G01X165400Y924633D02*
Y921300D01*
G01Y925967D02*
X165233Y926050D01*
Y926217D01*
X165400Y926300D01*
X165567Y926217D01*
Y926050D01*
X165400Y925967D01*
G01X172333Y924217D02*
X171750Y924550D01*
X171250Y924633D01*
X170583Y924467D01*
X170083Y924133D01*
X169750Y923550D01*
X169667Y922967D01*
X169750Y922383D01*
X170083Y921883D01*
X170583Y921467D01*
X171250Y921300D01*
X171833Y921467D01*
X172333Y921800D01*
G01X178100Y921300D02*
Y924633D01*
G01Y924050D02*
X177767Y924383D01*
X177267Y924550D01*
X176683Y924633D01*
X176100Y924467D01*
X175600Y924133D01*
X175267Y923633D01*
X175100Y922967D01*
X175267Y922300D01*
X175600Y921800D01*
X176100Y921467D01*
X176683Y921300D01*
X177267Y921383D01*
X177767Y921633D01*
X178100Y921967D01*
G01X182200Y926300D02*
Y921300D01*
G01X181033Y924633D02*
X183367D01*
G01X187800D02*
Y921300D01*
G01Y925967D02*
X187633Y926050D01*
Y926217D01*
X187800Y926300D01*
X187967Y926217D01*
Y926050D01*
X187800Y925967D01*
G01X193400Y921300D02*
X192900Y921383D01*
X192400Y921717D01*
X192067Y922300D01*
X191900Y922967D01*
X192067Y923633D01*
X192400Y924217D01*
X192900Y924550D01*
X193400Y924633D01*
X193900Y924550D01*
X194400Y924217D01*
X194733Y923633D01*
X194817Y922967D01*
X194733Y922300D01*
X194400Y921717D01*
X193900Y921383D01*
X193400Y921300D01*
G01X197583D02*
Y924633D01*
G01Y923800D02*
X197917Y924217D01*
X198417Y924550D01*
X199083Y924633D01*
X199667Y924550D01*
X200167Y924217D01*
X200417Y923633D01*
Y921300D01*
G01X211700Y926300D02*
Y921300D01*
G01Y922050D02*
X211367Y921633D01*
X210867Y921383D01*
X210283Y921300D01*
X209617Y921467D01*
X209117Y921883D01*
X208783Y922383D01*
X208700Y922967D01*
X208783Y923550D01*
X209117Y924050D01*
X209617Y924467D01*
X210283Y924633D01*
X210867Y924550D01*
X211283Y924383D01*
X211700Y924050D01*
G01X215800Y921300D02*
X215300Y921383D01*
X214800Y921717D01*
X214467Y922300D01*
X214300Y922967D01*
X214467Y923633D01*
X214800Y924217D01*
X215300Y924550D01*
X215800Y924633D01*
X216300Y924550D01*
X216800Y924217D01*
X217133Y923633D01*
X217217Y922967D01*
X217133Y922300D01*
X216800Y921717D01*
X216300Y921383D01*
X215800Y921300D01*
G01X222733Y924217D02*
X222150Y924550D01*
X221650Y924633D01*
X220983Y924467D01*
X220483Y924133D01*
X220150Y923550D01*
X220067Y922967D01*
X220150Y922383D01*
X220483Y921883D01*
X220983Y921467D01*
X221650Y921300D01*
X222233Y921467D01*
X222733Y921800D01*
G01X225583Y924633D02*
Y922300D01*
X225917Y921717D01*
X226417Y921383D01*
X227000Y921300D01*
X227583Y921383D01*
X228083Y921717D01*
X228417Y922300D01*
G01Y921300D02*
Y924633D01*
G01X230100Y921300D02*
Y924633D01*
G01Y923717D02*
X230350Y924133D01*
X230767Y924467D01*
X231350Y924633D01*
X231933Y924467D01*
X232350Y924133D01*
X232600Y923717D01*
Y921300D01*
G01Y923717D02*
X232850Y924133D01*
X233267Y924467D01*
X233850Y924633D01*
X234433Y924467D01*
X234850Y924133D01*
X235100Y923633D01*
Y921300D01*
G01X236950Y923550D02*
X239617D01*
X239367Y924133D01*
X238950Y924467D01*
X238367Y924633D01*
X237783Y924550D01*
X237283Y924300D01*
X236950Y923717D01*
X236783Y923217D01*
Y922717D01*
X236950Y922217D01*
X237367Y921717D01*
X237867Y921383D01*
X238450Y921300D01*
X239033Y921467D01*
X239617Y921967D01*
G01X242383Y921300D02*
Y924633D01*
G01Y923800D02*
X242717Y924217D01*
X243217Y924550D01*
X243883Y924633D01*
X244467Y924550D01*
X244967Y924217D01*
X245217Y923633D01*
Y921300D01*
G01X249400Y926300D02*
Y921300D01*
G01X248233Y924633D02*
X250567D01*
G01X255000Y921133D02*
X254833Y921217D01*
Y921383D01*
X255000Y921467D01*
X255167Y921383D01*
Y921217D01*
X255000Y921133D01*
G01Y923383D02*
X254833Y923467D01*
Y923633D01*
X255000Y923717D01*
X255167Y923633D01*
Y923467D01*
X255000Y923383D01*
G01X113600Y909300D02*
X808100D01*
G01X113600Y939300D02*
X808100D01*
G01X125350Y39967D02*
X126017Y39550D01*
X126767Y39300D01*
X127433D01*
X128100Y39550D01*
X128600Y39967D01*
X128850Y40550D01*
X128683Y41133D01*
X128267Y41633D01*
X127517Y41967D01*
X126517Y42133D01*
X125933Y42467D01*
X125683Y43050D01*
X125850Y43633D01*
X126267Y44050D01*
X126850Y44300D01*
X127433D01*
X128017Y44133D01*
X128517Y43717D01*
G01X132700Y42633D02*
Y39300D01*
G01Y43967D02*
X132533Y44050D01*
Y44217D01*
X132700Y44300D01*
X132867Y44217D01*
Y44050D01*
X132700Y43967D01*
G01X138300Y39300D02*
Y44300D01*
G01X142483Y39300D02*
Y44300D01*
G01X145150Y42633D02*
X142483Y40717D01*
G01X143567Y41467D02*
X145317Y39300D01*
G01X148250Y39883D02*
X148667Y39550D01*
X149250Y39300D01*
X149750D01*
X150250Y39467D01*
X150583Y39717D01*
X150750Y40050D01*
X150667Y40550D01*
X150333Y40800D01*
X148833Y41300D01*
X148500Y41883D01*
X148667Y42300D01*
X149000Y42550D01*
X149500Y42633D01*
X150000Y42550D01*
X150500Y42300D01*
G01X156433Y42217D02*
X155850Y42550D01*
X155350Y42633D01*
X154683Y42467D01*
X154183Y42133D01*
X153850Y41550D01*
X153767Y40967D01*
X153850Y40383D01*
X154183Y39883D01*
X154683Y39467D01*
X155350Y39300D01*
X155933Y39467D01*
X156433Y39800D01*
G01X159533Y39300D02*
Y42633D01*
G01Y41967D02*
X159950Y42300D01*
X160367Y42550D01*
X160950Y42633D01*
X161367Y42550D01*
X161867Y42300D01*
G01X165050Y41550D02*
X167717D01*
X167467Y42133D01*
X167050Y42467D01*
X166467Y42633D01*
X165883Y42550D01*
X165383Y42300D01*
X165050Y41717D01*
X164883Y41217D01*
Y40717D01*
X165050Y40217D01*
X165467Y39717D01*
X165967Y39383D01*
X166550Y39300D01*
X167133Y39467D01*
X167717Y39967D01*
G01X170650Y41550D02*
X173317D01*
X173067Y42133D01*
X172650Y42467D01*
X172067Y42633D01*
X171483Y42550D01*
X170983Y42300D01*
X170650Y41717D01*
X170483Y41217D01*
Y40717D01*
X170650Y40217D01*
X171067Y39717D01*
X171567Y39383D01*
X172150Y39300D01*
X172733Y39467D01*
X173317Y39967D01*
G01X176083Y39300D02*
Y42633D01*
G01Y41800D02*
X176417Y42217D01*
X176917Y42550D01*
X177583Y42633D01*
X178167Y42550D01*
X178667Y42217D01*
X178917Y41633D01*
Y39300D01*
G01X125350Y84967D02*
X126017Y84550D01*
X126767Y84300D01*
X127433D01*
X128100Y84550D01*
X128600Y84967D01*
X128850Y85550D01*
X128683Y86133D01*
X128267Y86633D01*
X127517Y86967D01*
X126517Y87133D01*
X125933Y87467D01*
X125683Y88050D01*
X125850Y88633D01*
X126267Y89050D01*
X126850Y89300D01*
X127433D01*
X128017Y89133D01*
X128517Y88717D01*
G01X132700Y84300D02*
X132200Y84383D01*
X131700Y84717D01*
X131367Y85300D01*
X131200Y85967D01*
X131367Y86633D01*
X131700Y87217D01*
X132200Y87550D01*
X132700Y87633D01*
X133200Y87550D01*
X133700Y87217D01*
X134033Y86633D01*
X134117Y85967D01*
X134033Y85300D01*
X133700Y84717D01*
X133200Y84383D01*
X132700Y84300D01*
G01X138300D02*
Y89300D01*
G01X145400D02*
Y84300D01*
G01Y85050D02*
X145067Y84633D01*
X144567Y84383D01*
X143983Y84300D01*
X143317Y84467D01*
X142817Y84883D01*
X142483Y85383D01*
X142400Y85967D01*
X142483Y86550D01*
X142817Y87050D01*
X143317Y87467D01*
X143983Y87633D01*
X144567Y87550D01*
X144983Y87383D01*
X145400Y87050D01*
G01X148250Y86550D02*
X150917D01*
X150667Y87133D01*
X150250Y87467D01*
X149667Y87633D01*
X149083Y87550D01*
X148583Y87300D01*
X148250Y86717D01*
X148083Y86217D01*
Y85717D01*
X148250Y85217D01*
X148667Y84717D01*
X149167Y84383D01*
X149750Y84300D01*
X150333Y84467D01*
X150917Y84967D01*
G01X153933Y84300D02*
Y87633D01*
G01Y86967D02*
X154350Y87300D01*
X154767Y87550D01*
X155350Y87633D01*
X155767Y87550D01*
X156267Y87300D01*
G01X163800Y84300D02*
Y87633D01*
G01Y86717D02*
X164050Y87133D01*
X164467Y87467D01*
X165050Y87633D01*
X165633Y87467D01*
X166050Y87133D01*
X166300Y86717D01*
Y84300D01*
G01Y86717D02*
X166550Y87133D01*
X166967Y87467D01*
X167550Y87633D01*
X168133Y87467D01*
X168550Y87133D01*
X168800Y86633D01*
Y84300D01*
G01X173400D02*
Y87633D01*
G01Y87050D02*
X173067Y87383D01*
X172567Y87550D01*
X171983Y87633D01*
X171400Y87467D01*
X170900Y87133D01*
X170567Y86633D01*
X170400Y85967D01*
X170567Y85300D01*
X170900Y84800D01*
X171400Y84467D01*
X171983Y84300D01*
X172567Y84383D01*
X173067Y84633D01*
X173400Y84967D01*
G01X176250Y84883D02*
X176667Y84550D01*
X177250Y84300D01*
X177750D01*
X178250Y84467D01*
X178583Y84717D01*
X178750Y85050D01*
X178667Y85550D01*
X178333Y85800D01*
X176833Y86300D01*
X176500Y86883D01*
X176667Y87300D01*
X177000Y87550D01*
X177500Y87633D01*
X178000Y87550D01*
X178500Y87300D01*
G01X181683Y84300D02*
Y89300D01*
G01X184350Y87633D02*
X181683Y85717D01*
G01X182767Y86467D02*
X184517Y84300D01*
G01X128767Y152800D02*
X125433D01*
Y157800D01*
X128767D01*
G01X127433Y155383D02*
X125433D01*
G01X132700Y157800D02*
Y152800D01*
G01X131533Y156133D02*
X133867D01*
G01X139633Y155717D02*
X139050Y156050D01*
X138550Y156133D01*
X137883Y155967D01*
X137383Y155633D01*
X137050Y155050D01*
X136967Y154467D01*
X137050Y153883D01*
X137383Y153383D01*
X137883Y152967D01*
X138550Y152800D01*
X139133Y152967D01*
X139633Y153300D01*
G01X142483Y152800D02*
Y157800D01*
G01Y155383D02*
X142900Y155800D01*
X143317Y156050D01*
X143983Y156133D01*
X144483Y156050D01*
X145067Y155717D01*
X145317Y155217D01*
Y152800D01*
G01X128767Y200300D02*
X125433D01*
Y205300D01*
X128767D01*
G01X127433Y202883D02*
X125433D01*
G01X131450Y203633D02*
X133950Y200300D01*
G01Y203633D02*
X131450Y200300D01*
G01X138300Y205300D02*
Y200300D01*
G01X137133Y203633D02*
X139467D01*
G01X142650Y202550D02*
X145317D01*
X145067Y203133D01*
X144650Y203467D01*
X144067Y203633D01*
X143483Y203550D01*
X142983Y203300D01*
X142650Y202717D01*
X142483Y202217D01*
Y201717D01*
X142650Y201217D01*
X143067Y200717D01*
X143567Y200383D01*
X144150Y200300D01*
X144733Y200467D01*
X145317Y200967D01*
G01X148333Y200300D02*
Y203633D01*
G01Y202967D02*
X148750Y203300D01*
X149167Y203550D01*
X149750Y203633D01*
X150167Y203550D01*
X150667Y203300D01*
G01X153683Y200300D02*
Y203633D01*
G01Y202800D02*
X154017Y203217D01*
X154517Y203550D01*
X155183Y203633D01*
X155767Y203550D01*
X156267Y203217D01*
X156517Y202633D01*
Y200300D01*
G01X162200D02*
Y203633D01*
G01Y203050D02*
X161867Y203383D01*
X161367Y203550D01*
X160783Y203633D01*
X160200Y203467D01*
X159700Y203133D01*
X159367Y202633D01*
X159200Y201967D01*
X159367Y201300D01*
X159700Y200800D01*
X160200Y200467D01*
X160783Y200300D01*
X161367Y200383D01*
X161867Y200633D01*
X162200Y200967D01*
G01X166300Y200300D02*
Y205300D01*
G01X177500Y200300D02*
Y205300D01*
G01X184600Y200300D02*
Y203633D01*
G01Y203050D02*
X184267Y203383D01*
X183767Y203550D01*
X183183Y203633D01*
X182600Y203467D01*
X182100Y203133D01*
X181767Y202633D01*
X181600Y201967D01*
X181767Y201300D01*
X182100Y200800D01*
X182600Y200467D01*
X183183Y200300D01*
X183767Y200383D01*
X184267Y200633D01*
X184600Y200967D01*
G01X186950Y198800D02*
X187450Y198633D01*
X188117Y198800D01*
X188533Y199133D01*
X188867Y199550D01*
X189367Y200883D01*
X190450Y203633D01*
G01X187783D02*
X189367Y200883D01*
G01X193050Y202550D02*
X195717D01*
X195467Y203133D01*
X195050Y203467D01*
X194467Y203633D01*
X193883Y203550D01*
X193383Y203300D01*
X193050Y202717D01*
X192883Y202217D01*
Y201717D01*
X193050Y201217D01*
X193467Y200717D01*
X193967Y200383D01*
X194550Y200300D01*
X195133Y200467D01*
X195717Y200967D01*
G01X198733Y200300D02*
Y203633D01*
G01Y202967D02*
X199150Y203300D01*
X199567Y203550D01*
X200150Y203633D01*
X200567Y203550D01*
X201067Y203300D01*
G01X128933Y234883D02*
X128433Y235133D01*
X127850Y235300D01*
X127183D01*
X126433Y235050D01*
X125850Y234633D01*
X125433Y234133D01*
X125100Y233300D01*
X125017Y232550D01*
X125183Y231800D01*
X125433Y231300D01*
X125933Y230800D01*
X126517Y230467D01*
X127100Y230300D01*
X127683D01*
X128267Y230467D01*
X128767Y230717D01*
X129183Y231050D01*
G01X132700Y230300D02*
X132200Y230383D01*
X131700Y230717D01*
X131367Y231300D01*
X131200Y231967D01*
X131367Y232633D01*
X131700Y233217D01*
X132200Y233550D01*
X132700Y233633D01*
X133200Y233550D01*
X133700Y233217D01*
X134033Y232633D01*
X134117Y231967D01*
X134033Y231300D01*
X133700Y230717D01*
X133200Y230383D01*
X132700Y230300D01*
G01X136800Y228633D02*
Y233633D01*
G01Y232883D02*
X137217Y233300D01*
X137633Y233550D01*
X138300Y233633D01*
X138883Y233550D01*
X139467Y233133D01*
X139717Y232550D01*
X139800Y231967D01*
X139717Y231383D01*
X139467Y230800D01*
X138967Y230467D01*
X138300Y230300D01*
X137717Y230383D01*
X137133Y230633D01*
X136800Y230967D01*
G01X142400Y228633D02*
Y233633D01*
G01Y232883D02*
X142817Y233300D01*
X143233Y233550D01*
X143900Y233633D01*
X144483Y233550D01*
X145067Y233133D01*
X145317Y232550D01*
X145400Y231967D01*
X145317Y231383D01*
X145067Y230800D01*
X144567Y230467D01*
X143900Y230300D01*
X143317Y230383D01*
X142733Y230633D01*
X142400Y230967D01*
G01X148250Y232550D02*
X150917D01*
X150667Y233133D01*
X150250Y233467D01*
X149667Y233633D01*
X149083Y233550D01*
X148583Y233300D01*
X148250Y232717D01*
X148083Y232217D01*
Y231717D01*
X148250Y231217D01*
X148667Y230717D01*
X149167Y230383D01*
X149750Y230300D01*
X150333Y230467D01*
X150917Y230967D01*
G01X153933Y230300D02*
Y233633D01*
G01Y232967D02*
X154350Y233300D01*
X154767Y233550D01*
X155350Y233633D01*
X155767Y233550D01*
X156267Y233300D01*
G01X164633Y230300D02*
Y235300D01*
X166633D01*
X167300Y235050D01*
X167800Y234467D01*
X167967Y233800D01*
X167800Y233133D01*
X167383Y232633D01*
X166633Y232383D01*
X164633D01*
G01X171900Y230300D02*
Y235300D01*
G01X179000Y230300D02*
Y233633D01*
G01Y233050D02*
X178667Y233383D01*
X178167Y233550D01*
X177583Y233633D01*
X177000Y233467D01*
X176500Y233133D01*
X176167Y232633D01*
X176000Y231967D01*
X176167Y231300D01*
X176500Y230800D01*
X177000Y230467D01*
X177583Y230300D01*
X178167Y230383D01*
X178667Y230633D01*
X179000Y230967D01*
G01X183100Y235300D02*
Y230300D01*
G01X181933Y233633D02*
X184267D01*
G01X188700D02*
Y230300D01*
G01Y234967D02*
X188533Y235050D01*
Y235217D01*
X188700Y235300D01*
X188867Y235217D01*
Y235050D01*
X188700Y234967D01*
G01X192883Y230300D02*
Y233633D01*
G01Y232800D02*
X193217Y233217D01*
X193717Y233550D01*
X194383Y233633D01*
X194967Y233550D01*
X195467Y233217D01*
X195717Y232633D01*
Y230300D01*
G01X198733Y229050D02*
X199317Y228717D01*
X199983Y228633D01*
X200567Y228717D01*
X201067Y229133D01*
X201400Y229717D01*
Y233633D01*
G01Y232967D02*
X201067Y233300D01*
X200567Y233550D01*
X199983Y233633D01*
X199317Y233467D01*
X198900Y233133D01*
X198567Y232550D01*
X198400Y231967D01*
X198483Y231467D01*
X198817Y230883D01*
X199317Y230467D01*
X199983Y230300D01*
X200483Y230383D01*
X201067Y230717D01*
X201400Y231050D01*
G01X125267Y547800D02*
Y552800D01*
X126933D01*
X127600Y552550D01*
X128100Y552217D01*
X128517Y551717D01*
X128850Y551133D01*
X128933Y550300D01*
X128850Y549467D01*
X128517Y548883D01*
X128100Y548383D01*
X127600Y548050D01*
X126933Y547800D01*
X125267D01*
G01X131533D02*
Y551133D01*
G01Y550467D02*
X131950Y550800D01*
X132367Y551050D01*
X132950Y551133D01*
X133367Y551050D01*
X133867Y550800D01*
G01X138300Y551133D02*
Y547800D01*
G01Y552467D02*
X138133Y552550D01*
Y552717D01*
X138300Y552800D01*
X138467Y552717D01*
Y552550D01*
X138300Y552467D01*
G01X143900Y547800D02*
Y552800D01*
G01X149500Y547800D02*
Y552800D01*
G01X138560Y715540D02*
X140560D01*
G01X139560D02*
Y710540D01*
G01X138560D02*
X140560D01*
G01X143743D02*
Y713873D01*
G01Y713040D02*
X144077Y713457D01*
X144577Y713790D01*
X145243Y713873D01*
X145827Y713790D01*
X146327Y713457D01*
X146577Y712873D01*
Y710540D01*
G01X149343D02*
Y713873D01*
G01Y713040D02*
X149677Y713457D01*
X150177Y713790D01*
X150843Y713873D01*
X151427Y713790D01*
X151927Y713457D01*
X152177Y712873D01*
Y710540D01*
G01X155110Y712790D02*
X157777D01*
X157527Y713373D01*
X157110Y713707D01*
X156527Y713873D01*
X155943Y713790D01*
X155443Y713540D01*
X155110Y712957D01*
X154943Y712457D01*
Y711957D01*
X155110Y711457D01*
X155527Y710957D01*
X156027Y710623D01*
X156610Y710540D01*
X157193Y710707D01*
X157777Y711207D01*
G01X160793Y710540D02*
Y713873D01*
G01Y713207D02*
X161210Y713540D01*
X161627Y713790D01*
X162210Y713873D01*
X162627Y713790D01*
X163127Y713540D01*
G01X173160Y710540D02*
Y715540D01*
G01X180260Y710540D02*
Y713873D01*
G01Y713290D02*
X179927Y713623D01*
X179427Y713790D01*
X178843Y713873D01*
X178260Y713707D01*
X177760Y713373D01*
X177427Y712873D01*
X177260Y712207D01*
X177427Y711540D01*
X177760Y711040D01*
X178260Y710707D01*
X178843Y710540D01*
X179427Y710623D01*
X179927Y710873D01*
X180260Y711207D01*
G01X182610Y709040D02*
X183110Y708873D01*
X183777Y709040D01*
X184193Y709373D01*
X184527Y709790D01*
X185027Y711123D01*
X186110Y713873D01*
G01X183443D02*
X185027Y711123D01*
G01X188710Y712790D02*
X191377D01*
X191127Y713373D01*
X190710Y713707D01*
X190127Y713873D01*
X189543Y713790D01*
X189043Y713540D01*
X188710Y712957D01*
X188543Y712457D01*
Y711957D01*
X188710Y711457D01*
X189127Y710957D01*
X189627Y710623D01*
X190210Y710540D01*
X190793Y710707D01*
X191377Y711207D01*
G01X194393Y710540D02*
Y713873D01*
G01Y713207D02*
X194810Y713540D01*
X195227Y713790D01*
X195810Y713873D01*
X196227Y713790D01*
X196727Y713540D01*
G01X123517Y782467D02*
X124017Y782967D01*
X124600Y783217D01*
X125267Y783300D01*
X126100Y783133D01*
X126683Y782717D01*
X126850Y782217D01*
X126767Y781717D01*
X126433Y781300D01*
X124767Y780467D01*
X124017Y779883D01*
X123517Y779050D01*
X123350Y778300D01*
X126850D01*
G01X130700Y778133D02*
X130533Y778217D01*
Y778383D01*
X130700Y778467D01*
X130867Y778383D01*
Y778217D01*
X130700Y778133D01*
G01X136300Y783300D02*
Y778300D01*
G01X134383Y783300D02*
X138217D01*
G01X141900Y778300D02*
X141400Y778383D01*
X140900Y778717D01*
X140567Y779300D01*
X140400Y779967D01*
X140567Y780633D01*
X140900Y781217D01*
X141400Y781550D01*
X141900Y781633D01*
X142400Y781550D01*
X142900Y781217D01*
X143233Y780633D01*
X143317Y779967D01*
X143233Y779300D01*
X142900Y778717D01*
X142400Y778383D01*
X141900Y778300D01*
G01X147500D02*
Y783300D01*
G01X151850Y780550D02*
X154517D01*
X154267Y781133D01*
X153850Y781467D01*
X153267Y781633D01*
X152683Y781550D01*
X152183Y781300D01*
X151850Y780717D01*
X151683Y780217D01*
Y779717D01*
X151850Y779217D01*
X152267Y778717D01*
X152767Y778383D01*
X153350Y778300D01*
X153933Y778467D01*
X154517Y778967D01*
G01X157533Y778300D02*
Y781633D01*
G01Y780967D02*
X157950Y781300D01*
X158367Y781550D01*
X158950Y781633D01*
X159367Y781550D01*
X159867Y781300D01*
G01X165800Y778300D02*
Y781633D01*
G01Y781050D02*
X165467Y781383D01*
X164967Y781550D01*
X164383Y781633D01*
X163800Y781467D01*
X163300Y781133D01*
X162967Y780633D01*
X162800Y779967D01*
X162967Y779300D01*
X163300Y778800D01*
X163800Y778467D01*
X164383Y778300D01*
X164967Y778383D01*
X165467Y778633D01*
X165800Y778967D01*
G01X168483Y778300D02*
Y781633D01*
G01Y780800D02*
X168817Y781217D01*
X169317Y781550D01*
X169983Y781633D01*
X170567Y781550D01*
X171067Y781217D01*
X171317Y780633D01*
Y778300D01*
G01X176833Y781217D02*
X176250Y781550D01*
X175750Y781633D01*
X175083Y781467D01*
X174583Y781133D01*
X174250Y780550D01*
X174167Y779967D01*
X174250Y779383D01*
X174583Y778883D01*
X175083Y778467D01*
X175750Y778300D01*
X176333Y778467D01*
X176833Y778800D01*
G01X179850Y780550D02*
X182517D01*
X182267Y781133D01*
X181850Y781467D01*
X181267Y781633D01*
X180683Y781550D01*
X180183Y781300D01*
X179850Y780717D01*
X179683Y780217D01*
Y779717D01*
X179850Y779217D01*
X180267Y778717D01*
X180767Y778383D01*
X181350Y778300D01*
X181933Y778467D01*
X182517Y778967D01*
G01X192300Y783300D02*
Y778300D01*
G01X191133Y781633D02*
X193467D01*
G01X199400Y778300D02*
Y781633D01*
G01Y781050D02*
X199067Y781383D01*
X198567Y781550D01*
X197983Y781633D01*
X197400Y781467D01*
X196900Y781133D01*
X196567Y780633D01*
X196400Y779967D01*
X196567Y779300D01*
X196900Y778800D01*
X197400Y778467D01*
X197983Y778300D01*
X198567Y778383D01*
X199067Y778633D01*
X199400Y778967D01*
G01X202000Y778300D02*
Y783300D01*
G01Y780800D02*
X202417Y781300D01*
X202917Y781550D01*
X203417Y781633D01*
X204167Y781467D01*
X204667Y781133D01*
X205000Y780550D01*
Y779883D01*
X204833Y779217D01*
X204500Y778717D01*
X203917Y778383D01*
X203417Y778300D01*
X202917Y778383D01*
X202417Y778633D01*
X202000Y779050D01*
G01X209100Y778300D02*
Y783300D01*
G01X213450Y780550D02*
X216117D01*
X215867Y781133D01*
X215450Y781467D01*
X214867Y781633D01*
X214283Y781550D01*
X213783Y781300D01*
X213450Y780717D01*
X213283Y780217D01*
Y779717D01*
X213450Y779217D01*
X213867Y778717D01*
X214367Y778383D01*
X214950Y778300D01*
X215533Y778467D01*
X216117Y778967D01*
G01X220300Y778133D02*
X220133Y778217D01*
Y778383D01*
X220300Y778467D01*
X220467Y778383D01*
Y778217D01*
X220300Y778133D01*
G01Y780383D02*
X220133Y780467D01*
Y780633D01*
X220300Y780717D01*
X220467Y780633D01*
Y780467D01*
X220300Y780383D01*
G01X147600Y752133D02*
Y757133D01*
G01Y756383D02*
X148017Y756800D01*
X148433Y757050D01*
X149100Y757133D01*
X149683Y757050D01*
X150267Y756633D01*
X150517Y756050D01*
X150600Y755467D01*
X150517Y754883D01*
X150267Y754300D01*
X149767Y753967D01*
X149100Y753800D01*
X148517Y753883D01*
X147933Y754133D01*
X147600Y754467D01*
G01X153533Y753800D02*
Y757133D01*
G01Y756467D02*
X153950Y756800D01*
X154367Y757050D01*
X154950Y757133D01*
X155367Y757050D01*
X155867Y756800D01*
G01X160300Y753800D02*
X159800Y753883D01*
X159300Y754217D01*
X158967Y754800D01*
X158800Y755467D01*
X158967Y756133D01*
X159300Y756717D01*
X159800Y757050D01*
X160300Y757133D01*
X160800Y757050D01*
X161300Y756717D01*
X161633Y756133D01*
X161717Y755467D01*
X161633Y754800D01*
X161300Y754217D01*
X160800Y753883D01*
X160300Y753800D01*
G01X167233Y756717D02*
X166650Y757050D01*
X166150Y757133D01*
X165483Y756967D01*
X164983Y756633D01*
X164650Y756050D01*
X164567Y755467D01*
X164650Y754883D01*
X164983Y754383D01*
X165483Y753967D01*
X166150Y753800D01*
X166733Y753967D01*
X167233Y754300D01*
G01X170250Y756050D02*
X172917D01*
X172667Y756633D01*
X172250Y756967D01*
X171667Y757133D01*
X171083Y757050D01*
X170583Y756800D01*
X170250Y756217D01*
X170083Y755717D01*
Y755217D01*
X170250Y754717D01*
X170667Y754217D01*
X171167Y753883D01*
X171750Y753800D01*
X172333Y753967D01*
X172917Y754467D01*
G01X175850Y754383D02*
X176267Y754050D01*
X176850Y753800D01*
X177350D01*
X177850Y753967D01*
X178183Y754217D01*
X178350Y754550D01*
X178267Y755050D01*
X177933Y755300D01*
X176433Y755800D01*
X176100Y756383D01*
X176267Y756800D01*
X176600Y757050D01*
X177100Y757133D01*
X177600Y757050D01*
X178100Y756800D01*
G01X181450Y754383D02*
X181867Y754050D01*
X182450Y753800D01*
X182950D01*
X183450Y753967D01*
X183783Y754217D01*
X183950Y754550D01*
X183867Y755050D01*
X183533Y755300D01*
X182033Y755800D01*
X181700Y756383D01*
X181867Y756800D01*
X182200Y757050D01*
X182700Y757133D01*
X183200Y757050D01*
X183700Y756800D01*
G01X170600Y891300D02*
X172600D01*
G01X171600D02*
Y886300D01*
G01X170600D02*
X172600D01*
G01X176700D02*
Y890550D01*
X176867Y890967D01*
X177200Y891217D01*
X177700Y891300D01*
X178200Y891133D01*
X178450Y890717D01*
G01X177450Y889300D02*
X175783D01*
G01X188400Y891300D02*
Y886300D01*
G01X187233Y889633D02*
X189567D01*
G01X192583Y886300D02*
Y891300D01*
G01Y888883D02*
X193000Y889300D01*
X193417Y889550D01*
X194083Y889633D01*
X194583Y889550D01*
X195167Y889217D01*
X195417Y888717D01*
Y886300D01*
G01X198350Y888550D02*
X201017D01*
X200767Y889133D01*
X200350Y889467D01*
X199767Y889633D01*
X199183Y889550D01*
X198683Y889300D01*
X198350Y888717D01*
X198183Y888217D01*
Y887717D01*
X198350Y887217D01*
X198767Y886717D01*
X199267Y886383D01*
X199850Y886300D01*
X200433Y886467D01*
X201017Y886967D01*
G01X212133Y889217D02*
X211550Y889550D01*
X211050Y889633D01*
X210383Y889467D01*
X209883Y889133D01*
X209550Y888550D01*
X209467Y887967D01*
X209550Y887383D01*
X209883Y886883D01*
X210383Y886467D01*
X211050Y886300D01*
X211633Y886467D01*
X212133Y886800D01*
G01X215233Y886300D02*
Y889633D01*
G01Y888967D02*
X215650Y889300D01*
X216067Y889550D01*
X216650Y889633D01*
X217067Y889550D01*
X217567Y889300D01*
G01X222000Y889633D02*
Y886300D01*
G01Y890967D02*
X221833Y891050D01*
Y891217D01*
X222000Y891300D01*
X222167Y891217D01*
Y891050D01*
X222000Y890967D01*
G01X227600Y891300D02*
Y886300D01*
G01X226433Y889633D02*
X228767D01*
G01X231950Y888550D02*
X234617D01*
X234367Y889133D01*
X233950Y889467D01*
X233367Y889633D01*
X232783Y889550D01*
X232283Y889300D01*
X231950Y888717D01*
X231783Y888217D01*
Y887717D01*
X231950Y887217D01*
X232367Y886717D01*
X232867Y886383D01*
X233450Y886300D01*
X234033Y886467D01*
X234617Y886967D01*
G01X237633Y886300D02*
Y889633D01*
G01Y888967D02*
X238050Y889300D01*
X238467Y889550D01*
X239050Y889633D01*
X239467Y889550D01*
X239967Y889300D01*
G01X244400Y889633D02*
Y886300D01*
G01Y890967D02*
X244233Y891050D01*
Y891217D01*
X244400Y891300D01*
X244567Y891217D01*
Y891050D01*
X244400Y890967D01*
G01X251500Y886300D02*
Y889633D01*
G01Y889050D02*
X251167Y889383D01*
X250667Y889550D01*
X250083Y889633D01*
X249500Y889467D01*
X249000Y889133D01*
X248667Y888633D01*
X248500Y887967D01*
X248667Y887300D01*
X249000Y886800D01*
X249500Y886467D01*
X250083Y886300D01*
X250667Y886383D01*
X251167Y886633D01*
X251500Y886967D01*
G01X261200Y889633D02*
Y886300D01*
G01Y890967D02*
X261033Y891050D01*
Y891217D01*
X261200Y891300D01*
X261367Y891217D01*
Y891050D01*
X261200Y890967D01*
G01X265550Y886883D02*
X265967Y886550D01*
X266550Y886300D01*
X267050D01*
X267550Y886467D01*
X267883Y886717D01*
X268050Y887050D01*
X267967Y887550D01*
X267633Y887800D01*
X266133Y888300D01*
X265800Y888883D01*
X265967Y889300D01*
X266300Y889550D01*
X266800Y889633D01*
X267300Y889550D01*
X267800Y889300D01*
G01X276583Y886300D02*
Y889633D01*
G01Y888800D02*
X276917Y889217D01*
X277417Y889550D01*
X278083Y889633D01*
X278667Y889550D01*
X279167Y889217D01*
X279417Y888633D01*
Y886300D01*
G01X283600D02*
X283100Y886383D01*
X282600Y886717D01*
X282267Y887300D01*
X282100Y887967D01*
X282267Y888633D01*
X282600Y889217D01*
X283100Y889550D01*
X283600Y889633D01*
X284100Y889550D01*
X284600Y889217D01*
X284933Y888633D01*
X285017Y887967D01*
X284933Y887300D01*
X284600Y886717D01*
X284100Y886383D01*
X283600Y886300D01*
G01X289200Y891300D02*
Y886300D01*
G01X288033Y889633D02*
X290367D01*
G01X299150Y886883D02*
X299567Y886550D01*
X300150Y886300D01*
X300650D01*
X301150Y886467D01*
X301483Y886717D01*
X301650Y887050D01*
X301567Y887550D01*
X301233Y887800D01*
X299733Y888300D01*
X299400Y888883D01*
X299567Y889300D01*
X299900Y889550D01*
X300400Y889633D01*
X300900Y889550D01*
X301400Y889300D01*
G01X304500Y884633D02*
Y889633D01*
G01Y888883D02*
X304917Y889300D01*
X305333Y889550D01*
X306000Y889633D01*
X306583Y889550D01*
X307167Y889133D01*
X307417Y888550D01*
X307500Y887967D01*
X307417Y887383D01*
X307167Y886800D01*
X306667Y886467D01*
X306000Y886300D01*
X305417Y886383D01*
X304833Y886633D01*
X304500Y886967D01*
G01X310350Y888550D02*
X313017D01*
X312767Y889133D01*
X312350Y889467D01*
X311767Y889633D01*
X311183Y889550D01*
X310683Y889300D01*
X310350Y888717D01*
X310183Y888217D01*
Y887717D01*
X310350Y887217D01*
X310767Y886717D01*
X311267Y886383D01*
X311850Y886300D01*
X312433Y886467D01*
X313017Y886967D01*
G01X318533Y889217D02*
X317950Y889550D01*
X317450Y889633D01*
X316783Y889467D01*
X316283Y889133D01*
X315950Y888550D01*
X315867Y887967D01*
X315950Y887383D01*
X316283Y886883D01*
X316783Y886467D01*
X317450Y886300D01*
X318033Y886467D01*
X318533Y886800D01*
G01X322800Y889633D02*
Y886300D01*
G01Y890967D02*
X322633Y891050D01*
Y891217D01*
X322800Y891300D01*
X322967Y891217D01*
Y891050D01*
X322800Y890967D01*
G01X327900Y886300D02*
Y890550D01*
X328067Y890967D01*
X328400Y891217D01*
X328900Y891300D01*
X329400Y891133D01*
X329650Y890717D01*
G01X328650Y889300D02*
X326983D01*
G01X334000Y889633D02*
Y886300D01*
G01Y890967D02*
X333833Y891050D01*
Y891217D01*
X334000Y891300D01*
X334167Y891217D01*
Y891050D01*
X334000Y890967D01*
G01X338350Y888550D02*
X341017D01*
X340767Y889133D01*
X340350Y889467D01*
X339767Y889633D01*
X339183Y889550D01*
X338683Y889300D01*
X338350Y888717D01*
X338183Y888217D01*
Y887717D01*
X338350Y887217D01*
X338767Y886717D01*
X339267Y886383D01*
X339850Y886300D01*
X340433Y886467D01*
X341017Y886967D01*
G01X346700Y891300D02*
Y886300D01*
G01Y887050D02*
X346367Y886633D01*
X345867Y886383D01*
X345283Y886300D01*
X344617Y886467D01*
X344117Y886883D01*
X343783Y887383D01*
X343700Y887967D01*
X343783Y888550D01*
X344117Y889050D01*
X344617Y889467D01*
X345283Y889633D01*
X345867Y889550D01*
X346283Y889383D01*
X346700Y889050D01*
G01X356400Y889633D02*
Y886300D01*
G01Y890967D02*
X356233Y891050D01*
Y891217D01*
X356400Y891300D01*
X356567Y891217D01*
Y891050D01*
X356400Y890967D01*
G01X360583Y886300D02*
Y889633D01*
G01Y888800D02*
X360917Y889217D01*
X361417Y889550D01*
X362083Y889633D01*
X362667Y889550D01*
X363167Y889217D01*
X363417Y888633D01*
Y886300D01*
G01X373200Y891300D02*
Y886300D01*
G01X372033Y889633D02*
X374367D01*
G01X377383Y886300D02*
Y891300D01*
G01Y888883D02*
X377800Y889300D01*
X378217Y889550D01*
X378883Y889633D01*
X379383Y889550D01*
X379967Y889217D01*
X380217Y888717D01*
Y886300D01*
G01X383150Y888550D02*
X385817D01*
X385567Y889133D01*
X385150Y889467D01*
X384567Y889633D01*
X383983Y889550D01*
X383483Y889300D01*
X383150Y888717D01*
X382983Y888217D01*
Y887717D01*
X383150Y887217D01*
X383567Y886717D01*
X384067Y886383D01*
X384650Y886300D01*
X385233Y886467D01*
X385817Y886967D01*
G01X395600Y891300D02*
Y886300D01*
G01X394433Y889633D02*
X396767D01*
G01X402700Y886300D02*
Y889633D01*
G01Y889050D02*
X402367Y889383D01*
X401867Y889550D01*
X401283Y889633D01*
X400700Y889467D01*
X400200Y889133D01*
X399867Y888633D01*
X399700Y887967D01*
X399867Y887300D01*
X400200Y886800D01*
X400700Y886467D01*
X401283Y886300D01*
X401867Y886383D01*
X402367Y886633D01*
X402700Y886967D01*
G01X405300Y886300D02*
Y891300D01*
G01Y888800D02*
X405717Y889300D01*
X406217Y889550D01*
X406717Y889633D01*
X407467Y889467D01*
X407967Y889133D01*
X408300Y888550D01*
Y887883D01*
X408133Y887217D01*
X407800Y886717D01*
X407217Y886383D01*
X406717Y886300D01*
X406217Y886383D01*
X405717Y886633D01*
X405300Y887050D01*
G01X412400Y886300D02*
Y891300D01*
G01X416750Y888550D02*
X419417D01*
X419167Y889133D01*
X418750Y889467D01*
X418167Y889633D01*
X417583Y889550D01*
X417083Y889300D01*
X416750Y888717D01*
X416583Y888217D01*
Y887717D01*
X416750Y887217D01*
X417167Y886717D01*
X417667Y886383D01*
X418250Y886300D01*
X418833Y886467D01*
X419417Y886967D01*
G01X423600Y886133D02*
X423433Y886217D01*
Y886383D01*
X423600Y886467D01*
X423767Y886383D01*
Y886217D01*
X423600Y886133D01*
G01Y888383D02*
X423433Y888467D01*
Y888633D01*
X423600Y888717D01*
X423767Y888633D01*
Y888467D01*
X423600Y888383D01*
G01X217100Y767800D02*
Y19300D01*
G01Y34300D02*
X808100D01*
G01X217100Y79300D02*
X808100D01*
G01X217100Y149300D02*
X808100D01*
G01X217100Y537800D02*
X808100D01*
G01X217100Y512800D02*
X808100D01*
G01X217100Y672800D02*
X808100D01*
G01X217100Y702800D02*
X808100D01*
G01X217100Y717800D02*
X808100D01*
G01X180600Y814233D02*
X180433Y814317D01*
Y814483D01*
X180600Y814567D01*
X180767Y814483D01*
Y814317D01*
X180600Y814233D01*
G01Y823233D02*
X180433Y823317D01*
Y823483D01*
X180600Y823567D01*
X180767Y823483D01*
Y823317D01*
X180600Y823233D01*
G01Y832233D02*
X180433Y832317D01*
Y832483D01*
X180600Y832567D01*
X180767Y832483D01*
Y832317D01*
X180600Y832233D01*
G01Y841233D02*
X180433Y841317D01*
Y841483D01*
X180600Y841567D01*
X180767Y841483D01*
Y841317D01*
X180600Y841233D01*
G01X184600Y818400D02*
X186600D01*
G01X185600D02*
Y813400D01*
G01X184600D02*
X186600D01*
G01X189533D02*
Y818400D01*
X191533D01*
X192200Y818150D01*
X192700Y817567D01*
X192867Y816900D01*
X192700Y816233D01*
X192283Y815733D01*
X191533Y815483D01*
X189533D01*
G01X198633Y817983D02*
X198133Y818233D01*
X197550Y818400D01*
X196883D01*
X196133Y818150D01*
X195550Y817733D01*
X195133Y817233D01*
X194800Y816400D01*
X194717Y815650D01*
X194883Y814900D01*
X195133Y814400D01*
X195633Y813900D01*
X196217Y813567D01*
X196800Y813400D01*
X197383D01*
X197967Y813567D01*
X198467Y813817D01*
X198883Y814150D01*
G01X201317Y815067D02*
X203483D01*
G01X206333Y818400D02*
Y813400D01*
X209667D01*
G01X212517Y815067D02*
X214683D01*
G01X219200Y813400D02*
Y818400D01*
X218200Y817400D01*
G01Y813400D02*
X220200D01*
G01X224800Y818400D02*
X224133Y818233D01*
X223633Y817817D01*
X223300Y817317D01*
X223050Y816650D01*
X222967Y815900D01*
X223050Y815150D01*
X223300Y814483D01*
X223633Y813983D01*
X224133Y813567D01*
X224800Y813400D01*
X225467Y813567D01*
X225967Y813983D01*
X226300Y814483D01*
X226550Y815150D01*
X226633Y815900D01*
X226550Y816650D01*
X226300Y817317D01*
X225967Y817817D01*
X225467Y818233D01*
X224800Y818400D01*
G01X228983Y813983D02*
X229567Y813567D01*
X230233Y813400D01*
X230900Y813567D01*
X231483Y814067D01*
X231900Y814817D01*
X232067Y815567D01*
Y816483D01*
X231900Y817233D01*
X231483Y817900D01*
X230983Y818233D01*
X230400Y818400D01*
X229733Y818233D01*
X229233Y817900D01*
X228900Y817400D01*
X228733Y816733D01*
X228900Y816150D01*
X229317Y815567D01*
X229817Y815233D01*
X230400Y815150D01*
X231067Y815317D01*
X231567Y815733D01*
X232067Y816483D01*
G01X239850Y814067D02*
X240517Y813650D01*
X241267Y813400D01*
X241933D01*
X242600Y813650D01*
X243100Y814067D01*
X243350Y814650D01*
X243183Y815233D01*
X242767Y815733D01*
X242017Y816067D01*
X241017Y816233D01*
X240433Y816567D01*
X240183Y817150D01*
X240350Y817733D01*
X240767Y818150D01*
X241350Y818400D01*
X241933D01*
X242517Y818233D01*
X243017Y817817D01*
G01X245700Y811733D02*
Y816733D01*
G01Y815983D02*
X246117Y816400D01*
X246533Y816650D01*
X247200Y816733D01*
X247783Y816650D01*
X248367Y816233D01*
X248617Y815650D01*
X248700Y815067D01*
X248617Y814483D01*
X248367Y813900D01*
X247867Y813567D01*
X247200Y813400D01*
X246617Y813483D01*
X246033Y813733D01*
X245700Y814067D01*
G01X251550Y815650D02*
X254217D01*
X253967Y816233D01*
X253550Y816567D01*
X252967Y816733D01*
X252383Y816650D01*
X251883Y816400D01*
X251550Y815817D01*
X251383Y815317D01*
Y814817D01*
X251550Y814317D01*
X251967Y813817D01*
X252467Y813483D01*
X253050Y813400D01*
X253633Y813567D01*
X254217Y814067D01*
G01X259733Y816317D02*
X259150Y816650D01*
X258650Y816733D01*
X257983Y816567D01*
X257483Y816233D01*
X257150Y815650D01*
X257067Y815067D01*
X257150Y814483D01*
X257483Y813983D01*
X257983Y813567D01*
X258650Y813400D01*
X259233Y813567D01*
X259733Y813900D01*
G01X264000Y816733D02*
Y813400D01*
G01Y818067D02*
X263833Y818150D01*
Y818317D01*
X264000Y818400D01*
X264167Y818317D01*
Y818150D01*
X264000Y818067D01*
G01X269100Y813400D02*
Y817650D01*
X269267Y818067D01*
X269600Y818317D01*
X270100Y818400D01*
X270600Y818233D01*
X270850Y817817D01*
G01X269850Y816400D02*
X268183D01*
G01X275200Y816733D02*
Y813400D01*
G01Y818067D02*
X275033Y818150D01*
Y818317D01*
X275200Y818400D01*
X275367Y818317D01*
Y818150D01*
X275200Y818067D01*
G01X282133Y816317D02*
X281550Y816650D01*
X281050Y816733D01*
X280383Y816567D01*
X279883Y816233D01*
X279550Y815650D01*
X279467Y815067D01*
X279550Y814483D01*
X279883Y813983D01*
X280383Y813567D01*
X281050Y813400D01*
X281633Y813567D01*
X282133Y813900D01*
G01X287900Y813400D02*
Y816733D01*
G01Y816150D02*
X287567Y816483D01*
X287067Y816650D01*
X286483Y816733D01*
X285900Y816567D01*
X285400Y816233D01*
X285067Y815733D01*
X284900Y815067D01*
X285067Y814400D01*
X285400Y813900D01*
X285900Y813567D01*
X286483Y813400D01*
X287067Y813483D01*
X287567Y813733D01*
X287900Y814067D01*
G01X292000Y818400D02*
Y813400D01*
G01X290833Y816733D02*
X293167D01*
G01X297600D02*
Y813400D01*
G01Y818067D02*
X297433Y818150D01*
Y818317D01*
X297600Y818400D01*
X297767Y818317D01*
Y818150D01*
X297600Y818067D01*
G01X303200Y813400D02*
X302700Y813483D01*
X302200Y813817D01*
X301867Y814400D01*
X301700Y815067D01*
X301867Y815733D01*
X302200Y816317D01*
X302700Y816650D01*
X303200Y816733D01*
X303700Y816650D01*
X304200Y816317D01*
X304533Y815733D01*
X304617Y815067D01*
X304533Y814400D01*
X304200Y813817D01*
X303700Y813483D01*
X303200Y813400D01*
G01X307383D02*
Y816733D01*
G01Y815900D02*
X307717Y816317D01*
X308217Y816650D01*
X308883Y816733D01*
X309467Y816650D01*
X309967Y816317D01*
X310217Y815733D01*
Y813400D01*
G01X319500D02*
Y817650D01*
X319667Y818067D01*
X320000Y818317D01*
X320500Y818400D01*
X321000Y818233D01*
X321250Y817817D01*
G01X320250Y816400D02*
X318583D01*
G01X325600Y813400D02*
X325100Y813483D01*
X324600Y813817D01*
X324267Y814400D01*
X324100Y815067D01*
X324267Y815733D01*
X324600Y816317D01*
X325100Y816650D01*
X325600Y816733D01*
X326100Y816650D01*
X326600Y816317D01*
X326933Y815733D01*
X327017Y815067D01*
X326933Y814400D01*
X326600Y813817D01*
X326100Y813483D01*
X325600Y813400D01*
G01X330033D02*
Y816733D01*
G01Y816067D02*
X330450Y816400D01*
X330867Y816650D01*
X331450Y816733D01*
X331867Y816650D01*
X332367Y816400D01*
G01X340733Y813400D02*
Y818400D01*
X342817D01*
X343483Y818150D01*
X343900Y817817D01*
X344067Y817150D01*
X343900Y816483D01*
X343400Y816067D01*
X342817Y815817D01*
X340733D01*
G01X342817D02*
X344067Y813400D01*
G01X346750Y815650D02*
X349417D01*
X349167Y816233D01*
X348750Y816567D01*
X348167Y816733D01*
X347583Y816650D01*
X347083Y816400D01*
X346750Y815817D01*
X346583Y815317D01*
Y814817D01*
X346750Y814317D01*
X347167Y813817D01*
X347667Y813483D01*
X348250Y813400D01*
X348833Y813567D01*
X349417Y814067D01*
G01X352350Y813983D02*
X352767Y813650D01*
X353350Y813400D01*
X353850D01*
X354350Y813567D01*
X354683Y813817D01*
X354850Y814150D01*
X354767Y814650D01*
X354433Y814900D01*
X352933Y815400D01*
X352600Y815983D01*
X352767Y816400D01*
X353100Y816650D01*
X353600Y816733D01*
X354100Y816650D01*
X354600Y816400D01*
G01X359200Y816733D02*
Y813400D01*
G01Y818067D02*
X359033Y818150D01*
Y818317D01*
X359200Y818400D01*
X359367Y818317D01*
Y818150D01*
X359200Y818067D01*
G01X363383Y813400D02*
Y816733D01*
G01Y815900D02*
X363717Y816317D01*
X364217Y816650D01*
X364883Y816733D01*
X365467Y816650D01*
X365967Y816317D01*
X366217Y815733D01*
Y813400D01*
G01X375000Y818400D02*
X377000D01*
G01X376000D02*
Y813400D01*
G01X375000D02*
X377000D01*
G01X379100D02*
Y816733D01*
G01Y815817D02*
X379350Y816233D01*
X379767Y816567D01*
X380350Y816733D01*
X380933Y816567D01*
X381350Y816233D01*
X381600Y815817D01*
Y813400D01*
G01Y815817D02*
X381850Y816233D01*
X382267Y816567D01*
X382850Y816733D01*
X383433Y816567D01*
X383850Y816233D01*
X384100Y815733D01*
Y813400D01*
G01X385700Y811733D02*
Y816733D01*
G01Y815983D02*
X386117Y816400D01*
X386533Y816650D01*
X387200Y816733D01*
X387783Y816650D01*
X388367Y816233D01*
X388617Y815650D01*
X388700Y815067D01*
X388617Y814483D01*
X388367Y813900D01*
X387867Y813567D01*
X387200Y813400D01*
X386617Y813483D01*
X386033Y813733D01*
X385700Y814067D01*
G01X391633Y813400D02*
Y816733D01*
G01Y816067D02*
X392050Y816400D01*
X392467Y816650D01*
X393050Y816733D01*
X393467Y816650D01*
X393967Y816400D01*
G01X397150Y815650D02*
X399817D01*
X399567Y816233D01*
X399150Y816567D01*
X398567Y816733D01*
X397983Y816650D01*
X397483Y816400D01*
X397150Y815817D01*
X396983Y815317D01*
Y814817D01*
X397150Y814317D01*
X397567Y813817D01*
X398067Y813483D01*
X398650Y813400D01*
X399233Y813567D01*
X399817Y814067D01*
G01X402833Y812150D02*
X403417Y811817D01*
X404083Y811733D01*
X404667Y811817D01*
X405167Y812233D01*
X405500Y812817D01*
Y816733D01*
G01Y816067D02*
X405167Y816400D01*
X404667Y816650D01*
X404083Y816733D01*
X403417Y816567D01*
X403000Y816233D01*
X402667Y815650D01*
X402500Y815067D01*
X402583Y814567D01*
X402917Y813983D01*
X403417Y813567D01*
X404083Y813400D01*
X404583Y813483D01*
X405167Y813817D01*
X405500Y814150D01*
G01X408183Y813400D02*
Y816733D01*
G01Y815900D02*
X408517Y816317D01*
X409017Y816650D01*
X409683Y816733D01*
X410267Y816650D01*
X410767Y816317D01*
X411017Y815733D01*
Y813400D01*
G01X416700D02*
Y816733D01*
G01Y816150D02*
X416367Y816483D01*
X415867Y816650D01*
X415283Y816733D01*
X414700Y816567D01*
X414200Y816233D01*
X413867Y815733D01*
X413700Y815067D01*
X413867Y814400D01*
X414200Y813900D01*
X414700Y813567D01*
X415283Y813400D01*
X415867Y813483D01*
X416367Y813733D01*
X416700Y814067D01*
G01X420800Y818400D02*
Y813400D01*
G01X419633Y816733D02*
X421967D01*
G01X425150Y815650D02*
X427817D01*
X427567Y816233D01*
X427150Y816567D01*
X426567Y816733D01*
X425983Y816650D01*
X425483Y816400D01*
X425150Y815817D01*
X424983Y815317D01*
Y814817D01*
X425150Y814317D01*
X425567Y813817D01*
X426067Y813483D01*
X426650Y813400D01*
X427233Y813567D01*
X427817Y814067D01*
G01X433500Y818400D02*
Y813400D01*
G01Y814150D02*
X433167Y813733D01*
X432667Y813483D01*
X432083Y813400D01*
X431417Y813567D01*
X430917Y813983D01*
X430583Y814483D01*
X430500Y815067D01*
X430583Y815650D01*
X430917Y816150D01*
X431417Y816567D01*
X432083Y816733D01*
X432667Y816650D01*
X433083Y816483D01*
X433500Y816150D01*
G01X441617Y813400D02*
Y818400D01*
X444783D01*
G01X443617Y815983D02*
X441617D01*
G01X450300Y813400D02*
Y816733D01*
G01Y816150D02*
X449967Y816483D01*
X449467Y816650D01*
X448883Y816733D01*
X448300Y816567D01*
X447800Y816233D01*
X447467Y815733D01*
X447300Y815067D01*
X447467Y814400D01*
X447800Y813900D01*
X448300Y813567D01*
X448883Y813400D01*
X449467Y813483D01*
X449967Y813733D01*
X450300Y814067D01*
G01X452900Y813400D02*
Y818400D01*
G01Y815900D02*
X453317Y816400D01*
X453817Y816650D01*
X454317Y816733D01*
X455067Y816567D01*
X455567Y816233D01*
X455900Y815650D01*
Y814983D01*
X455733Y814317D01*
X455400Y813817D01*
X454817Y813483D01*
X454317Y813400D01*
X453817Y813483D01*
X453317Y813733D01*
X452900Y814150D01*
G01X458833Y813400D02*
Y816733D01*
G01Y816067D02*
X459250Y816400D01*
X459667Y816650D01*
X460250Y816733D01*
X460667Y816650D01*
X461167Y816400D01*
G01X465600Y816733D02*
Y813400D01*
G01Y818067D02*
X465433Y818150D01*
Y818317D01*
X465600Y818400D01*
X465767Y818317D01*
Y818150D01*
X465600Y818067D01*
G01X472533Y816317D02*
X471950Y816650D01*
X471450Y816733D01*
X470783Y816567D01*
X470283Y816233D01*
X469950Y815650D01*
X469867Y815067D01*
X469950Y814483D01*
X470283Y813983D01*
X470783Y813567D01*
X471450Y813400D01*
X472033Y813567D01*
X472533Y813900D01*
G01X476383Y811733D02*
X475550Y812567D01*
X475133Y813400D01*
Y816733D01*
X475550Y817567D01*
X476383Y818400D01*
G01X480733Y813400D02*
Y818400D01*
X482733D01*
X483400Y818150D01*
X483900Y817567D01*
X484067Y816900D01*
X483900Y816233D01*
X483483Y815733D01*
X482733Y815483D01*
X480733D01*
G01X486833Y813400D02*
Y816733D01*
G01Y816067D02*
X487250Y816400D01*
X487667Y816650D01*
X488250Y816733D01*
X488667Y816650D01*
X489167Y816400D01*
G01X492350Y815650D02*
X495017D01*
X494767Y816233D01*
X494350Y816567D01*
X493767Y816733D01*
X493183Y816650D01*
X492683Y816400D01*
X492350Y815817D01*
X492183Y815317D01*
Y814817D01*
X492350Y814317D01*
X492767Y813817D01*
X493267Y813483D01*
X493850Y813400D01*
X494433Y813567D01*
X495017Y814067D01*
G01X497700Y811733D02*
Y816733D01*
G01Y815983D02*
X498117Y816400D01*
X498533Y816650D01*
X499200Y816733D01*
X499783Y816650D01*
X500367Y816233D01*
X500617Y815650D01*
X500700Y815067D01*
X500617Y814483D01*
X500367Y813900D01*
X499867Y813567D01*
X499200Y813400D01*
X498617Y813483D01*
X498033Y813733D01*
X497700Y814067D01*
G01X503633Y813400D02*
Y816733D01*
G01Y816067D02*
X504050Y816400D01*
X504467Y816650D01*
X505050Y816733D01*
X505467Y816650D01*
X505967Y816400D01*
G01X509150Y815650D02*
X511817D01*
X511567Y816233D01*
X511150Y816567D01*
X510567Y816733D01*
X509983Y816650D01*
X509483Y816400D01*
X509150Y815817D01*
X508983Y815317D01*
Y814817D01*
X509150Y814317D01*
X509567Y813817D01*
X510067Y813483D01*
X510650Y813400D01*
X511233Y813567D01*
X511817Y814067D01*
G01X514833Y812150D02*
X515417Y811817D01*
X516083Y811733D01*
X516667Y811817D01*
X517167Y812233D01*
X517500Y812817D01*
Y816733D01*
G01Y816067D02*
X517167Y816400D01*
X516667Y816650D01*
X516083Y816733D01*
X515417Y816567D01*
X515000Y816233D01*
X514667Y815650D01*
X514500Y815067D01*
X514583Y814567D01*
X514917Y813983D01*
X515417Y813567D01*
X516083Y813400D01*
X516583Y813483D01*
X517167Y813817D01*
X517500Y814150D01*
G01X522017Y811733D02*
X522850Y812567D01*
X523267Y813400D01*
Y816733D01*
X522850Y817567D01*
X522017Y818400D01*
G01X532300Y813400D02*
Y817650D01*
X532467Y818067D01*
X532800Y818317D01*
X533300Y818400D01*
X533800Y818233D01*
X534050Y817817D01*
G01X533050Y816400D02*
X531383D01*
G01X538400Y813400D02*
X537900Y813483D01*
X537400Y813817D01*
X537067Y814400D01*
X536900Y815067D01*
X537067Y815733D01*
X537400Y816317D01*
X537900Y816650D01*
X538400Y816733D01*
X538900Y816650D01*
X539400Y816317D01*
X539733Y815733D01*
X539817Y815067D01*
X539733Y814400D01*
X539400Y813817D01*
X538900Y813483D01*
X538400Y813400D01*
G01X542833D02*
Y816733D01*
G01Y816067D02*
X543250Y816400D01*
X543667Y816650D01*
X544250Y816733D01*
X544667Y816650D01*
X545167Y816400D01*
G01X553033Y813400D02*
Y818400D01*
X555200Y814233D01*
X557367Y818400D01*
Y813400D01*
G01X559383Y816733D02*
Y814400D01*
X559717Y813817D01*
X560217Y813483D01*
X560800Y813400D01*
X561383Y813483D01*
X561883Y813817D01*
X562217Y814400D01*
G01Y813400D02*
Y816733D01*
G01X566400Y813400D02*
Y818400D01*
G01X572000D02*
Y813400D01*
G01X570833Y816733D02*
X573167D01*
G01X577600D02*
Y813400D01*
G01Y818067D02*
X577433Y818150D01*
Y818317D01*
X577600Y818400D01*
X577767Y818317D01*
Y818150D01*
X577600Y818067D01*
G01X583200Y813400D02*
Y818400D01*
G01X590300Y813400D02*
Y816733D01*
G01Y816150D02*
X589967Y816483D01*
X589467Y816650D01*
X588883Y816733D01*
X588300Y816567D01*
X587800Y816233D01*
X587467Y815733D01*
X587300Y815067D01*
X587467Y814400D01*
X587800Y813900D01*
X588300Y813567D01*
X588883Y813400D01*
X589467Y813483D01*
X589967Y813733D01*
X590300Y814067D01*
G01X592650Y811900D02*
X593150Y811733D01*
X593817Y811900D01*
X594233Y812233D01*
X594567Y812650D01*
X595067Y813983D01*
X596150Y816733D01*
G01X593483D02*
X595067Y813983D01*
G01X598750Y815650D02*
X601417D01*
X601167Y816233D01*
X600750Y816567D01*
X600167Y816733D01*
X599583Y816650D01*
X599083Y816400D01*
X598750Y815817D01*
X598583Y815317D01*
Y814817D01*
X598750Y814317D01*
X599167Y813817D01*
X599667Y813483D01*
X600250Y813400D01*
X600833Y813567D01*
X601417Y814067D01*
G01X604433Y813400D02*
Y816733D01*
G01Y816067D02*
X604850Y816400D01*
X605267Y816650D01*
X605850Y816733D01*
X606267Y816650D01*
X606767Y816400D01*
G01X615133Y813400D02*
Y818400D01*
X617133D01*
X617800Y818150D01*
X618300Y817567D01*
X618467Y816900D01*
X618300Y816233D01*
X617883Y815733D01*
X617133Y815483D01*
X615133D01*
G01X621233Y813400D02*
Y816733D01*
G01Y816067D02*
X621650Y816400D01*
X622067Y816650D01*
X622650Y816733D01*
X623067Y816650D01*
X623567Y816400D01*
G01X628000Y816733D02*
Y813400D01*
G01Y818067D02*
X627833Y818150D01*
Y818317D01*
X628000Y818400D01*
X628167Y818317D01*
Y818150D01*
X628000Y818067D01*
G01X632183Y813400D02*
Y816733D01*
G01Y815900D02*
X632517Y816317D01*
X633017Y816650D01*
X633683Y816733D01*
X634267Y816650D01*
X634767Y816317D01*
X635017Y815733D01*
Y813400D01*
G01X639200Y818400D02*
Y813400D01*
G01X638033Y816733D02*
X640367D01*
G01X643550Y815650D02*
X646217D01*
X645967Y816233D01*
X645550Y816567D01*
X644967Y816733D01*
X644383Y816650D01*
X643883Y816400D01*
X643550Y815817D01*
X643383Y815317D01*
Y814817D01*
X643550Y814317D01*
X643967Y813817D01*
X644467Y813483D01*
X645050Y813400D01*
X645633Y813567D01*
X646217Y814067D01*
G01X651900Y818400D02*
Y813400D01*
G01Y814150D02*
X651567Y813733D01*
X651067Y813483D01*
X650483Y813400D01*
X649817Y813567D01*
X649317Y813983D01*
X648983Y814483D01*
X648900Y815067D01*
X648983Y815650D01*
X649317Y816150D01*
X649817Y816567D01*
X650483Y816733D01*
X651067Y816650D01*
X651483Y816483D01*
X651900Y816150D01*
G01X662267Y816067D02*
X662600Y816317D01*
X662850Y816733D01*
X663017Y817317D01*
X662850Y817817D01*
X662517Y818150D01*
X661933Y818400D01*
X659683D01*
Y813400D01*
X662433D01*
X663017Y813733D01*
X663350Y814233D01*
X663517Y814817D01*
X663350Y815400D01*
X662850Y815900D01*
X662267Y816067D01*
X659683D01*
G01X667200Y813400D02*
X666700Y813483D01*
X666200Y813817D01*
X665867Y814400D01*
X665700Y815067D01*
X665867Y815733D01*
X666200Y816317D01*
X666700Y816650D01*
X667200Y816733D01*
X667700Y816650D01*
X668200Y816317D01*
X668533Y815733D01*
X668617Y815067D01*
X668533Y814400D01*
X668200Y813817D01*
X667700Y813483D01*
X667200Y813400D01*
G01X674300D02*
Y816733D01*
G01Y816150D02*
X673967Y816483D01*
X673467Y816650D01*
X672883Y816733D01*
X672300Y816567D01*
X671800Y816233D01*
X671467Y815733D01*
X671300Y815067D01*
X671467Y814400D01*
X671800Y813900D01*
X672300Y813567D01*
X672883Y813400D01*
X673467Y813483D01*
X673967Y813733D01*
X674300Y814067D01*
G01X677233Y813400D02*
Y816733D01*
G01Y816067D02*
X677650Y816400D01*
X678067Y816650D01*
X678650Y816733D01*
X679067Y816650D01*
X679567Y816400D01*
G01X685500Y818400D02*
Y813400D01*
G01Y814150D02*
X685167Y813733D01*
X684667Y813483D01*
X684083Y813400D01*
X683417Y813567D01*
X682917Y813983D01*
X682583Y814483D01*
X682500Y815067D01*
X682583Y815650D01*
X682917Y816150D01*
X683417Y816567D01*
X684083Y816733D01*
X684667Y816650D01*
X685083Y816483D01*
X685500Y816150D01*
G01X688350Y813983D02*
X688767Y813650D01*
X689350Y813400D01*
X689850D01*
X690350Y813567D01*
X690683Y813817D01*
X690850Y814150D01*
X690767Y814650D01*
X690433Y814900D01*
X688933Y815400D01*
X688600Y815983D01*
X688767Y816400D01*
X689100Y816650D01*
X689600Y816733D01*
X690100Y816650D01*
X690600Y816400D01*
G01X184600Y827400D02*
X186600D01*
G01X185600D02*
Y822400D01*
G01X184600D02*
X186600D01*
G01X189533D02*
Y827400D01*
X191533D01*
X192200Y827150D01*
X192700Y826567D01*
X192867Y825900D01*
X192700Y825233D01*
X192283Y824733D01*
X191533Y824483D01*
X189533D01*
G01X198633Y826983D02*
X198133Y827233D01*
X197550Y827400D01*
X196883D01*
X196133Y827150D01*
X195550Y826733D01*
X195133Y826233D01*
X194800Y825400D01*
X194717Y824650D01*
X194883Y823900D01*
X195133Y823400D01*
X195633Y822900D01*
X196217Y822567D01*
X196800Y822400D01*
X197383D01*
X197967Y822567D01*
X198467Y822817D01*
X198883Y823150D01*
G01X201317Y824067D02*
X203483D01*
G01X205833Y822400D02*
Y827400D01*
X208000Y823233D01*
X210167Y827400D01*
Y822400D01*
G01X212017D02*
Y827400D01*
X215183D01*
G01X214017Y824983D02*
X212017D01*
G01X218117Y824067D02*
X220283D01*
G01X224800Y822400D02*
Y827400D01*
X223800Y826400D01*
G01Y822400D02*
X225800D01*
G01X228567Y823150D02*
X229067Y822733D01*
X229650Y822483D01*
X230400Y822400D01*
X231150Y822567D01*
X231733Y822900D01*
X232150Y823483D01*
X232233Y824150D01*
X232067Y824817D01*
X231650Y825233D01*
X231067Y825567D01*
X230483Y825650D01*
X229900Y825567D01*
X229150Y825233D01*
X229400Y827400D01*
X231650D01*
G01X236000D02*
X235333Y827233D01*
X234833Y826817D01*
X234500Y826317D01*
X234250Y825650D01*
X234167Y824900D01*
X234250Y824150D01*
X234500Y823483D01*
X234833Y822983D01*
X235333Y822567D01*
X236000Y822400D01*
X236667Y822567D01*
X237167Y822983D01*
X237500Y823483D01*
X237750Y824150D01*
X237833Y824900D01*
X237750Y825650D01*
X237500Y826317D01*
X237167Y826817D01*
X236667Y827233D01*
X236000Y827400D01*
G01X245033Y822400D02*
Y827400D01*
X247200Y823233D01*
X249367Y827400D01*
Y822400D01*
G01X251550Y824650D02*
X254217D01*
X253967Y825233D01*
X253550Y825567D01*
X252967Y825733D01*
X252383Y825650D01*
X251883Y825400D01*
X251550Y824817D01*
X251383Y824317D01*
Y823817D01*
X251550Y823317D01*
X251967Y822817D01*
X252467Y822483D01*
X253050Y822400D01*
X253633Y822567D01*
X254217Y823067D01*
G01X258400Y827400D02*
Y822400D01*
G01X257233Y825733D02*
X259567D01*
G01X265500Y822400D02*
Y825733D01*
G01Y825150D02*
X265167Y825483D01*
X264667Y825650D01*
X264083Y825733D01*
X263500Y825567D01*
X263000Y825233D01*
X262667Y824733D01*
X262500Y824067D01*
X262667Y823400D01*
X263000Y822900D01*
X263500Y822567D01*
X264083Y822400D01*
X264667Y822483D01*
X265167Y822733D01*
X265500Y823067D01*
G01X269600Y822400D02*
Y827400D01*
G01X279217Y822400D02*
Y827400D01*
X282383D01*
G01X281217Y824983D02*
X279217D01*
G01X286400Y822400D02*
X285900Y822483D01*
X285400Y822817D01*
X285067Y823400D01*
X284900Y824067D01*
X285067Y824733D01*
X285400Y825317D01*
X285900Y825650D01*
X286400Y825733D01*
X286900Y825650D01*
X287400Y825317D01*
X287733Y824733D01*
X287817Y824067D01*
X287733Y823400D01*
X287400Y822817D01*
X286900Y822483D01*
X286400Y822400D01*
G01X292000Y825733D02*
Y822400D01*
G01Y827067D02*
X291833Y827150D01*
Y827317D01*
X292000Y827400D01*
X292167Y827317D01*
Y827150D01*
X292000Y827067D01*
G01X297600Y822400D02*
Y827400D01*
G01X308300Y822400D02*
Y826650D01*
X308467Y827067D01*
X308800Y827317D01*
X309300Y827400D01*
X309800Y827233D01*
X310050Y826817D01*
G01X309050Y825400D02*
X307383D01*
G01X314400Y822400D02*
X313900Y822483D01*
X313400Y822817D01*
X313067Y823400D01*
X312900Y824067D01*
X313067Y824733D01*
X313400Y825317D01*
X313900Y825650D01*
X314400Y825733D01*
X314900Y825650D01*
X315400Y825317D01*
X315733Y824733D01*
X315817Y824067D01*
X315733Y823400D01*
X315400Y822817D01*
X314900Y822483D01*
X314400Y822400D01*
G01X318833D02*
Y825733D01*
G01Y825067D02*
X319250Y825400D01*
X319667Y825650D01*
X320250Y825733D01*
X320667Y825650D01*
X321167Y825400D01*
G01X329533Y822400D02*
Y827400D01*
X331533D01*
X332200Y827150D01*
X332700Y826567D01*
X332867Y825900D01*
X332700Y825233D01*
X332283Y824733D01*
X331533Y824483D01*
X329533D01*
G01X335633Y822400D02*
Y825733D01*
G01Y825067D02*
X336050Y825400D01*
X336467Y825650D01*
X337050Y825733D01*
X337467Y825650D01*
X337967Y825400D01*
G01X342400Y825733D02*
Y822400D01*
G01Y827067D02*
X342233Y827150D01*
Y827317D01*
X342400Y827400D01*
X342567Y827317D01*
Y827150D01*
X342400Y827067D01*
G01X346583Y822400D02*
Y825733D01*
G01Y824900D02*
X346917Y825317D01*
X347417Y825650D01*
X348083Y825733D01*
X348667Y825650D01*
X349167Y825317D01*
X349417Y824733D01*
Y822400D01*
G01X353600Y827400D02*
Y822400D01*
G01X352433Y825733D02*
X354767D01*
G01X357950Y824650D02*
X360617D01*
X360367Y825233D01*
X359950Y825567D01*
X359367Y825733D01*
X358783Y825650D01*
X358283Y825400D01*
X357950Y824817D01*
X357783Y824317D01*
Y823817D01*
X357950Y823317D01*
X358367Y822817D01*
X358867Y822483D01*
X359450Y822400D01*
X360033Y822567D01*
X360617Y823067D01*
G01X366300Y827400D02*
Y822400D01*
G01Y823150D02*
X365967Y822733D01*
X365467Y822483D01*
X364883Y822400D01*
X364217Y822567D01*
X363717Y822983D01*
X363383Y823483D01*
X363300Y824067D01*
X363383Y824650D01*
X363717Y825150D01*
X364217Y825567D01*
X364883Y825733D01*
X365467Y825650D01*
X365883Y825483D01*
X366300Y825150D01*
G01X373500Y827400D02*
X374667Y822400D01*
X376000Y827400D01*
X377333Y822400D01*
X378500Y827400D01*
G01X381600Y825733D02*
Y822400D01*
G01Y827067D02*
X381433Y827150D01*
Y827317D01*
X381600Y827400D01*
X381767Y827317D01*
Y827150D01*
X381600Y827067D01*
G01X386033Y822400D02*
Y825733D01*
G01Y825067D02*
X386450Y825400D01*
X386867Y825650D01*
X387450Y825733D01*
X387867Y825650D01*
X388367Y825400D01*
G01X392800Y825733D02*
Y822400D01*
G01Y827067D02*
X392633Y827150D01*
Y827317D01*
X392800Y827400D01*
X392967Y827317D01*
Y827150D01*
X392800Y827067D01*
G01X396983Y822400D02*
Y825733D01*
G01Y824900D02*
X397317Y825317D01*
X397817Y825650D01*
X398483Y825733D01*
X399067Y825650D01*
X399567Y825317D01*
X399817Y824733D01*
Y822400D01*
G01X402833Y821150D02*
X403417Y820817D01*
X404083Y820733D01*
X404667Y820817D01*
X405167Y821233D01*
X405500Y821817D01*
Y825733D01*
G01Y825067D02*
X405167Y825400D01*
X404667Y825650D01*
X404083Y825733D01*
X403417Y825567D01*
X403000Y825233D01*
X402667Y824650D01*
X402500Y824067D01*
X402583Y823567D01*
X402917Y822983D01*
X403417Y822567D01*
X404083Y822400D01*
X404583Y822483D01*
X405167Y822817D01*
X405500Y823150D01*
G01X413117Y822400D02*
X415200Y827400D01*
X417283Y822400D01*
G01X416533Y824150D02*
X413867D01*
G01X419300Y820733D02*
Y825733D01*
G01Y824983D02*
X419717Y825400D01*
X420133Y825650D01*
X420800Y825733D01*
X421383Y825650D01*
X421967Y825233D01*
X422217Y824650D01*
X422300Y824067D01*
X422217Y823483D01*
X421967Y822900D01*
X421467Y822567D01*
X420800Y822400D01*
X420217Y822483D01*
X419633Y822733D01*
X419300Y823067D01*
G01X424900Y820733D02*
Y825733D01*
G01Y824983D02*
X425317Y825400D01*
X425733Y825650D01*
X426400Y825733D01*
X426983Y825650D01*
X427567Y825233D01*
X427817Y824650D01*
X427900Y824067D01*
X427817Y823483D01*
X427567Y822900D01*
X427067Y822567D01*
X426400Y822400D01*
X425817Y822483D01*
X425233Y822733D01*
X424900Y823067D01*
G01X432000Y822400D02*
Y827400D01*
G01X437600Y825733D02*
Y822400D01*
G01Y827067D02*
X437433Y827150D01*
Y827317D01*
X437600Y827400D01*
X437767Y827317D01*
Y827150D01*
X437600Y827067D01*
G01X444533Y825317D02*
X443950Y825650D01*
X443450Y825733D01*
X442783Y825567D01*
X442283Y825233D01*
X441950Y824650D01*
X441867Y824067D01*
X441950Y823483D01*
X442283Y822983D01*
X442783Y822567D01*
X443450Y822400D01*
X444033Y822567D01*
X444533Y822900D01*
G01X450300Y822400D02*
Y825733D01*
G01Y825150D02*
X449967Y825483D01*
X449467Y825650D01*
X448883Y825733D01*
X448300Y825567D01*
X447800Y825233D01*
X447467Y824733D01*
X447300Y824067D01*
X447467Y823400D01*
X447800Y822900D01*
X448300Y822567D01*
X448883Y822400D01*
X449467Y822483D01*
X449967Y822733D01*
X450300Y823067D01*
G01X454400Y827400D02*
Y822400D01*
G01X453233Y825733D02*
X455567D01*
G01X460000D02*
Y822400D01*
G01Y827067D02*
X459833Y827150D01*
Y827317D01*
X460000Y827400D01*
X460167Y827317D01*
Y827150D01*
X460000Y827067D01*
G01X465600Y822400D02*
X465100Y822483D01*
X464600Y822817D01*
X464267Y823400D01*
X464100Y824067D01*
X464267Y824733D01*
X464600Y825317D01*
X465100Y825650D01*
X465600Y825733D01*
X466100Y825650D01*
X466600Y825317D01*
X466933Y824733D01*
X467017Y824067D01*
X466933Y823400D01*
X466600Y822817D01*
X466100Y822483D01*
X465600Y822400D01*
G01X469783D02*
Y825733D01*
G01Y824900D02*
X470117Y825317D01*
X470617Y825650D01*
X471283Y825733D01*
X471867Y825650D01*
X472367Y825317D01*
X472617Y824733D01*
Y822400D01*
G01X475550Y822983D02*
X475967Y822650D01*
X476550Y822400D01*
X477050D01*
X477550Y822567D01*
X477883Y822817D01*
X478050Y823150D01*
X477967Y823650D01*
X477633Y823900D01*
X476133Y824400D01*
X475800Y824983D01*
X475967Y825400D01*
X476300Y825650D01*
X476800Y825733D01*
X477300Y825650D01*
X477800Y825400D01*
G01X184600Y836400D02*
X186600D01*
G01X185600D02*
Y831400D01*
G01X184600D02*
X186600D01*
G01X189533D02*
Y836400D01*
X191533D01*
X192200Y836150D01*
X192700Y835567D01*
X192867Y834900D01*
X192700Y834233D01*
X192283Y833733D01*
X191533Y833483D01*
X189533D01*
G01X198633Y835983D02*
X198133Y836233D01*
X197550Y836400D01*
X196883D01*
X196133Y836150D01*
X195550Y835733D01*
X195133Y835233D01*
X194800Y834400D01*
X194717Y833650D01*
X194883Y832900D01*
X195133Y832400D01*
X195633Y831900D01*
X196217Y831567D01*
X196800Y831400D01*
X197383D01*
X197967Y831567D01*
X198467Y831817D01*
X198883Y832150D01*
G01X201317Y833067D02*
X203483D01*
G01X209000Y831400D02*
Y836400D01*
X205917Y832817D01*
X210083D01*
G01X213600Y831400D02*
Y836400D01*
X212600Y835400D01*
G01Y831400D02*
X214600D01*
G01X219200Y836400D02*
X218533Y836233D01*
X218033Y835817D01*
X217700Y835317D01*
X217450Y834650D01*
X217367Y833900D01*
X217450Y833150D01*
X217700Y832483D01*
X218033Y831983D01*
X218533Y831567D01*
X219200Y831400D01*
X219867Y831567D01*
X220367Y831983D01*
X220700Y832483D01*
X220950Y833150D01*
X221033Y833900D01*
X220950Y834650D01*
X220700Y835317D01*
X220367Y835817D01*
X219867Y836233D01*
X219200Y836400D01*
G01X224800Y831400D02*
Y836400D01*
X223800Y835400D01*
G01Y831400D02*
X225800D01*
G01X234250Y832067D02*
X234917Y831650D01*
X235667Y831400D01*
X236333D01*
X237000Y831650D01*
X237500Y832067D01*
X237750Y832650D01*
X237583Y833233D01*
X237167Y833733D01*
X236417Y834067D01*
X235417Y834233D01*
X234833Y834567D01*
X234583Y835150D01*
X234750Y835733D01*
X235167Y836150D01*
X235750Y836400D01*
X236333D01*
X236917Y836233D01*
X237417Y835817D01*
G01X240100Y829733D02*
Y834733D01*
G01Y833983D02*
X240517Y834400D01*
X240933Y834650D01*
X241600Y834733D01*
X242183Y834650D01*
X242767Y834233D01*
X243017Y833650D01*
X243100Y833067D01*
X243017Y832483D01*
X242767Y831900D01*
X242267Y831567D01*
X241600Y831400D01*
X241017Y831483D01*
X240433Y831733D01*
X240100Y832067D01*
G01X245950Y833650D02*
X248617D01*
X248367Y834233D01*
X247950Y834567D01*
X247367Y834733D01*
X246783Y834650D01*
X246283Y834400D01*
X245950Y833817D01*
X245783Y833317D01*
Y832817D01*
X245950Y832317D01*
X246367Y831817D01*
X246867Y831483D01*
X247450Y831400D01*
X248033Y831567D01*
X248617Y832067D01*
G01X254133Y834317D02*
X253550Y834650D01*
X253050Y834733D01*
X252383Y834567D01*
X251883Y834233D01*
X251550Y833650D01*
X251467Y833067D01*
X251550Y832483D01*
X251883Y831983D01*
X252383Y831567D01*
X253050Y831400D01*
X253633Y831567D01*
X254133Y831900D01*
G01X258400Y834733D02*
Y831400D01*
G01Y836067D02*
X258233Y836150D01*
Y836317D01*
X258400Y836400D01*
X258567Y836317D01*
Y836150D01*
X258400Y836067D01*
G01X263500Y831400D02*
Y835650D01*
X263667Y836067D01*
X264000Y836317D01*
X264500Y836400D01*
X265000Y836233D01*
X265250Y835817D01*
G01X264250Y834400D02*
X262583D01*
G01X269600Y834733D02*
Y831400D01*
G01Y836067D02*
X269433Y836150D01*
Y836317D01*
X269600Y836400D01*
X269767Y836317D01*
Y836150D01*
X269600Y836067D01*
G01X276533Y834317D02*
X275950Y834650D01*
X275450Y834733D01*
X274783Y834567D01*
X274283Y834233D01*
X273950Y833650D01*
X273867Y833067D01*
X273950Y832483D01*
X274283Y831983D01*
X274783Y831567D01*
X275450Y831400D01*
X276033Y831567D01*
X276533Y831900D01*
G01X282300Y831400D02*
Y834733D01*
G01Y834150D02*
X281967Y834483D01*
X281467Y834650D01*
X280883Y834733D01*
X280300Y834567D01*
X279800Y834233D01*
X279467Y833733D01*
X279300Y833067D01*
X279467Y832400D01*
X279800Y831900D01*
X280300Y831567D01*
X280883Y831400D01*
X281467Y831483D01*
X281967Y831733D01*
X282300Y832067D01*
G01X286400Y836400D02*
Y831400D01*
G01X285233Y834733D02*
X287567D01*
G01X292000D02*
Y831400D01*
G01Y836067D02*
X291833Y836150D01*
Y836317D01*
X292000Y836400D01*
X292167Y836317D01*
Y836150D01*
X292000Y836067D01*
G01X297600Y831400D02*
X297100Y831483D01*
X296600Y831817D01*
X296267Y832400D01*
X296100Y833067D01*
X296267Y833733D01*
X296600Y834317D01*
X297100Y834650D01*
X297600Y834733D01*
X298100Y834650D01*
X298600Y834317D01*
X298933Y833733D01*
X299017Y833067D01*
X298933Y832400D01*
X298600Y831817D01*
X298100Y831483D01*
X297600Y831400D01*
G01X301783D02*
Y834733D01*
G01Y833900D02*
X302117Y834317D01*
X302617Y834650D01*
X303283Y834733D01*
X303867Y834650D01*
X304367Y834317D01*
X304617Y833733D01*
Y831400D01*
G01X313900D02*
Y835650D01*
X314067Y836067D01*
X314400Y836317D01*
X314900Y836400D01*
X315400Y836233D01*
X315650Y835817D01*
G01X314650Y834400D02*
X312983D01*
G01X320000Y831400D02*
X319500Y831483D01*
X319000Y831817D01*
X318667Y832400D01*
X318500Y833067D01*
X318667Y833733D01*
X319000Y834317D01*
X319500Y834650D01*
X320000Y834733D01*
X320500Y834650D01*
X321000Y834317D01*
X321333Y833733D01*
X321417Y833067D01*
X321333Y832400D01*
X321000Y831817D01*
X320500Y831483D01*
X320000Y831400D01*
G01X324433D02*
Y834733D01*
G01Y834067D02*
X324850Y834400D01*
X325267Y834650D01*
X325850Y834733D01*
X326267Y834650D01*
X326767Y834400D01*
G01X337467Y834067D02*
X337800Y834317D01*
X338050Y834733D01*
X338217Y835317D01*
X338050Y835817D01*
X337717Y836150D01*
X337133Y836400D01*
X334883D01*
Y831400D01*
X337633D01*
X338217Y831733D01*
X338550Y832233D01*
X338717Y832817D01*
X338550Y833400D01*
X338050Y833900D01*
X337467Y834067D01*
X334883D01*
G01X343900Y831400D02*
Y834733D01*
G01Y834150D02*
X343567Y834483D01*
X343067Y834650D01*
X342483Y834733D01*
X341900Y834567D01*
X341400Y834233D01*
X341067Y833733D01*
X340900Y833067D01*
X341067Y832400D01*
X341400Y831900D01*
X341900Y831567D01*
X342483Y831400D01*
X343067Y831483D01*
X343567Y831733D01*
X343900Y832067D01*
G01X346750Y831983D02*
X347167Y831650D01*
X347750Y831400D01*
X348250D01*
X348750Y831567D01*
X349083Y831817D01*
X349250Y832150D01*
X349167Y832650D01*
X348833Y832900D01*
X347333Y833400D01*
X347000Y833983D01*
X347167Y834400D01*
X347500Y834650D01*
X348000Y834733D01*
X348500Y834650D01*
X349000Y834400D01*
G01X352350Y833650D02*
X355017D01*
X354767Y834233D01*
X354350Y834567D01*
X353767Y834733D01*
X353183Y834650D01*
X352683Y834400D01*
X352350Y833817D01*
X352183Y833317D01*
Y832817D01*
X352350Y832317D01*
X352767Y831817D01*
X353267Y831483D01*
X353850Y831400D01*
X354433Y831567D01*
X355017Y832067D01*
G01X362633Y831400D02*
Y836400D01*
X364800Y832233D01*
X366967Y836400D01*
Y831400D01*
G01X371900D02*
Y834733D01*
G01Y834150D02*
X371567Y834483D01*
X371067Y834650D01*
X370483Y834733D01*
X369900Y834567D01*
X369400Y834233D01*
X369067Y833733D01*
X368900Y833067D01*
X369067Y832400D01*
X369400Y831900D01*
X369900Y831567D01*
X370483Y831400D01*
X371067Y831483D01*
X371567Y831733D01*
X371900Y832067D01*
G01X376000Y836400D02*
Y831400D01*
G01X374833Y834733D02*
X377167D01*
G01X380350Y833650D02*
X383017D01*
X382767Y834233D01*
X382350Y834567D01*
X381767Y834733D01*
X381183Y834650D01*
X380683Y834400D01*
X380350Y833817D01*
X380183Y833317D01*
Y832817D01*
X380350Y832317D01*
X380767Y831817D01*
X381267Y831483D01*
X381850Y831400D01*
X382433Y831567D01*
X383017Y832067D01*
G01X386033Y831400D02*
Y834733D01*
G01Y834067D02*
X386450Y834400D01*
X386867Y834650D01*
X387450Y834733D01*
X387867Y834650D01*
X388367Y834400D01*
G01X392800Y834733D02*
Y831400D01*
G01Y836067D02*
X392633Y836150D01*
Y836317D01*
X392800Y836400D01*
X392967Y836317D01*
Y836150D01*
X392800Y836067D01*
G01X399900Y831400D02*
Y834733D01*
G01Y834150D02*
X399567Y834483D01*
X399067Y834650D01*
X398483Y834733D01*
X397900Y834567D01*
X397400Y834233D01*
X397067Y833733D01*
X396900Y833067D01*
X397067Y832400D01*
X397400Y831900D01*
X397900Y831567D01*
X398483Y831400D01*
X399067Y831483D01*
X399567Y831733D01*
X399900Y832067D01*
G01X404000Y831400D02*
Y836400D01*
G01X408350Y831983D02*
X408767Y831650D01*
X409350Y831400D01*
X409850D01*
X410350Y831567D01*
X410683Y831817D01*
X410850Y832150D01*
X410767Y832650D01*
X410433Y832900D01*
X408933Y833400D01*
X408600Y833983D01*
X408767Y834400D01*
X409100Y834650D01*
X409600Y834733D01*
X410100Y834650D01*
X410600Y834400D01*
G01X420300Y831400D02*
Y835650D01*
X420467Y836067D01*
X420800Y836317D01*
X421300Y836400D01*
X421800Y836233D01*
X422050Y835817D01*
G01X421050Y834400D02*
X419383D01*
G01X426400Y831400D02*
X425900Y831483D01*
X425400Y831817D01*
X425067Y832400D01*
X424900Y833067D01*
X425067Y833733D01*
X425400Y834317D01*
X425900Y834650D01*
X426400Y834733D01*
X426900Y834650D01*
X427400Y834317D01*
X427733Y833733D01*
X427817Y833067D01*
X427733Y832400D01*
X427400Y831817D01*
X426900Y831483D01*
X426400Y831400D01*
G01X430833D02*
Y834733D01*
G01Y834067D02*
X431250Y834400D01*
X431667Y834650D01*
X432250Y834733D01*
X432667Y834650D01*
X433167Y834400D01*
G01X441533Y831400D02*
Y836400D01*
X443617D01*
X444283Y836150D01*
X444700Y835817D01*
X444867Y835150D01*
X444700Y834483D01*
X444200Y834067D01*
X443617Y833817D01*
X441533D01*
G01X443617D02*
X444867Y831400D01*
G01X448800Y834733D02*
Y831400D01*
G01Y836067D02*
X448633Y836150D01*
Y836317D01*
X448800Y836400D01*
X448967Y836317D01*
Y836150D01*
X448800Y836067D01*
G01X453233Y830150D02*
X453817Y829817D01*
X454483Y829733D01*
X455067Y829817D01*
X455567Y830233D01*
X455900Y830817D01*
Y834733D01*
G01Y834067D02*
X455567Y834400D01*
X455067Y834650D01*
X454483Y834733D01*
X453817Y834567D01*
X453400Y834233D01*
X453067Y833650D01*
X452900Y833067D01*
X452983Y832567D01*
X453317Y831983D01*
X453817Y831567D01*
X454483Y831400D01*
X454983Y831483D01*
X455567Y831817D01*
X455900Y832150D01*
G01X460000Y834733D02*
Y831400D01*
G01Y836067D02*
X459833Y836150D01*
Y836317D01*
X460000Y836400D01*
X460167Y836317D01*
Y836150D01*
X460000Y836067D01*
G01X467100Y836400D02*
Y831400D01*
G01Y832150D02*
X466767Y831733D01*
X466267Y831483D01*
X465683Y831400D01*
X465017Y831567D01*
X464517Y831983D01*
X464183Y832483D01*
X464100Y833067D01*
X464183Y833650D01*
X464517Y834150D01*
X465017Y834567D01*
X465683Y834733D01*
X466267Y834650D01*
X466683Y834483D01*
X467100Y834150D01*
G01X478300Y831400D02*
Y834733D01*
G01Y834150D02*
X477967Y834483D01*
X477467Y834650D01*
X476883Y834733D01*
X476300Y834567D01*
X475800Y834233D01*
X475467Y833733D01*
X475300Y833067D01*
X475467Y832400D01*
X475800Y831900D01*
X476300Y831567D01*
X476883Y831400D01*
X477467Y831483D01*
X477967Y831733D01*
X478300Y832067D01*
G01X480983Y831400D02*
Y834733D01*
G01Y833900D02*
X481317Y834317D01*
X481817Y834650D01*
X482483Y834733D01*
X483067Y834650D01*
X483567Y834317D01*
X483817Y833733D01*
Y831400D01*
G01X489500Y836400D02*
Y831400D01*
G01Y832150D02*
X489167Y831733D01*
X488667Y831483D01*
X488083Y831400D01*
X487417Y831567D01*
X486917Y831983D01*
X486583Y832483D01*
X486500Y833067D01*
X486583Y833650D01*
X486917Y834150D01*
X487417Y834567D01*
X488083Y834733D01*
X488667Y834650D01*
X489083Y834483D01*
X489500Y834150D01*
G01X497033Y831400D02*
Y836400D01*
X499200Y832233D01*
X501367Y836400D01*
Y831400D01*
G01X503383Y834733D02*
Y832400D01*
X503717Y831817D01*
X504217Y831483D01*
X504800Y831400D01*
X505383Y831483D01*
X505883Y831817D01*
X506217Y832400D01*
G01Y831400D02*
Y834733D01*
G01X510400Y831400D02*
Y836400D01*
G01X516000D02*
Y831400D01*
G01X514833Y834733D02*
X517167D01*
G01X521600D02*
Y831400D01*
G01Y836067D02*
X521433Y836150D01*
Y836317D01*
X521600Y836400D01*
X521767Y836317D01*
Y836150D01*
X521600Y836067D01*
G01X527200Y831400D02*
Y836400D01*
G01X534300Y831400D02*
Y834733D01*
G01Y834150D02*
X533967Y834483D01*
X533467Y834650D01*
X532883Y834733D01*
X532300Y834567D01*
X531800Y834233D01*
X531467Y833733D01*
X531300Y833067D01*
X531467Y832400D01*
X531800Y831900D01*
X532300Y831567D01*
X532883Y831400D01*
X533467Y831483D01*
X533967Y831733D01*
X534300Y832067D01*
G01X536650Y829900D02*
X537150Y829733D01*
X537817Y829900D01*
X538233Y830233D01*
X538567Y830650D01*
X539067Y831983D01*
X540150Y834733D01*
G01X537483D02*
X539067Y831983D01*
G01X542750Y833650D02*
X545417D01*
X545167Y834233D01*
X544750Y834567D01*
X544167Y834733D01*
X543583Y834650D01*
X543083Y834400D01*
X542750Y833817D01*
X542583Y833317D01*
Y832817D01*
X542750Y832317D01*
X543167Y831817D01*
X543667Y831483D01*
X544250Y831400D01*
X544833Y831567D01*
X545417Y832067D01*
G01X548433Y831400D02*
Y834733D01*
G01Y834067D02*
X548850Y834400D01*
X549267Y834650D01*
X549850Y834733D01*
X550267Y834650D01*
X550767Y834400D01*
G01X559133Y831400D02*
Y836400D01*
X561133D01*
X561800Y836150D01*
X562300Y835567D01*
X562467Y834900D01*
X562300Y834233D01*
X561883Y833733D01*
X561133Y833483D01*
X559133D01*
G01X565233Y831400D02*
Y834733D01*
G01Y834067D02*
X565650Y834400D01*
X566067Y834650D01*
X566650Y834733D01*
X567067Y834650D01*
X567567Y834400D01*
G01X572000Y834733D02*
Y831400D01*
G01Y836067D02*
X571833Y836150D01*
Y836317D01*
X572000Y836400D01*
X572167Y836317D01*
Y836150D01*
X572000Y836067D01*
G01X576183Y831400D02*
Y834733D01*
G01Y833900D02*
X576517Y834317D01*
X577017Y834650D01*
X577683Y834733D01*
X578267Y834650D01*
X578767Y834317D01*
X579017Y833733D01*
Y831400D01*
G01X583200Y836400D02*
Y831400D01*
G01X582033Y834733D02*
X584367D01*
G01X587550Y833650D02*
X590217D01*
X589967Y834233D01*
X589550Y834567D01*
X588967Y834733D01*
X588383Y834650D01*
X587883Y834400D01*
X587550Y833817D01*
X587383Y833317D01*
Y832817D01*
X587550Y832317D01*
X587967Y831817D01*
X588467Y831483D01*
X589050Y831400D01*
X589633Y831567D01*
X590217Y832067D01*
G01X595900Y836400D02*
Y831400D01*
G01Y832150D02*
X595567Y831733D01*
X595067Y831483D01*
X594483Y831400D01*
X593817Y831567D01*
X593317Y831983D01*
X592983Y832483D01*
X592900Y833067D01*
X592983Y833650D01*
X593317Y834150D01*
X593817Y834567D01*
X594483Y834733D01*
X595067Y834650D01*
X595483Y834483D01*
X595900Y834150D01*
G01X606267Y834067D02*
X606600Y834317D01*
X606850Y834733D01*
X607017Y835317D01*
X606850Y835817D01*
X606517Y836150D01*
X605933Y836400D01*
X603683D01*
Y831400D01*
X606433D01*
X607017Y831733D01*
X607350Y832233D01*
X607517Y832817D01*
X607350Y833400D01*
X606850Y833900D01*
X606267Y834067D01*
X603683D01*
G01X611200Y831400D02*
X610700Y831483D01*
X610200Y831817D01*
X609867Y832400D01*
X609700Y833067D01*
X609867Y833733D01*
X610200Y834317D01*
X610700Y834650D01*
X611200Y834733D01*
X611700Y834650D01*
X612200Y834317D01*
X612533Y833733D01*
X612617Y833067D01*
X612533Y832400D01*
X612200Y831817D01*
X611700Y831483D01*
X611200Y831400D01*
G01X618300D02*
Y834733D01*
G01Y834150D02*
X617967Y834483D01*
X617467Y834650D01*
X616883Y834733D01*
X616300Y834567D01*
X615800Y834233D01*
X615467Y833733D01*
X615300Y833067D01*
X615467Y832400D01*
X615800Y831900D01*
X616300Y831567D01*
X616883Y831400D01*
X617467Y831483D01*
X617967Y831733D01*
X618300Y832067D01*
G01X621233Y831400D02*
Y834733D01*
G01Y834067D02*
X621650Y834400D01*
X622067Y834650D01*
X622650Y834733D01*
X623067Y834650D01*
X623567Y834400D01*
G01X629500Y836400D02*
Y831400D01*
G01Y832150D02*
X629167Y831733D01*
X628667Y831483D01*
X628083Y831400D01*
X627417Y831567D01*
X626917Y831983D01*
X626583Y832483D01*
X626500Y833067D01*
X626583Y833650D01*
X626917Y834150D01*
X627417Y834567D01*
X628083Y834733D01*
X628667Y834650D01*
X629083Y834483D01*
X629500Y834150D01*
G01X632350Y831983D02*
X632767Y831650D01*
X633350Y831400D01*
X633850D01*
X634350Y831567D01*
X634683Y831817D01*
X634850Y832150D01*
X634767Y832650D01*
X634433Y832900D01*
X632933Y833400D01*
X632600Y833983D01*
X632767Y834400D01*
X633100Y834650D01*
X633600Y834733D01*
X634100Y834650D01*
X634600Y834400D01*
G01X184600Y845400D02*
X186600D01*
G01X185600D02*
Y840400D01*
G01X184600D02*
X186600D01*
G01X189533D02*
Y845400D01*
X191533D01*
X192200Y845150D01*
X192700Y844567D01*
X192867Y843900D01*
X192700Y843233D01*
X192283Y842733D01*
X191533Y842483D01*
X189533D01*
G01X198633Y844983D02*
X198133Y845233D01*
X197550Y845400D01*
X196883D01*
X196133Y845150D01*
X195550Y844733D01*
X195133Y844233D01*
X194800Y843400D01*
X194717Y842650D01*
X194883Y841900D01*
X195133Y841400D01*
X195633Y840900D01*
X196217Y840567D01*
X196800Y840400D01*
X197383D01*
X197967Y840567D01*
X198467Y840817D01*
X198883Y841150D01*
G01X201317Y842067D02*
X203483D01*
G01X208000Y845400D02*
Y840400D01*
G01X206083Y845400D02*
X209917D01*
G01X211433Y840400D02*
Y845400D01*
X213600Y841233D01*
X215767Y845400D01*
Y840400D01*
G01X218117Y842067D02*
X220283D01*
G01X223217Y842483D02*
X223800Y843067D01*
X224300Y843400D01*
X224967Y843567D01*
X225550Y843400D01*
X225967Y843067D01*
X226300Y842567D01*
X226383Y841983D01*
X226300Y841483D01*
X225967Y840983D01*
X225467Y840567D01*
X224883Y840400D01*
X224217Y840567D01*
X223633Y841067D01*
X223300Y841817D01*
X223217Y842650D01*
X223383Y843733D01*
X223633Y844317D01*
X224050Y844900D01*
X224633Y845317D01*
X225217Y845400D01*
X225800Y845233D01*
X226217Y844817D01*
G01X228567Y841150D02*
X229067Y840733D01*
X229650Y840483D01*
X230400Y840400D01*
X231150Y840567D01*
X231733Y840900D01*
X232150Y841483D01*
X232233Y842150D01*
X232067Y842817D01*
X231650Y843233D01*
X231067Y843567D01*
X230483Y843650D01*
X229900Y843567D01*
X229150Y843233D01*
X229400Y845400D01*
X231650D01*
G01X236000D02*
X235333Y845233D01*
X234833Y844817D01*
X234500Y844317D01*
X234250Y843650D01*
X234167Y842900D01*
X234250Y842150D01*
X234500Y841483D01*
X234833Y840983D01*
X235333Y840567D01*
X236000Y840400D01*
X236667Y840567D01*
X237167Y840983D01*
X237500Y841483D01*
X237750Y842150D01*
X237833Y842900D01*
X237750Y843650D01*
X237500Y844317D01*
X237167Y844817D01*
X236667Y845233D01*
X236000Y845400D01*
G01X247200D02*
Y840400D01*
G01X245283Y845400D02*
X249117D01*
G01X251550Y842650D02*
X254217D01*
X253967Y843233D01*
X253550Y843567D01*
X252967Y843733D01*
X252383Y843650D01*
X251883Y843400D01*
X251550Y842817D01*
X251383Y842317D01*
Y841817D01*
X251550Y841317D01*
X251967Y840817D01*
X252467Y840483D01*
X253050Y840400D01*
X253633Y840567D01*
X254217Y841067D01*
G01X257150Y840983D02*
X257567Y840650D01*
X258150Y840400D01*
X258650D01*
X259150Y840567D01*
X259483Y840817D01*
X259650Y841150D01*
X259567Y841650D01*
X259233Y841900D01*
X257733Y842400D01*
X257400Y842983D01*
X257567Y843400D01*
X257900Y843650D01*
X258400Y843733D01*
X258900Y843650D01*
X259400Y843400D01*
G01X264000Y845400D02*
Y840400D01*
G01X262833Y843733D02*
X265167D01*
G01X273033Y840400D02*
Y845400D01*
X275200Y841233D01*
X277367Y845400D01*
Y840400D01*
G01X279550Y842650D02*
X282217D01*
X281967Y843233D01*
X281550Y843567D01*
X280967Y843733D01*
X280383Y843650D01*
X279883Y843400D01*
X279550Y842817D01*
X279383Y842317D01*
Y841817D01*
X279550Y841317D01*
X279967Y840817D01*
X280467Y840483D01*
X281050Y840400D01*
X281633Y840567D01*
X282217Y841067D01*
G01X286400Y845400D02*
Y840400D01*
G01X285233Y843733D02*
X287567D01*
G01X290583Y840400D02*
Y845400D01*
G01Y842983D02*
X291000Y843400D01*
X291417Y843650D01*
X292083Y843733D01*
X292583Y843650D01*
X293167Y843317D01*
X293417Y842817D01*
Y840400D01*
G01X297600D02*
X297100Y840483D01*
X296600Y840817D01*
X296267Y841400D01*
X296100Y842067D01*
X296267Y842733D01*
X296600Y843317D01*
X297100Y843650D01*
X297600Y843733D01*
X298100Y843650D01*
X298600Y843317D01*
X298933Y842733D01*
X299017Y842067D01*
X298933Y841400D01*
X298600Y840817D01*
X298100Y840483D01*
X297600Y840400D01*
G01X304700Y845400D02*
Y840400D01*
G01Y841150D02*
X304367Y840733D01*
X303867Y840483D01*
X303283Y840400D01*
X302617Y840567D01*
X302117Y840983D01*
X301783Y841483D01*
X301700Y842067D01*
X301783Y842650D01*
X302117Y843150D01*
X302617Y843567D01*
X303283Y843733D01*
X303867Y843650D01*
X304283Y843483D01*
X304700Y843150D01*
G01X307550Y840983D02*
X307967Y840650D01*
X308550Y840400D01*
X309050D01*
X309550Y840567D01*
X309883Y840817D01*
X310050Y841150D01*
X309967Y841650D01*
X309633Y841900D01*
X308133Y842400D01*
X307800Y842983D01*
X307967Y843400D01*
X308300Y843650D01*
X308800Y843733D01*
X309300Y843650D01*
X309800Y843400D01*
G01X317833Y840400D02*
Y845400D01*
X320000Y841233D01*
X322167Y845400D01*
Y840400D01*
G01X327100D02*
Y843733D01*
G01Y843150D02*
X326767Y843483D01*
X326267Y843650D01*
X325683Y843733D01*
X325100Y843567D01*
X324600Y843233D01*
X324267Y842733D01*
X324100Y842067D01*
X324267Y841400D01*
X324600Y840900D01*
X325100Y840567D01*
X325683Y840400D01*
X326267Y840483D01*
X326767Y840733D01*
X327100Y841067D01*
G01X329783Y840400D02*
Y843733D01*
G01Y842900D02*
X330117Y843317D01*
X330617Y843650D01*
X331283Y843733D01*
X331867Y843650D01*
X332367Y843317D01*
X332617Y842733D01*
Y840400D01*
G01X335383Y843733D02*
Y841400D01*
X335717Y840817D01*
X336217Y840483D01*
X336800Y840400D01*
X337383Y840483D01*
X337883Y840817D01*
X338217Y841400D01*
G01Y840400D02*
Y843733D01*
G01X343900Y840400D02*
Y843733D01*
G01Y843150D02*
X343567Y843483D01*
X343067Y843650D01*
X342483Y843733D01*
X341900Y843567D01*
X341400Y843233D01*
X341067Y842733D01*
X340900Y842067D01*
X341067Y841400D01*
X341400Y840900D01*
X341900Y840567D01*
X342483Y840400D01*
X343067Y840483D01*
X343567Y840733D01*
X343900Y841067D01*
G01X348000Y840400D02*
Y845400D01*
G01X180600Y850233D02*
X180433Y850317D01*
Y850483D01*
X180600Y850567D01*
X180767Y850483D01*
Y850317D01*
X180600Y850233D01*
G01Y859233D02*
X180433Y859317D01*
Y859483D01*
X180600Y859567D01*
X180767Y859483D01*
Y859317D01*
X180600Y859233D01*
G01X184600Y854400D02*
X186600D01*
G01X185600D02*
Y849400D01*
G01X184600D02*
X186600D01*
G01X189533D02*
Y854400D01*
X191533D01*
X192200Y854150D01*
X192700Y853567D01*
X192867Y852900D01*
X192700Y852233D01*
X192283Y851733D01*
X191533Y851483D01*
X189533D01*
G01X198633Y853983D02*
X198133Y854233D01*
X197550Y854400D01*
X196883D01*
X196133Y854150D01*
X195550Y853733D01*
X195133Y853233D01*
X194800Y852400D01*
X194717Y851650D01*
X194883Y850900D01*
X195133Y850400D01*
X195633Y849900D01*
X196217Y849567D01*
X196800Y849400D01*
X197383D01*
X197967Y849567D01*
X198467Y849817D01*
X198883Y850150D01*
G01X201317Y851067D02*
X203483D01*
G01X206417Y851483D02*
X207000Y852067D01*
X207500Y852400D01*
X208167Y852567D01*
X208750Y852400D01*
X209167Y852067D01*
X209500Y851567D01*
X209583Y850983D01*
X209500Y850483D01*
X209167Y849983D01*
X208667Y849567D01*
X208083Y849400D01*
X207417Y849567D01*
X206833Y850067D01*
X206500Y850817D01*
X206417Y851650D01*
X206583Y852733D01*
X206833Y853317D01*
X207250Y853900D01*
X207833Y854317D01*
X208417Y854400D01*
X209000Y854233D01*
X209417Y853817D01*
G01X213600Y854400D02*
X212933Y854233D01*
X212433Y853817D01*
X212100Y853317D01*
X211850Y852650D01*
X211767Y851900D01*
X211850Y851150D01*
X212100Y850483D01*
X212433Y849983D01*
X212933Y849567D01*
X213600Y849400D01*
X214267Y849567D01*
X214767Y849983D01*
X215100Y850483D01*
X215350Y851150D01*
X215433Y851900D01*
X215350Y852650D01*
X215100Y853317D01*
X214767Y853817D01*
X214267Y854233D01*
X213600Y854400D01*
G01X219200Y849400D02*
Y854400D01*
X218200Y853400D01*
G01Y849400D02*
X220200D01*
G01X223217Y851483D02*
X223800Y852067D01*
X224300Y852400D01*
X224967Y852567D01*
X225550Y852400D01*
X225967Y852067D01*
X226300Y851567D01*
X226383Y850983D01*
X226300Y850483D01*
X225967Y849983D01*
X225467Y849567D01*
X224883Y849400D01*
X224217Y849567D01*
X223633Y850067D01*
X223300Y850817D01*
X223217Y851650D01*
X223383Y852733D01*
X223633Y853317D01*
X224050Y853900D01*
X224633Y854317D01*
X225217Y854400D01*
X225800Y854233D01*
X226217Y853817D01*
G01X236000Y849400D02*
X235333Y849483D01*
X234750Y849817D01*
X234250Y850317D01*
X233917Y850900D01*
X233750Y851567D01*
Y852233D01*
X233917Y852900D01*
X234250Y853483D01*
X234750Y853983D01*
X235333Y854317D01*
X236000Y854400D01*
X236667Y854317D01*
X237250Y853983D01*
X237750Y853483D01*
X238083Y852900D01*
X238250Y852233D01*
Y851567D01*
X238083Y850900D01*
X237750Y850317D01*
X237250Y849817D01*
X236667Y849483D01*
X236000Y849400D01*
G01X236667Y850733D02*
X237667Y849400D01*
G01X240183Y852733D02*
Y850400D01*
X240517Y849817D01*
X241017Y849483D01*
X241600Y849400D01*
X242183Y849483D01*
X242683Y849817D01*
X243017Y850400D01*
G01Y849400D02*
Y852733D01*
G01X248700Y849400D02*
Y852733D01*
G01Y852150D02*
X248367Y852483D01*
X247867Y852650D01*
X247283Y852733D01*
X246700Y852567D01*
X246200Y852233D01*
X245867Y851733D01*
X245700Y851067D01*
X245867Y850400D01*
X246200Y849900D01*
X246700Y849567D01*
X247283Y849400D01*
X247867Y849483D01*
X248367Y849733D01*
X248700Y850067D01*
G01X252800Y849400D02*
Y854400D01*
G01X258400Y852733D02*
Y849400D01*
G01Y854067D02*
X258233Y854150D01*
Y854317D01*
X258400Y854400D01*
X258567Y854317D01*
Y854150D01*
X258400Y854067D01*
G01X263500Y849400D02*
Y853650D01*
X263667Y854067D01*
X264000Y854317D01*
X264500Y854400D01*
X265000Y854233D01*
X265250Y853817D01*
G01X264250Y852400D02*
X262583D01*
G01X269600Y852733D02*
Y849400D01*
G01Y854067D02*
X269433Y854150D01*
Y854317D01*
X269600Y854400D01*
X269767Y854317D01*
Y854150D01*
X269600Y854067D01*
G01X276533Y852317D02*
X275950Y852650D01*
X275450Y852733D01*
X274783Y852567D01*
X274283Y852233D01*
X273950Y851650D01*
X273867Y851067D01*
X273950Y850483D01*
X274283Y849983D01*
X274783Y849567D01*
X275450Y849400D01*
X276033Y849567D01*
X276533Y849900D01*
G01X282300Y849400D02*
Y852733D01*
G01Y852150D02*
X281967Y852483D01*
X281467Y852650D01*
X280883Y852733D01*
X280300Y852567D01*
X279800Y852233D01*
X279467Y851733D01*
X279300Y851067D01*
X279467Y850400D01*
X279800Y849900D01*
X280300Y849567D01*
X280883Y849400D01*
X281467Y849483D01*
X281967Y849733D01*
X282300Y850067D01*
G01X286400Y854400D02*
Y849400D01*
G01X285233Y852733D02*
X287567D01*
G01X292000D02*
Y849400D01*
G01Y854067D02*
X291833Y854150D01*
Y854317D01*
X292000Y854400D01*
X292167Y854317D01*
Y854150D01*
X292000Y854067D01*
G01X297600Y849400D02*
X297100Y849483D01*
X296600Y849817D01*
X296267Y850400D01*
X296100Y851067D01*
X296267Y851733D01*
X296600Y852317D01*
X297100Y852650D01*
X297600Y852733D01*
X298100Y852650D01*
X298600Y852317D01*
X298933Y851733D01*
X299017Y851067D01*
X298933Y850400D01*
X298600Y849817D01*
X298100Y849483D01*
X297600Y849400D01*
G01X301783D02*
Y852733D01*
G01Y851900D02*
X302117Y852317D01*
X302617Y852650D01*
X303283Y852733D01*
X303867Y852650D01*
X304367Y852317D01*
X304617Y851733D01*
Y849400D01*
G01X316900Y847733D02*
X312733Y852733D01*
Y853567D01*
X313567Y854400D01*
X314400D01*
X315233Y853567D01*
Y852733D01*
X314400Y851900D01*
X312733Y851067D01*
X311900Y850233D01*
Y848567D01*
X312733Y847733D01*
X315233D01*
X316900Y849400D01*
G01X323933D02*
Y854400D01*
X325933D01*
X326600Y854150D01*
X327100Y853567D01*
X327267Y852900D01*
X327100Y852233D01*
X326683Y851733D01*
X325933Y851483D01*
X323933D01*
G01X329950Y851650D02*
X332617D01*
X332367Y852233D01*
X331950Y852567D01*
X331367Y852733D01*
X330783Y852650D01*
X330283Y852400D01*
X329950Y851817D01*
X329783Y851317D01*
Y850817D01*
X329950Y850317D01*
X330367Y849817D01*
X330867Y849483D01*
X331450Y849400D01*
X332033Y849567D01*
X332617Y850067D01*
G01X335633Y849400D02*
Y852733D01*
G01Y852067D02*
X336050Y852400D01*
X336467Y852650D01*
X337050Y852733D01*
X337467Y852650D01*
X337967Y852400D01*
G01X341900Y849400D02*
Y853650D01*
X342067Y854067D01*
X342400Y854317D01*
X342900Y854400D01*
X343400Y854233D01*
X343650Y853817D01*
G01X342650Y852400D02*
X340983D01*
G01X348000Y849400D02*
X347500Y849483D01*
X347000Y849817D01*
X346667Y850400D01*
X346500Y851067D01*
X346667Y851733D01*
X347000Y852317D01*
X347500Y852650D01*
X348000Y852733D01*
X348500Y852650D01*
X349000Y852317D01*
X349333Y851733D01*
X349417Y851067D01*
X349333Y850400D01*
X349000Y849817D01*
X348500Y849483D01*
X348000Y849400D01*
G01X352433D02*
Y852733D01*
G01Y852067D02*
X352850Y852400D01*
X353267Y852650D01*
X353850Y852733D01*
X354267Y852650D01*
X354767Y852400D01*
G01X356700Y849400D02*
Y852733D01*
G01Y851817D02*
X356950Y852233D01*
X357367Y852567D01*
X357950Y852733D01*
X358533Y852567D01*
X358950Y852233D01*
X359200Y851817D01*
Y849400D01*
G01Y851817D02*
X359450Y852233D01*
X359867Y852567D01*
X360450Y852733D01*
X361033Y852567D01*
X361450Y852233D01*
X361700Y851733D01*
Y849400D01*
G01X366300D02*
Y852733D01*
G01Y852150D02*
X365967Y852483D01*
X365467Y852650D01*
X364883Y852733D01*
X364300Y852567D01*
X363800Y852233D01*
X363467Y851733D01*
X363300Y851067D01*
X363467Y850400D01*
X363800Y849900D01*
X364300Y849567D01*
X364883Y849400D01*
X365467Y849483D01*
X365967Y849733D01*
X366300Y850067D01*
G01X368983Y849400D02*
Y852733D01*
G01Y851900D02*
X369317Y852317D01*
X369817Y852650D01*
X370483Y852733D01*
X371067Y852650D01*
X371567Y852317D01*
X371817Y851733D01*
Y849400D01*
G01X377333Y852317D02*
X376750Y852650D01*
X376250Y852733D01*
X375583Y852567D01*
X375083Y852233D01*
X374750Y851650D01*
X374667Y851067D01*
X374750Y850483D01*
X375083Y849983D01*
X375583Y849567D01*
X376250Y849400D01*
X376833Y849567D01*
X377333Y849900D01*
G01X380350Y851650D02*
X383017D01*
X382767Y852233D01*
X382350Y852567D01*
X381767Y852733D01*
X381183Y852650D01*
X380683Y852400D01*
X380350Y851817D01*
X380183Y851317D01*
Y850817D01*
X380350Y850317D01*
X380767Y849817D01*
X381267Y849483D01*
X381850Y849400D01*
X382433Y849567D01*
X383017Y850067D01*
G01X391050D02*
X391717Y849650D01*
X392467Y849400D01*
X393133D01*
X393800Y849650D01*
X394300Y850067D01*
X394550Y850650D01*
X394383Y851233D01*
X393967Y851733D01*
X393217Y852067D01*
X392217Y852233D01*
X391633Y852567D01*
X391383Y853150D01*
X391550Y853733D01*
X391967Y854150D01*
X392550Y854400D01*
X393133D01*
X393717Y854233D01*
X394217Y853817D01*
G01X396900Y847733D02*
Y852733D01*
G01Y851983D02*
X397317Y852400D01*
X397733Y852650D01*
X398400Y852733D01*
X398983Y852650D01*
X399567Y852233D01*
X399817Y851650D01*
X399900Y851067D01*
X399817Y850483D01*
X399567Y849900D01*
X399067Y849567D01*
X398400Y849400D01*
X397817Y849483D01*
X397233Y849733D01*
X396900Y850067D01*
G01X402750Y851650D02*
X405417D01*
X405167Y852233D01*
X404750Y852567D01*
X404167Y852733D01*
X403583Y852650D01*
X403083Y852400D01*
X402750Y851817D01*
X402583Y851317D01*
Y850817D01*
X402750Y850317D01*
X403167Y849817D01*
X403667Y849483D01*
X404250Y849400D01*
X404833Y849567D01*
X405417Y850067D01*
G01X410933Y852317D02*
X410350Y852650D01*
X409850Y852733D01*
X409183Y852567D01*
X408683Y852233D01*
X408350Y851650D01*
X408267Y851067D01*
X408350Y850483D01*
X408683Y849983D01*
X409183Y849567D01*
X409850Y849400D01*
X410433Y849567D01*
X410933Y849900D01*
G01X415200Y852733D02*
Y849400D01*
G01Y854067D02*
X415033Y854150D01*
Y854317D01*
X415200Y854400D01*
X415367Y854317D01*
Y854150D01*
X415200Y854067D01*
G01X420300Y849400D02*
Y853650D01*
X420467Y854067D01*
X420800Y854317D01*
X421300Y854400D01*
X421800Y854233D01*
X422050Y853817D01*
G01X421050Y852400D02*
X419383D01*
G01X426400Y852733D02*
Y849400D01*
G01Y854067D02*
X426233Y854150D01*
Y854317D01*
X426400Y854400D01*
X426567Y854317D01*
Y854150D01*
X426400Y854067D01*
G01X433333Y852317D02*
X432750Y852650D01*
X432250Y852733D01*
X431583Y852567D01*
X431083Y852233D01*
X430750Y851650D01*
X430667Y851067D01*
X430750Y850483D01*
X431083Y849983D01*
X431583Y849567D01*
X432250Y849400D01*
X432833Y849567D01*
X433333Y849900D01*
G01X439100Y849400D02*
Y852733D01*
G01Y852150D02*
X438767Y852483D01*
X438267Y852650D01*
X437683Y852733D01*
X437100Y852567D01*
X436600Y852233D01*
X436267Y851733D01*
X436100Y851067D01*
X436267Y850400D01*
X436600Y849900D01*
X437100Y849567D01*
X437683Y849400D01*
X438267Y849483D01*
X438767Y849733D01*
X439100Y850067D01*
G01X443200Y854400D02*
Y849400D01*
G01X442033Y852733D02*
X444367D01*
G01X448800D02*
Y849400D01*
G01Y854067D02*
X448633Y854150D01*
Y854317D01*
X448800Y854400D01*
X448967Y854317D01*
Y854150D01*
X448800Y854067D01*
G01X454400Y849400D02*
X453900Y849483D01*
X453400Y849817D01*
X453067Y850400D01*
X452900Y851067D01*
X453067Y851733D01*
X453400Y852317D01*
X453900Y852650D01*
X454400Y852733D01*
X454900Y852650D01*
X455400Y852317D01*
X455733Y851733D01*
X455817Y851067D01*
X455733Y850400D01*
X455400Y849817D01*
X454900Y849483D01*
X454400Y849400D01*
G01X458583D02*
Y852733D01*
G01Y851900D02*
X458917Y852317D01*
X459417Y852650D01*
X460083Y852733D01*
X460667Y852650D01*
X461167Y852317D01*
X461417Y851733D01*
Y849400D01*
G01X470700D02*
Y853650D01*
X470867Y854067D01*
X471200Y854317D01*
X471700Y854400D01*
X472200Y854233D01*
X472450Y853817D01*
G01X471450Y852400D02*
X469783D01*
G01X476800Y849400D02*
X476300Y849483D01*
X475800Y849817D01*
X475467Y850400D01*
X475300Y851067D01*
X475467Y851733D01*
X475800Y852317D01*
X476300Y852650D01*
X476800Y852733D01*
X477300Y852650D01*
X477800Y852317D01*
X478133Y851733D01*
X478217Y851067D01*
X478133Y850400D01*
X477800Y849817D01*
X477300Y849483D01*
X476800Y849400D01*
G01X481233D02*
Y852733D01*
G01Y852067D02*
X481650Y852400D01*
X482067Y852650D01*
X482650Y852733D01*
X483067Y852650D01*
X483567Y852400D01*
G01X491850Y849400D02*
Y854400D01*
G01X495350D02*
Y849400D01*
G01Y851900D02*
X491850D01*
G01X499200Y852733D02*
Y849400D01*
G01Y854067D02*
X499033Y854150D01*
Y854317D01*
X499200Y854400D01*
X499367Y854317D01*
Y854150D01*
X499200Y854067D01*
G01X503633Y848150D02*
X504217Y847817D01*
X504883Y847733D01*
X505467Y847817D01*
X505967Y848233D01*
X506300Y848817D01*
Y852733D01*
G01Y852067D02*
X505967Y852400D01*
X505467Y852650D01*
X504883Y852733D01*
X504217Y852567D01*
X503800Y852233D01*
X503467Y851650D01*
X503300Y851067D01*
X503383Y850567D01*
X503717Y849983D01*
X504217Y849567D01*
X504883Y849400D01*
X505383Y849483D01*
X505967Y849817D01*
X506300Y850150D01*
G01X508983Y849400D02*
Y854400D01*
G01Y851983D02*
X509400Y852400D01*
X509817Y852650D01*
X510483Y852733D01*
X510983Y852650D01*
X511567Y852317D01*
X511817Y851817D01*
Y849400D01*
G01X519767D02*
Y854400D01*
X521433D01*
X522100Y854150D01*
X522600Y853817D01*
X523017Y853317D01*
X523350Y852733D01*
X523433Y851900D01*
X523350Y851067D01*
X523017Y850483D01*
X522600Y849983D01*
X522100Y849650D01*
X521433Y849400D01*
X519767D01*
G01X525950Y851650D02*
X528617D01*
X528367Y852233D01*
X527950Y852567D01*
X527367Y852733D01*
X526783Y852650D01*
X526283Y852400D01*
X525950Y851817D01*
X525783Y851317D01*
Y850817D01*
X525950Y850317D01*
X526367Y849817D01*
X526867Y849483D01*
X527450Y849400D01*
X528033Y849567D01*
X528617Y850067D01*
G01X531383Y849400D02*
Y852733D01*
G01Y851900D02*
X531717Y852317D01*
X532217Y852650D01*
X532883Y852733D01*
X533467Y852650D01*
X533967Y852317D01*
X534217Y851733D01*
Y849400D01*
G01X537150Y849983D02*
X537567Y849650D01*
X538150Y849400D01*
X538650D01*
X539150Y849567D01*
X539483Y849817D01*
X539650Y850150D01*
X539567Y850650D01*
X539233Y850900D01*
X537733Y851400D01*
X537400Y851983D01*
X537567Y852400D01*
X537900Y852650D01*
X538400Y852733D01*
X538900Y852650D01*
X539400Y852400D01*
G01X544000Y852733D02*
Y849400D01*
G01Y854067D02*
X543833Y854150D01*
Y854317D01*
X544000Y854400D01*
X544167Y854317D01*
Y854150D01*
X544000Y854067D01*
G01X549600Y854400D02*
Y849400D01*
G01X548433Y852733D02*
X550767D01*
G01X553450Y847900D02*
X553950Y847733D01*
X554617Y847900D01*
X555033Y848233D01*
X555367Y848650D01*
X555867Y849983D01*
X556950Y852733D01*
G01X554283D02*
X555867Y849983D01*
G01X565400Y854400D02*
X567400D01*
G01X566400D02*
Y849400D01*
G01X565400D02*
X567400D01*
G01X570583D02*
Y852733D01*
G01Y851900D02*
X570917Y852317D01*
X571417Y852650D01*
X572083Y852733D01*
X572667Y852650D01*
X573167Y852317D01*
X573417Y851733D01*
Y849400D01*
G01X577600Y854400D02*
Y849400D01*
G01X576433Y852733D02*
X578767D01*
G01X581950Y851650D02*
X584617D01*
X584367Y852233D01*
X583950Y852567D01*
X583367Y852733D01*
X582783Y852650D01*
X582283Y852400D01*
X581950Y851817D01*
X581783Y851317D01*
Y850817D01*
X581950Y850317D01*
X582367Y849817D01*
X582867Y849483D01*
X583450Y849400D01*
X584033Y849567D01*
X584617Y850067D01*
G01X587633Y849400D02*
Y852733D01*
G01Y852067D02*
X588050Y852400D01*
X588467Y852650D01*
X589050Y852733D01*
X589467Y852650D01*
X589967Y852400D01*
G01X595733Y852317D02*
X595150Y852650D01*
X594650Y852733D01*
X593983Y852567D01*
X593483Y852233D01*
X593150Y851650D01*
X593067Y851067D01*
X593150Y850483D01*
X593483Y849983D01*
X593983Y849567D01*
X594650Y849400D01*
X595233Y849567D01*
X595733Y849900D01*
G01X600000Y849400D02*
X599500Y849483D01*
X599000Y849817D01*
X598667Y850400D01*
X598500Y851067D01*
X598667Y851733D01*
X599000Y852317D01*
X599500Y852650D01*
X600000Y852733D01*
X600500Y852650D01*
X601000Y852317D01*
X601333Y851733D01*
X601417Y851067D01*
X601333Y850400D01*
X601000Y849817D01*
X600500Y849483D01*
X600000Y849400D01*
G01X604183D02*
Y852733D01*
G01Y851900D02*
X604517Y852317D01*
X605017Y852650D01*
X605683Y852733D01*
X606267Y852650D01*
X606767Y852317D01*
X607017Y851733D01*
Y849400D01*
G01X609783D02*
Y852733D01*
G01Y851900D02*
X610117Y852317D01*
X610617Y852650D01*
X611283Y852733D01*
X611867Y852650D01*
X612367Y852317D01*
X612617Y851733D01*
Y849400D01*
G01X615550Y851650D02*
X618217D01*
X617967Y852233D01*
X617550Y852567D01*
X616967Y852733D01*
X616383Y852650D01*
X615883Y852400D01*
X615550Y851817D01*
X615383Y851317D01*
Y850817D01*
X615550Y850317D01*
X615967Y849817D01*
X616467Y849483D01*
X617050Y849400D01*
X617633Y849567D01*
X618217Y850067D01*
G01X623733Y852317D02*
X623150Y852650D01*
X622650Y852733D01*
X621983Y852567D01*
X621483Y852233D01*
X621150Y851650D01*
X621067Y851067D01*
X621150Y850483D01*
X621483Y849983D01*
X621983Y849567D01*
X622650Y849400D01*
X623233Y849567D01*
X623733Y849900D01*
G01X628000Y854400D02*
Y849400D01*
G01X626833Y852733D02*
X629167D01*
G01X633183Y847733D02*
X632350Y848567D01*
X631933Y849400D01*
Y852733D01*
X632350Y853567D01*
X633183Y854400D01*
G01X637450Y849400D02*
Y854400D01*
G01X640950D02*
Y849400D01*
G01Y851900D02*
X637450D01*
G01X642967Y849400D02*
Y854400D01*
X644633D01*
X645300Y854150D01*
X645800Y853817D01*
X646217Y853317D01*
X646550Y852733D01*
X646633Y851900D01*
X646550Y851067D01*
X646217Y850483D01*
X645800Y849983D01*
X645300Y849650D01*
X644633Y849400D01*
X642967D01*
G01X649400Y854400D02*
X651400D01*
G01X650400D02*
Y849400D01*
G01X649400D02*
X651400D01*
G01X656417Y847733D02*
X657250Y848567D01*
X657667Y849400D01*
Y852733D01*
X657250Y853567D01*
X656417Y854400D01*
G01X665533D02*
Y849400D01*
X668867D01*
G01X674300D02*
Y852733D01*
G01Y852150D02*
X673967Y852483D01*
X673467Y852650D01*
X672883Y852733D01*
X672300Y852567D01*
X671800Y852233D01*
X671467Y851733D01*
X671300Y851067D01*
X671467Y850400D01*
X671800Y849900D01*
X672300Y849567D01*
X672883Y849400D01*
X673467Y849483D01*
X673967Y849733D01*
X674300Y850067D01*
G01X676650Y847900D02*
X677150Y847733D01*
X677817Y847900D01*
X678233Y848233D01*
X678567Y848650D01*
X679067Y849983D01*
X680150Y852733D01*
G01X677483D02*
X679067Y849983D01*
G01X682750Y851650D02*
X685417D01*
X685167Y852233D01*
X684750Y852567D01*
X684167Y852733D01*
X683583Y852650D01*
X683083Y852400D01*
X682750Y851817D01*
X682583Y851317D01*
Y850817D01*
X682750Y850317D01*
X683167Y849817D01*
X683667Y849483D01*
X684250Y849400D01*
X684833Y849567D01*
X685417Y850067D01*
G01X688433Y849400D02*
Y852733D01*
G01Y852067D02*
X688850Y852400D01*
X689267Y852650D01*
X689850Y852733D01*
X690267Y852650D01*
X690767Y852400D01*
G01X693950Y849983D02*
X694367Y849650D01*
X694950Y849400D01*
X695450D01*
X695950Y849567D01*
X696283Y849817D01*
X696450Y850150D01*
X696367Y850650D01*
X696033Y850900D01*
X694533Y851400D01*
X694200Y851983D01*
X694367Y852400D01*
X694700Y852650D01*
X695200Y852733D01*
X695700Y852650D01*
X696200Y852400D01*
G01X706400Y849400D02*
X705900Y849483D01*
X705400Y849817D01*
X705067Y850400D01*
X704900Y851067D01*
X705067Y851733D01*
X705400Y852317D01*
X705900Y852650D01*
X706400Y852733D01*
X706900Y852650D01*
X707400Y852317D01*
X707733Y851733D01*
X707817Y851067D01*
X707733Y850400D01*
X707400Y849817D01*
X706900Y849483D01*
X706400Y849400D01*
G01X710833D02*
Y852733D01*
G01Y852067D02*
X711250Y852400D01*
X711667Y852650D01*
X712250Y852733D01*
X712667Y852650D01*
X713167Y852400D01*
G01X723867Y852067D02*
X724200Y852317D01*
X724450Y852733D01*
X724617Y853317D01*
X724450Y853817D01*
X724117Y854150D01*
X723533Y854400D01*
X721283D01*
Y849400D01*
X724033D01*
X724617Y849733D01*
X724950Y850233D01*
X725117Y850817D01*
X724950Y851400D01*
X724450Y851900D01*
X723867Y852067D01*
X721283D01*
G01X728800Y849400D02*
X728300Y849483D01*
X727800Y849817D01*
X727467Y850400D01*
X727300Y851067D01*
X727467Y851733D01*
X727800Y852317D01*
X728300Y852650D01*
X728800Y852733D01*
X729300Y852650D01*
X729800Y852317D01*
X730133Y851733D01*
X730217Y851067D01*
X730133Y850400D01*
X729800Y849817D01*
X729300Y849483D01*
X728800Y849400D01*
G01X735900D02*
Y852733D01*
G01Y852150D02*
X735567Y852483D01*
X735067Y852650D01*
X734483Y852733D01*
X733900Y852567D01*
X733400Y852233D01*
X733067Y851733D01*
X732900Y851067D01*
X733067Y850400D01*
X733400Y849900D01*
X733900Y849567D01*
X734483Y849400D01*
X735067Y849483D01*
X735567Y849733D01*
X735900Y850067D01*
G01X738833Y849400D02*
Y852733D01*
G01Y852067D02*
X739250Y852400D01*
X739667Y852650D01*
X740250Y852733D01*
X740667Y852650D01*
X741167Y852400D01*
G01X747100Y854400D02*
Y849400D01*
G01Y850150D02*
X746767Y849733D01*
X746267Y849483D01*
X745683Y849400D01*
X745017Y849567D01*
X744517Y849983D01*
X744183Y850483D01*
X744100Y851067D01*
X744183Y851650D01*
X744517Y852150D01*
X745017Y852567D01*
X745683Y852733D01*
X746267Y852650D01*
X746683Y852483D01*
X747100Y852150D01*
G01X749950Y849983D02*
X750367Y849650D01*
X750950Y849400D01*
X751450D01*
X751950Y849567D01*
X752283Y849817D01*
X752450Y850150D01*
X752367Y850650D01*
X752033Y850900D01*
X750533Y851400D01*
X750200Y851983D01*
X750367Y852400D01*
X750700Y852650D01*
X751200Y852733D01*
X751700Y852650D01*
X752200Y852400D01*
G01X757217Y847733D02*
X758050Y848567D01*
X758467Y849400D01*
Y852733D01*
X758050Y853567D01*
X757217Y854400D01*
G01X184600Y863400D02*
X186600D01*
G01X185600D02*
Y858400D01*
G01X184600D02*
X186600D01*
G01X189533D02*
Y863400D01*
X191533D01*
X192200Y863150D01*
X192700Y862567D01*
X192867Y861900D01*
X192700Y861233D01*
X192283Y860733D01*
X191533Y860483D01*
X189533D01*
G01X198633Y862983D02*
X198133Y863233D01*
X197550Y863400D01*
X196883D01*
X196133Y863150D01*
X195550Y862733D01*
X195133Y862233D01*
X194800Y861400D01*
X194717Y860650D01*
X194883Y859900D01*
X195133Y859400D01*
X195633Y858900D01*
X196217Y858567D01*
X196800Y858400D01*
X197383D01*
X197967Y858567D01*
X198467Y858817D01*
X198883Y859150D01*
G01X201317Y860067D02*
X203483D01*
G01X206417Y860483D02*
X207000Y861067D01*
X207500Y861400D01*
X208167Y861567D01*
X208750Y861400D01*
X209167Y861067D01*
X209500Y860567D01*
X209583Y859983D01*
X209500Y859483D01*
X209167Y858983D01*
X208667Y858567D01*
X208083Y858400D01*
X207417Y858567D01*
X206833Y859067D01*
X206500Y859817D01*
X206417Y860650D01*
X206583Y861733D01*
X206833Y862317D01*
X207250Y862900D01*
X207833Y863317D01*
X208417Y863400D01*
X209000Y863233D01*
X209417Y862817D01*
G01X213600Y863400D02*
X212933Y863233D01*
X212433Y862817D01*
X212100Y862317D01*
X211850Y861650D01*
X211767Y860900D01*
X211850Y860150D01*
X212100Y859483D01*
X212433Y858983D01*
X212933Y858567D01*
X213600Y858400D01*
X214267Y858567D01*
X214767Y858983D01*
X215100Y859483D01*
X215350Y860150D01*
X215433Y860900D01*
X215350Y861650D01*
X215100Y862317D01*
X214767Y862817D01*
X214267Y863233D01*
X213600Y863400D01*
G01X219200Y858400D02*
Y863400D01*
X218200Y862400D01*
G01Y858400D02*
X220200D01*
G01X223217Y862567D02*
X223717Y863067D01*
X224300Y863317D01*
X224967Y863400D01*
X225800Y863233D01*
X226383Y862817D01*
X226550Y862317D01*
X226467Y861817D01*
X226133Y861400D01*
X224467Y860567D01*
X223717Y859983D01*
X223217Y859150D01*
X223050Y858400D01*
X226550D01*
G01X236000D02*
X235333Y858483D01*
X234750Y858817D01*
X234250Y859317D01*
X233917Y859900D01*
X233750Y860567D01*
Y861233D01*
X233917Y861900D01*
X234250Y862483D01*
X234750Y862983D01*
X235333Y863317D01*
X236000Y863400D01*
X236667Y863317D01*
X237250Y862983D01*
X237750Y862483D01*
X238083Y861900D01*
X238250Y861233D01*
Y860567D01*
X238083Y859900D01*
X237750Y859317D01*
X237250Y858817D01*
X236667Y858483D01*
X236000Y858400D01*
G01X236667Y859733D02*
X237667Y858400D01*
G01X240183Y861733D02*
Y859400D01*
X240517Y858817D01*
X241017Y858483D01*
X241600Y858400D01*
X242183Y858483D01*
X242683Y858817D01*
X243017Y859400D01*
G01Y858400D02*
Y861733D01*
G01X248700Y858400D02*
Y861733D01*
G01Y861150D02*
X248367Y861483D01*
X247867Y861650D01*
X247283Y861733D01*
X246700Y861567D01*
X246200Y861233D01*
X245867Y860733D01*
X245700Y860067D01*
X245867Y859400D01*
X246200Y858900D01*
X246700Y858567D01*
X247283Y858400D01*
X247867Y858483D01*
X248367Y858733D01*
X248700Y859067D01*
G01X252800Y858400D02*
Y863400D01*
G01X258400Y861733D02*
Y858400D01*
G01Y863067D02*
X258233Y863150D01*
Y863317D01*
X258400Y863400D01*
X258567Y863317D01*
Y863150D01*
X258400Y863067D01*
G01X263500Y858400D02*
Y862650D01*
X263667Y863067D01*
X264000Y863317D01*
X264500Y863400D01*
X265000Y863233D01*
X265250Y862817D01*
G01X264250Y861400D02*
X262583D01*
G01X269600Y861733D02*
Y858400D01*
G01Y863067D02*
X269433Y863150D01*
Y863317D01*
X269600Y863400D01*
X269767Y863317D01*
Y863150D01*
X269600Y863067D01*
G01X276533Y861317D02*
X275950Y861650D01*
X275450Y861733D01*
X274783Y861567D01*
X274283Y861233D01*
X273950Y860650D01*
X273867Y860067D01*
X273950Y859483D01*
X274283Y858983D01*
X274783Y858567D01*
X275450Y858400D01*
X276033Y858567D01*
X276533Y858900D01*
G01X282300Y858400D02*
Y861733D01*
G01Y861150D02*
X281967Y861483D01*
X281467Y861650D01*
X280883Y861733D01*
X280300Y861567D01*
X279800Y861233D01*
X279467Y860733D01*
X279300Y860067D01*
X279467Y859400D01*
X279800Y858900D01*
X280300Y858567D01*
X280883Y858400D01*
X281467Y858483D01*
X281967Y858733D01*
X282300Y859067D01*
G01X286400Y863400D02*
Y858400D01*
G01X285233Y861733D02*
X287567D01*
G01X292000D02*
Y858400D01*
G01Y863067D02*
X291833Y863150D01*
Y863317D01*
X292000Y863400D01*
X292167Y863317D01*
Y863150D01*
X292000Y863067D01*
G01X297600Y858400D02*
X297100Y858483D01*
X296600Y858817D01*
X296267Y859400D01*
X296100Y860067D01*
X296267Y860733D01*
X296600Y861317D01*
X297100Y861650D01*
X297600Y861733D01*
X298100Y861650D01*
X298600Y861317D01*
X298933Y860733D01*
X299017Y860067D01*
X298933Y859400D01*
X298600Y858817D01*
X298100Y858483D01*
X297600Y858400D01*
G01X301783D02*
Y861733D01*
G01Y860900D02*
X302117Y861317D01*
X302617Y861650D01*
X303283Y861733D01*
X303867Y861650D01*
X304367Y861317D01*
X304617Y860733D01*
Y858400D01*
G01X315900D02*
Y861733D01*
G01Y861150D02*
X315567Y861483D01*
X315067Y861650D01*
X314483Y861733D01*
X313900Y861567D01*
X313400Y861233D01*
X313067Y860733D01*
X312900Y860067D01*
X313067Y859400D01*
X313400Y858900D01*
X313900Y858567D01*
X314483Y858400D01*
X315067Y858483D01*
X315567Y858733D01*
X315900Y859067D01*
G01X318583Y858400D02*
Y861733D01*
G01Y860900D02*
X318917Y861317D01*
X319417Y861650D01*
X320083Y861733D01*
X320667Y861650D01*
X321167Y861317D01*
X321417Y860733D01*
Y858400D01*
G01X327100Y863400D02*
Y858400D01*
G01Y859150D02*
X326767Y858733D01*
X326267Y858483D01*
X325683Y858400D01*
X325017Y858567D01*
X324517Y858983D01*
X324183Y859483D01*
X324100Y860067D01*
X324183Y860650D01*
X324517Y861150D01*
X325017Y861567D01*
X325683Y861733D01*
X326267Y861650D01*
X326683Y861483D01*
X327100Y861150D01*
G01X335133Y858400D02*
Y863400D01*
X337133D01*
X337800Y863150D01*
X338300Y862567D01*
X338467Y861900D01*
X338300Y861233D01*
X337883Y860733D01*
X337133Y860483D01*
X335133D01*
G01X341150Y860650D02*
X343817D01*
X343567Y861233D01*
X343150Y861567D01*
X342567Y861733D01*
X341983Y861650D01*
X341483Y861400D01*
X341150Y860817D01*
X340983Y860317D01*
Y859817D01*
X341150Y859317D01*
X341567Y858817D01*
X342067Y858483D01*
X342650Y858400D01*
X343233Y858567D01*
X343817Y859067D01*
G01X346833Y858400D02*
Y861733D01*
G01Y861067D02*
X347250Y861400D01*
X347667Y861650D01*
X348250Y861733D01*
X348667Y861650D01*
X349167Y861400D01*
G01X353100Y858400D02*
Y862650D01*
X353267Y863067D01*
X353600Y863317D01*
X354100Y863400D01*
X354600Y863233D01*
X354850Y862817D01*
G01X353850Y861400D02*
X352183D01*
G01X359200Y858400D02*
X358700Y858483D01*
X358200Y858817D01*
X357867Y859400D01*
X357700Y860067D01*
X357867Y860733D01*
X358200Y861317D01*
X358700Y861650D01*
X359200Y861733D01*
X359700Y861650D01*
X360200Y861317D01*
X360533Y860733D01*
X360617Y860067D01*
X360533Y859400D01*
X360200Y858817D01*
X359700Y858483D01*
X359200Y858400D01*
G01X363633D02*
Y861733D01*
G01Y861067D02*
X364050Y861400D01*
X364467Y861650D01*
X365050Y861733D01*
X365467Y861650D01*
X365967Y861400D01*
G01X367900Y858400D02*
Y861733D01*
G01Y860817D02*
X368150Y861233D01*
X368567Y861567D01*
X369150Y861733D01*
X369733Y861567D01*
X370150Y861233D01*
X370400Y860817D01*
Y858400D01*
G01Y860817D02*
X370650Y861233D01*
X371067Y861567D01*
X371650Y861733D01*
X372233Y861567D01*
X372650Y861233D01*
X372900Y860733D01*
Y858400D01*
G01X377500D02*
Y861733D01*
G01Y861150D02*
X377167Y861483D01*
X376667Y861650D01*
X376083Y861733D01*
X375500Y861567D01*
X375000Y861233D01*
X374667Y860733D01*
X374500Y860067D01*
X374667Y859400D01*
X375000Y858900D01*
X375500Y858567D01*
X376083Y858400D01*
X376667Y858483D01*
X377167Y858733D01*
X377500Y859067D01*
G01X380183Y858400D02*
Y861733D01*
G01Y860900D02*
X380517Y861317D01*
X381017Y861650D01*
X381683Y861733D01*
X382267Y861650D01*
X382767Y861317D01*
X383017Y860733D01*
Y858400D01*
G01X388533Y861317D02*
X387950Y861650D01*
X387450Y861733D01*
X386783Y861567D01*
X386283Y861233D01*
X385950Y860650D01*
X385867Y860067D01*
X385950Y859483D01*
X386283Y858983D01*
X386783Y858567D01*
X387450Y858400D01*
X388033Y858567D01*
X388533Y858900D01*
G01X391550Y860650D02*
X394217D01*
X393967Y861233D01*
X393550Y861567D01*
X392967Y861733D01*
X392383Y861650D01*
X391883Y861400D01*
X391550Y860817D01*
X391383Y860317D01*
Y859817D01*
X391550Y859317D01*
X391967Y858817D01*
X392467Y858483D01*
X393050Y858400D01*
X393633Y858567D01*
X394217Y859067D01*
G01X402250D02*
X402917Y858650D01*
X403667Y858400D01*
X404333D01*
X405000Y858650D01*
X405500Y859067D01*
X405750Y859650D01*
X405583Y860233D01*
X405167Y860733D01*
X404417Y861067D01*
X403417Y861233D01*
X402833Y861567D01*
X402583Y862150D01*
X402750Y862733D01*
X403167Y863150D01*
X403750Y863400D01*
X404333D01*
X404917Y863233D01*
X405417Y862817D01*
G01X408100Y856733D02*
Y861733D01*
G01Y860983D02*
X408517Y861400D01*
X408933Y861650D01*
X409600Y861733D01*
X410183Y861650D01*
X410767Y861233D01*
X411017Y860650D01*
X411100Y860067D01*
X411017Y859483D01*
X410767Y858900D01*
X410267Y858567D01*
X409600Y858400D01*
X409017Y858483D01*
X408433Y858733D01*
X408100Y859067D01*
G01X413950Y860650D02*
X416617D01*
X416367Y861233D01*
X415950Y861567D01*
X415367Y861733D01*
X414783Y861650D01*
X414283Y861400D01*
X413950Y860817D01*
X413783Y860317D01*
Y859817D01*
X413950Y859317D01*
X414367Y858817D01*
X414867Y858483D01*
X415450Y858400D01*
X416033Y858567D01*
X416617Y859067D01*
G01X422133Y861317D02*
X421550Y861650D01*
X421050Y861733D01*
X420383Y861567D01*
X419883Y861233D01*
X419550Y860650D01*
X419467Y860067D01*
X419550Y859483D01*
X419883Y858983D01*
X420383Y858567D01*
X421050Y858400D01*
X421633Y858567D01*
X422133Y858900D01*
G01X426400Y861733D02*
Y858400D01*
G01Y863067D02*
X426233Y863150D01*
Y863317D01*
X426400Y863400D01*
X426567Y863317D01*
Y863150D01*
X426400Y863067D01*
G01X431500Y858400D02*
Y862650D01*
X431667Y863067D01*
X432000Y863317D01*
X432500Y863400D01*
X433000Y863233D01*
X433250Y862817D01*
G01X432250Y861400D02*
X430583D01*
G01X437600Y861733D02*
Y858400D01*
G01Y863067D02*
X437433Y863150D01*
Y863317D01*
X437600Y863400D01*
X437767Y863317D01*
Y863150D01*
X437600Y863067D01*
G01X444533Y861317D02*
X443950Y861650D01*
X443450Y861733D01*
X442783Y861567D01*
X442283Y861233D01*
X441950Y860650D01*
X441867Y860067D01*
X441950Y859483D01*
X442283Y858983D01*
X442783Y858567D01*
X443450Y858400D01*
X444033Y858567D01*
X444533Y858900D01*
G01X450300Y858400D02*
Y861733D01*
G01Y861150D02*
X449967Y861483D01*
X449467Y861650D01*
X448883Y861733D01*
X448300Y861567D01*
X447800Y861233D01*
X447467Y860733D01*
X447300Y860067D01*
X447467Y859400D01*
X447800Y858900D01*
X448300Y858567D01*
X448883Y858400D01*
X449467Y858483D01*
X449967Y858733D01*
X450300Y859067D01*
G01X454400Y863400D02*
Y858400D01*
G01X453233Y861733D02*
X455567D01*
G01X460000D02*
Y858400D01*
G01Y863067D02*
X459833Y863150D01*
Y863317D01*
X460000Y863400D01*
X460167Y863317D01*
Y863150D01*
X460000Y863067D01*
G01X465600Y858400D02*
X465100Y858483D01*
X464600Y858817D01*
X464267Y859400D01*
X464100Y860067D01*
X464267Y860733D01*
X464600Y861317D01*
X465100Y861650D01*
X465600Y861733D01*
X466100Y861650D01*
X466600Y861317D01*
X466933Y860733D01*
X467017Y860067D01*
X466933Y859400D01*
X466600Y858817D01*
X466100Y858483D01*
X465600Y858400D01*
G01X469783D02*
Y861733D01*
G01Y860900D02*
X470117Y861317D01*
X470617Y861650D01*
X471283Y861733D01*
X471867Y861650D01*
X472367Y861317D01*
X472617Y860733D01*
Y858400D01*
G01X481900D02*
Y862650D01*
X482067Y863067D01*
X482400Y863317D01*
X482900Y863400D01*
X483400Y863233D01*
X483650Y862817D01*
G01X482650Y861400D02*
X480983D01*
G01X488000Y858400D02*
X487500Y858483D01*
X487000Y858817D01*
X486667Y859400D01*
X486500Y860067D01*
X486667Y860733D01*
X487000Y861317D01*
X487500Y861650D01*
X488000Y861733D01*
X488500Y861650D01*
X489000Y861317D01*
X489333Y860733D01*
X489417Y860067D01*
X489333Y859400D01*
X489000Y858817D01*
X488500Y858483D01*
X488000Y858400D01*
G01X492433D02*
Y861733D01*
G01Y861067D02*
X492850Y861400D01*
X493267Y861650D01*
X493850Y861733D01*
X494267Y861650D01*
X494767Y861400D01*
G01X503133Y858400D02*
Y863400D01*
X505217D01*
X505883Y863150D01*
X506300Y862817D01*
X506467Y862150D01*
X506300Y861483D01*
X505800Y861067D01*
X505217Y860817D01*
X503133D01*
G01X505217D02*
X506467Y858400D01*
G01X510400Y861733D02*
Y858400D01*
G01Y863067D02*
X510233Y863150D01*
Y863317D01*
X510400Y863400D01*
X510567Y863317D01*
Y863150D01*
X510400Y863067D01*
G01X514833Y857150D02*
X515417Y856817D01*
X516083Y856733D01*
X516667Y856817D01*
X517167Y857233D01*
X517500Y857817D01*
Y861733D01*
G01Y861067D02*
X517167Y861400D01*
X516667Y861650D01*
X516083Y861733D01*
X515417Y861567D01*
X515000Y861233D01*
X514667Y860650D01*
X514500Y860067D01*
X514583Y859567D01*
X514917Y858983D01*
X515417Y858567D01*
X516083Y858400D01*
X516583Y858483D01*
X517167Y858817D01*
X517500Y859150D01*
G01X521600Y861733D02*
Y858400D01*
G01Y863067D02*
X521433Y863150D01*
Y863317D01*
X521600Y863400D01*
X521767Y863317D01*
Y863150D01*
X521600Y863067D01*
G01X528700Y863400D02*
Y858400D01*
G01Y859150D02*
X528367Y858733D01*
X527867Y858483D01*
X527283Y858400D01*
X526617Y858567D01*
X526117Y858983D01*
X525783Y859483D01*
X525700Y860067D01*
X525783Y860650D01*
X526117Y861150D01*
X526617Y861567D01*
X527283Y861733D01*
X527867Y861650D01*
X528283Y861483D01*
X528700Y861150D01*
G01X536733Y858400D02*
Y863400D01*
X538733D01*
X539400Y863150D01*
X539900Y862567D01*
X540067Y861900D01*
X539900Y861233D01*
X539483Y860733D01*
X538733Y860483D01*
X536733D01*
G01X542833Y858400D02*
Y861733D01*
G01Y861067D02*
X543250Y861400D01*
X543667Y861650D01*
X544250Y861733D01*
X544667Y861650D01*
X545167Y861400D01*
G01X549600Y861733D02*
Y858400D01*
G01Y863067D02*
X549433Y863150D01*
Y863317D01*
X549600Y863400D01*
X549767Y863317D01*
Y863150D01*
X549600Y863067D01*
G01X553783Y858400D02*
Y861733D01*
G01Y860900D02*
X554117Y861317D01*
X554617Y861650D01*
X555283Y861733D01*
X555867Y861650D01*
X556367Y861317D01*
X556617Y860733D01*
Y858400D01*
G01X560800Y863400D02*
Y858400D01*
G01X559633Y861733D02*
X561967D01*
G01X565150Y860650D02*
X567817D01*
X567567Y861233D01*
X567150Y861567D01*
X566567Y861733D01*
X565983Y861650D01*
X565483Y861400D01*
X565150Y860817D01*
X564983Y860317D01*
Y859817D01*
X565150Y859317D01*
X565567Y858817D01*
X566067Y858483D01*
X566650Y858400D01*
X567233Y858567D01*
X567817Y859067D01*
G01X573500Y863400D02*
Y858400D01*
G01Y859150D02*
X573167Y858733D01*
X572667Y858483D01*
X572083Y858400D01*
X571417Y858567D01*
X570917Y858983D01*
X570583Y859483D01*
X570500Y860067D01*
X570583Y860650D01*
X570917Y861150D01*
X571417Y861567D01*
X572083Y861733D01*
X572667Y861650D01*
X573083Y861483D01*
X573500Y861150D01*
G01X583867Y861067D02*
X584200Y861317D01*
X584450Y861733D01*
X584617Y862317D01*
X584450Y862817D01*
X584117Y863150D01*
X583533Y863400D01*
X581283D01*
Y858400D01*
X584033D01*
X584617Y858733D01*
X584950Y859233D01*
X585117Y859817D01*
X584950Y860400D01*
X584450Y860900D01*
X583867Y861067D01*
X581283D01*
G01X588800Y858400D02*
X588300Y858483D01*
X587800Y858817D01*
X587467Y859400D01*
X587300Y860067D01*
X587467Y860733D01*
X587800Y861317D01*
X588300Y861650D01*
X588800Y861733D01*
X589300Y861650D01*
X589800Y861317D01*
X590133Y860733D01*
X590217Y860067D01*
X590133Y859400D01*
X589800Y858817D01*
X589300Y858483D01*
X588800Y858400D01*
G01X595900D02*
Y861733D01*
G01Y861150D02*
X595567Y861483D01*
X595067Y861650D01*
X594483Y861733D01*
X593900Y861567D01*
X593400Y861233D01*
X593067Y860733D01*
X592900Y860067D01*
X593067Y859400D01*
X593400Y858900D01*
X593900Y858567D01*
X594483Y858400D01*
X595067Y858483D01*
X595567Y858733D01*
X595900Y859067D01*
G01X598833Y858400D02*
Y861733D01*
G01Y861067D02*
X599250Y861400D01*
X599667Y861650D01*
X600250Y861733D01*
X600667Y861650D01*
X601167Y861400D01*
G01X607100Y863400D02*
Y858400D01*
G01Y859150D02*
X606767Y858733D01*
X606267Y858483D01*
X605683Y858400D01*
X605017Y858567D01*
X604517Y858983D01*
X604183Y859483D01*
X604100Y860067D01*
X604183Y860650D01*
X604517Y861150D01*
X605017Y861567D01*
X605683Y861733D01*
X606267Y861650D01*
X606683Y861483D01*
X607100Y861150D01*
G01X609950Y858983D02*
X610367Y858650D01*
X610950Y858400D01*
X611450D01*
X611950Y858567D01*
X612283Y858817D01*
X612450Y859150D01*
X612367Y859650D01*
X612033Y859900D01*
X610533Y860400D01*
X610200Y860983D01*
X610367Y861400D01*
X610700Y861650D01*
X611200Y861733D01*
X611700Y861650D01*
X612200Y861400D01*
G01X180600Y868233D02*
X180433Y868317D01*
Y868483D01*
X180600Y868567D01*
X180767Y868483D01*
Y868317D01*
X180600Y868233D01*
G01Y875133D02*
X180433Y875217D01*
Y875383D01*
X180600Y875467D01*
X180767Y875383D01*
Y875217D01*
X180600Y875133D01*
G01X184600Y872400D02*
X186600D01*
G01X185600D02*
Y867400D01*
G01X184600D02*
X186600D01*
G01X189533D02*
Y872400D01*
X191533D01*
X192200Y872150D01*
X192700Y871567D01*
X192867Y870900D01*
X192700Y870233D01*
X192283Y869733D01*
X191533Y869483D01*
X189533D01*
G01X198633Y871983D02*
X198133Y872233D01*
X197550Y872400D01*
X196883D01*
X196133Y872150D01*
X195550Y871733D01*
X195133Y871233D01*
X194800Y870400D01*
X194717Y869650D01*
X194883Y868900D01*
X195133Y868400D01*
X195633Y867900D01*
X196217Y867567D01*
X196800Y867400D01*
X197383D01*
X197967Y867567D01*
X198467Y867817D01*
X198883Y868150D01*
G01X201317Y869067D02*
X203483D01*
G01X206417Y869483D02*
X207000Y870067D01*
X207500Y870400D01*
X208167Y870567D01*
X208750Y870400D01*
X209167Y870067D01*
X209500Y869567D01*
X209583Y868983D01*
X209500Y868483D01*
X209167Y867983D01*
X208667Y867567D01*
X208083Y867400D01*
X207417Y867567D01*
X206833Y868067D01*
X206500Y868817D01*
X206417Y869650D01*
X206583Y870733D01*
X206833Y871317D01*
X207250Y871900D01*
X207833Y872317D01*
X208417Y872400D01*
X209000Y872233D01*
X209417Y871817D01*
G01X213600Y872400D02*
X212933Y872233D01*
X212433Y871817D01*
X212100Y871317D01*
X211850Y870650D01*
X211767Y869900D01*
X211850Y869150D01*
X212100Y868483D01*
X212433Y867983D01*
X212933Y867567D01*
X213600Y867400D01*
X214267Y867567D01*
X214767Y867983D01*
X215100Y868483D01*
X215350Y869150D01*
X215433Y869900D01*
X215350Y870650D01*
X215100Y871317D01*
X214767Y871817D01*
X214267Y872233D01*
X213600Y872400D01*
G01X219200Y867400D02*
Y872400D01*
X218200Y871400D01*
G01Y867400D02*
X220200D01*
G01X224800D02*
Y872400D01*
X223800Y871400D01*
G01Y867400D02*
X225800D01*
G01X236500Y869900D02*
X238167D01*
Y868400D01*
X237667Y867900D01*
X237083Y867567D01*
X236250Y867400D01*
X235417Y867567D01*
X234833Y867900D01*
X234333Y868400D01*
X234000Y868983D01*
X233833Y869650D01*
Y870233D01*
X234000Y870733D01*
X234333Y871317D01*
X234833Y871817D01*
X235333Y872150D01*
X236000Y872400D01*
X236583D01*
X237250Y872233D01*
X237750Y871900D01*
G01X240350Y869650D02*
X243017D01*
X242767Y870233D01*
X242350Y870567D01*
X241767Y870733D01*
X241183Y870650D01*
X240683Y870400D01*
X240350Y869817D01*
X240183Y869317D01*
Y868817D01*
X240350Y868317D01*
X240767Y867817D01*
X241267Y867483D01*
X241850Y867400D01*
X242433Y867567D01*
X243017Y868067D01*
G01X245783Y867400D02*
Y870733D01*
G01Y869900D02*
X246117Y870317D01*
X246617Y870650D01*
X247283Y870733D01*
X247867Y870650D01*
X248367Y870317D01*
X248617Y869733D01*
Y867400D01*
G01X251550Y869650D02*
X254217D01*
X253967Y870233D01*
X253550Y870567D01*
X252967Y870733D01*
X252383Y870650D01*
X251883Y870400D01*
X251550Y869817D01*
X251383Y869317D01*
Y868817D01*
X251550Y868317D01*
X251967Y867817D01*
X252467Y867483D01*
X253050Y867400D01*
X253633Y867567D01*
X254217Y868067D01*
G01X257233Y867400D02*
Y870733D01*
G01Y870067D02*
X257650Y870400D01*
X258067Y870650D01*
X258650Y870733D01*
X259067Y870650D01*
X259567Y870400D01*
G01X264000Y870733D02*
Y867400D01*
G01Y872067D02*
X263833Y872150D01*
Y872317D01*
X264000Y872400D01*
X264167Y872317D01*
Y872150D01*
X264000Y872067D01*
G01X270933Y870317D02*
X270350Y870650D01*
X269850Y870733D01*
X269183Y870567D01*
X268683Y870233D01*
X268350Y869650D01*
X268267Y869067D01*
X268350Y868483D01*
X268683Y867983D01*
X269183Y867567D01*
X269850Y867400D01*
X270433Y867567D01*
X270933Y867900D01*
G01X279133Y867400D02*
Y872400D01*
X281133D01*
X281800Y872150D01*
X282300Y871567D01*
X282467Y870900D01*
X282300Y870233D01*
X281883Y869733D01*
X281133Y869483D01*
X279133D01*
G01X285150Y869650D02*
X287817D01*
X287567Y870233D01*
X287150Y870567D01*
X286567Y870733D01*
X285983Y870650D01*
X285483Y870400D01*
X285150Y869817D01*
X284983Y869317D01*
Y868817D01*
X285150Y868317D01*
X285567Y867817D01*
X286067Y867483D01*
X286650Y867400D01*
X287233Y867567D01*
X287817Y868067D01*
G01X290833Y867400D02*
Y870733D01*
G01Y870067D02*
X291250Y870400D01*
X291667Y870650D01*
X292250Y870733D01*
X292667Y870650D01*
X293167Y870400D01*
G01X297100Y867400D02*
Y871650D01*
X297267Y872067D01*
X297600Y872317D01*
X298100Y872400D01*
X298600Y872233D01*
X298850Y871817D01*
G01X297850Y870400D02*
X296183D01*
G01X303200Y867400D02*
X302700Y867483D01*
X302200Y867817D01*
X301867Y868400D01*
X301700Y869067D01*
X301867Y869733D01*
X302200Y870317D01*
X302700Y870650D01*
X303200Y870733D01*
X303700Y870650D01*
X304200Y870317D01*
X304533Y869733D01*
X304617Y869067D01*
X304533Y868400D01*
X304200Y867817D01*
X303700Y867483D01*
X303200Y867400D01*
G01X307633D02*
Y870733D01*
G01Y870067D02*
X308050Y870400D01*
X308467Y870650D01*
X309050Y870733D01*
X309467Y870650D01*
X309967Y870400D01*
G01X311900Y867400D02*
Y870733D01*
G01Y869817D02*
X312150Y870233D01*
X312567Y870567D01*
X313150Y870733D01*
X313733Y870567D01*
X314150Y870233D01*
X314400Y869817D01*
Y867400D01*
G01Y869817D02*
X314650Y870233D01*
X315067Y870567D01*
X315650Y870733D01*
X316233Y870567D01*
X316650Y870233D01*
X316900Y869733D01*
Y867400D01*
G01X321500D02*
Y870733D01*
G01Y870150D02*
X321167Y870483D01*
X320667Y870650D01*
X320083Y870733D01*
X319500Y870567D01*
X319000Y870233D01*
X318667Y869733D01*
X318500Y869067D01*
X318667Y868400D01*
X319000Y867900D01*
X319500Y867567D01*
X320083Y867400D01*
X320667Y867483D01*
X321167Y867733D01*
X321500Y868067D01*
G01X324183Y867400D02*
Y870733D01*
G01Y869900D02*
X324517Y870317D01*
X325017Y870650D01*
X325683Y870733D01*
X326267Y870650D01*
X326767Y870317D01*
X327017Y869733D01*
Y867400D01*
G01X332533Y870317D02*
X331950Y870650D01*
X331450Y870733D01*
X330783Y870567D01*
X330283Y870233D01*
X329950Y869650D01*
X329867Y869067D01*
X329950Y868483D01*
X330283Y867983D01*
X330783Y867567D01*
X331450Y867400D01*
X332033Y867567D01*
X332533Y867900D01*
G01X335550Y869650D02*
X338217D01*
X337967Y870233D01*
X337550Y870567D01*
X336967Y870733D01*
X336383Y870650D01*
X335883Y870400D01*
X335550Y869817D01*
X335383Y869317D01*
Y868817D01*
X335550Y868317D01*
X335967Y867817D01*
X336467Y867483D01*
X337050Y867400D01*
X337633Y867567D01*
X338217Y868067D01*
G01X346250D02*
X346917Y867650D01*
X347667Y867400D01*
X348333D01*
X349000Y867650D01*
X349500Y868067D01*
X349750Y868650D01*
X349583Y869233D01*
X349167Y869733D01*
X348417Y870067D01*
X347417Y870233D01*
X346833Y870567D01*
X346583Y871150D01*
X346750Y871733D01*
X347167Y872150D01*
X347750Y872400D01*
X348333D01*
X348917Y872233D01*
X349417Y871817D01*
G01X352100Y865733D02*
Y870733D01*
G01Y869983D02*
X352517Y870400D01*
X352933Y870650D01*
X353600Y870733D01*
X354183Y870650D01*
X354767Y870233D01*
X355017Y869650D01*
X355100Y869067D01*
X355017Y868483D01*
X354767Y867900D01*
X354267Y867567D01*
X353600Y867400D01*
X353017Y867483D01*
X352433Y867733D01*
X352100Y868067D01*
G01X357950Y869650D02*
X360617D01*
X360367Y870233D01*
X359950Y870567D01*
X359367Y870733D01*
X358783Y870650D01*
X358283Y870400D01*
X357950Y869817D01*
X357783Y869317D01*
Y868817D01*
X357950Y868317D01*
X358367Y867817D01*
X358867Y867483D01*
X359450Y867400D01*
X360033Y867567D01*
X360617Y868067D01*
G01X366133Y870317D02*
X365550Y870650D01*
X365050Y870733D01*
X364383Y870567D01*
X363883Y870233D01*
X363550Y869650D01*
X363467Y869067D01*
X363550Y868483D01*
X363883Y867983D01*
X364383Y867567D01*
X365050Y867400D01*
X365633Y867567D01*
X366133Y867900D01*
G01X370400Y870733D02*
Y867400D01*
G01Y872067D02*
X370233Y872150D01*
Y872317D01*
X370400Y872400D01*
X370567Y872317D01*
Y872150D01*
X370400Y872067D01*
G01X375500Y867400D02*
Y871650D01*
X375667Y872067D01*
X376000Y872317D01*
X376500Y872400D01*
X377000Y872233D01*
X377250Y871817D01*
G01X376250Y870400D02*
X374583D01*
G01X381600Y870733D02*
Y867400D01*
G01Y872067D02*
X381433Y872150D01*
Y872317D01*
X381600Y872400D01*
X381767Y872317D01*
Y872150D01*
X381600Y872067D01*
G01X388533Y870317D02*
X387950Y870650D01*
X387450Y870733D01*
X386783Y870567D01*
X386283Y870233D01*
X385950Y869650D01*
X385867Y869067D01*
X385950Y868483D01*
X386283Y867983D01*
X386783Y867567D01*
X387450Y867400D01*
X388033Y867567D01*
X388533Y867900D01*
G01X394300Y867400D02*
Y870733D01*
G01Y870150D02*
X393967Y870483D01*
X393467Y870650D01*
X392883Y870733D01*
X392300Y870567D01*
X391800Y870233D01*
X391467Y869733D01*
X391300Y869067D01*
X391467Y868400D01*
X391800Y867900D01*
X392300Y867567D01*
X392883Y867400D01*
X393467Y867483D01*
X393967Y867733D01*
X394300Y868067D01*
G01X398400Y872400D02*
Y867400D01*
G01X397233Y870733D02*
X399567D01*
G01X404000D02*
Y867400D01*
G01Y872067D02*
X403833Y872150D01*
Y872317D01*
X404000Y872400D01*
X404167Y872317D01*
Y872150D01*
X404000Y872067D01*
G01X409600Y867400D02*
X409100Y867483D01*
X408600Y867817D01*
X408267Y868400D01*
X408100Y869067D01*
X408267Y869733D01*
X408600Y870317D01*
X409100Y870650D01*
X409600Y870733D01*
X410100Y870650D01*
X410600Y870317D01*
X410933Y869733D01*
X411017Y869067D01*
X410933Y868400D01*
X410600Y867817D01*
X410100Y867483D01*
X409600Y867400D01*
G01X413783D02*
Y870733D01*
G01Y869900D02*
X414117Y870317D01*
X414617Y870650D01*
X415283Y870733D01*
X415867Y870650D01*
X416367Y870317D01*
X416617Y869733D01*
Y867400D01*
G01X425900D02*
Y871650D01*
X426067Y872067D01*
X426400Y872317D01*
X426900Y872400D01*
X427400Y872233D01*
X427650Y871817D01*
G01X426650Y870400D02*
X424983D01*
G01X432000Y867400D02*
X431500Y867483D01*
X431000Y867817D01*
X430667Y868400D01*
X430500Y869067D01*
X430667Y869733D01*
X431000Y870317D01*
X431500Y870650D01*
X432000Y870733D01*
X432500Y870650D01*
X433000Y870317D01*
X433333Y869733D01*
X433417Y869067D01*
X433333Y868400D01*
X433000Y867817D01*
X432500Y867483D01*
X432000Y867400D01*
G01X436433D02*
Y870733D01*
G01Y870067D02*
X436850Y870400D01*
X437267Y870650D01*
X437850Y870733D01*
X438267Y870650D01*
X438767Y870400D01*
G01X447133Y867400D02*
Y872400D01*
X449133D01*
X449800Y872150D01*
X450300Y871567D01*
X450467Y870900D01*
X450300Y870233D01*
X449883Y869733D01*
X449133Y869483D01*
X447133D01*
G01X453233Y867400D02*
Y870733D01*
G01Y870067D02*
X453650Y870400D01*
X454067Y870650D01*
X454650Y870733D01*
X455067Y870650D01*
X455567Y870400D01*
G01X460000Y870733D02*
Y867400D01*
G01Y872067D02*
X459833Y872150D01*
Y872317D01*
X460000Y872400D01*
X460167Y872317D01*
Y872150D01*
X460000Y872067D01*
G01X464183Y867400D02*
Y870733D01*
G01Y869900D02*
X464517Y870317D01*
X465017Y870650D01*
X465683Y870733D01*
X466267Y870650D01*
X466767Y870317D01*
X467017Y869733D01*
Y867400D01*
G01X471200Y872400D02*
Y867400D01*
G01X470033Y870733D02*
X472367D01*
G01X475550Y869650D02*
X478217D01*
X477967Y870233D01*
X477550Y870567D01*
X476967Y870733D01*
X476383Y870650D01*
X475883Y870400D01*
X475550Y869817D01*
X475383Y869317D01*
Y868817D01*
X475550Y868317D01*
X475967Y867817D01*
X476467Y867483D01*
X477050Y867400D01*
X477633Y867567D01*
X478217Y868067D01*
G01X483900Y872400D02*
Y867400D01*
G01Y868150D02*
X483567Y867733D01*
X483067Y867483D01*
X482483Y867400D01*
X481817Y867567D01*
X481317Y867983D01*
X480983Y868483D01*
X480900Y869067D01*
X480983Y869650D01*
X481317Y870150D01*
X481817Y870567D01*
X482483Y870733D01*
X483067Y870650D01*
X483483Y870483D01*
X483900Y870150D01*
G01X494267Y870067D02*
X494600Y870317D01*
X494850Y870733D01*
X495017Y871317D01*
X494850Y871817D01*
X494517Y872150D01*
X493933Y872400D01*
X491683D01*
Y867400D01*
X494433D01*
X495017Y867733D01*
X495350Y868233D01*
X495517Y868817D01*
X495350Y869400D01*
X494850Y869900D01*
X494267Y870067D01*
X491683D01*
G01X499200Y867400D02*
X498700Y867483D01*
X498200Y867817D01*
X497867Y868400D01*
X497700Y869067D01*
X497867Y869733D01*
X498200Y870317D01*
X498700Y870650D01*
X499200Y870733D01*
X499700Y870650D01*
X500200Y870317D01*
X500533Y869733D01*
X500617Y869067D01*
X500533Y868400D01*
X500200Y867817D01*
X499700Y867483D01*
X499200Y867400D01*
G01X506300D02*
Y870733D01*
G01Y870150D02*
X505967Y870483D01*
X505467Y870650D01*
X504883Y870733D01*
X504300Y870567D01*
X503800Y870233D01*
X503467Y869733D01*
X503300Y869067D01*
X503467Y868400D01*
X503800Y867900D01*
X504300Y867567D01*
X504883Y867400D01*
X505467Y867483D01*
X505967Y867733D01*
X506300Y868067D01*
G01X509233Y867400D02*
Y870733D01*
G01Y870067D02*
X509650Y870400D01*
X510067Y870650D01*
X510650Y870733D01*
X511067Y870650D01*
X511567Y870400D01*
G01X517500Y872400D02*
Y867400D01*
G01Y868150D02*
X517167Y867733D01*
X516667Y867483D01*
X516083Y867400D01*
X515417Y867567D01*
X514917Y867983D01*
X514583Y868483D01*
X514500Y869067D01*
X514583Y869650D01*
X514917Y870150D01*
X515417Y870567D01*
X516083Y870733D01*
X516667Y870650D01*
X517083Y870483D01*
X517500Y870150D01*
G01X520350Y867983D02*
X520767Y867650D01*
X521350Y867400D01*
X521850D01*
X522350Y867567D01*
X522683Y867817D01*
X522850Y868150D01*
X522767Y868650D01*
X522433Y868900D01*
X520933Y869400D01*
X520600Y869983D01*
X520767Y870400D01*
X521100Y870650D01*
X521600Y870733D01*
X522100Y870650D01*
X522600Y870400D01*
G01X184600Y880300D02*
X186600D01*
G01X185600D02*
Y875300D01*
G01X184600D02*
X186600D01*
G01X189533D02*
Y880300D01*
X191533D01*
X192200Y880050D01*
X192700Y879467D01*
X192867Y878800D01*
X192700Y878133D01*
X192283Y877633D01*
X191533Y877383D01*
X189533D01*
G01X198633Y879883D02*
X198133Y880133D01*
X197550Y880300D01*
X196883D01*
X196133Y880050D01*
X195550Y879633D01*
X195133Y879133D01*
X194800Y878300D01*
X194717Y877550D01*
X194883Y876800D01*
X195133Y876300D01*
X195633Y875800D01*
X196217Y875467D01*
X196800Y875300D01*
X197383D01*
X197967Y875467D01*
X198467Y875717D01*
X198883Y876050D01*
G01X201317Y876967D02*
X203483D01*
G01X205917Y875300D02*
X208000Y880300D01*
X210083Y875300D01*
G01X209333Y877050D02*
X206667D01*
G01X212517Y876967D02*
X214683D01*
G01X217617Y877383D02*
X218200Y877967D01*
X218700Y878300D01*
X219367Y878467D01*
X219950Y878300D01*
X220367Y877967D01*
X220700Y877467D01*
X220783Y876883D01*
X220700Y876383D01*
X220367Y875883D01*
X219867Y875467D01*
X219283Y875300D01*
X218617Y875467D01*
X218033Y875967D01*
X217700Y876717D01*
X217617Y877550D01*
X217783Y878633D01*
X218033Y879217D01*
X218450Y879800D01*
X219033Y880217D01*
X219617Y880300D01*
X220200Y880133D01*
X220617Y879717D01*
G01X224800Y880300D02*
X224133Y880133D01*
X223633Y879717D01*
X223300Y879217D01*
X223050Y878550D01*
X222967Y877800D01*
X223050Y877050D01*
X223300Y876383D01*
X223633Y875883D01*
X224133Y875467D01*
X224800Y875300D01*
X225467Y875467D01*
X225967Y875883D01*
X226300Y876383D01*
X226550Y877050D01*
X226633Y877800D01*
X226550Y878550D01*
X226300Y879217D01*
X225967Y879717D01*
X225467Y880133D01*
X224800Y880300D01*
G01X230400D02*
X229733Y880133D01*
X229233Y879717D01*
X228900Y879217D01*
X228650Y878550D01*
X228567Y877800D01*
X228650Y877050D01*
X228900Y876383D01*
X229233Y875883D01*
X229733Y875467D01*
X230400Y875300D01*
X231067Y875467D01*
X231567Y875883D01*
X231900Y876383D01*
X232150Y877050D01*
X232233Y877800D01*
X232150Y878550D01*
X231900Y879217D01*
X231567Y879717D01*
X231067Y880133D01*
X230400Y880300D01*
G01X239517Y875300D02*
X241600Y880300D01*
X243683Y875300D01*
G01X242933Y877050D02*
X240267D01*
G01X248533Y878217D02*
X247950Y878550D01*
X247450Y878633D01*
X246783Y878467D01*
X246283Y878133D01*
X245950Y877550D01*
X245867Y876967D01*
X245950Y876383D01*
X246283Y875883D01*
X246783Y875467D01*
X247450Y875300D01*
X248033Y875467D01*
X248533Y875800D01*
G01X254133Y878217D02*
X253550Y878550D01*
X253050Y878633D01*
X252383Y878467D01*
X251883Y878133D01*
X251550Y877550D01*
X251467Y876967D01*
X251550Y876383D01*
X251883Y875883D01*
X252383Y875467D01*
X253050Y875300D01*
X253633Y875467D01*
X254133Y875800D01*
G01X257150Y877550D02*
X259817D01*
X259567Y878133D01*
X259150Y878467D01*
X258567Y878633D01*
X257983Y878550D01*
X257483Y878300D01*
X257150Y877717D01*
X256983Y877217D01*
Y876717D01*
X257150Y876217D01*
X257567Y875717D01*
X258067Y875383D01*
X258650Y875300D01*
X259233Y875467D01*
X259817Y875967D01*
G01X262500Y873633D02*
Y878633D01*
G01Y877883D02*
X262917Y878300D01*
X263333Y878550D01*
X264000Y878633D01*
X264583Y878550D01*
X265167Y878133D01*
X265417Y877550D01*
X265500Y876967D01*
X265417Y876383D01*
X265167Y875800D01*
X264667Y875467D01*
X264000Y875300D01*
X263417Y875383D01*
X262833Y875633D01*
X262500Y875967D01*
G01X269600Y880300D02*
Y875300D01*
G01X268433Y878633D02*
X270767D01*
G01X276700Y875300D02*
Y878633D01*
G01Y878050D02*
X276367Y878383D01*
X275867Y878550D01*
X275283Y878633D01*
X274700Y878467D01*
X274200Y878133D01*
X273867Y877633D01*
X273700Y876967D01*
X273867Y876300D01*
X274200Y875800D01*
X274700Y875467D01*
X275283Y875300D01*
X275867Y875383D01*
X276367Y875633D01*
X276700Y875967D01*
G01X279300Y875300D02*
Y880300D01*
G01Y877800D02*
X279717Y878300D01*
X280217Y878550D01*
X280717Y878633D01*
X281467Y878467D01*
X281967Y878133D01*
X282300Y877550D01*
Y876883D01*
X282133Y876217D01*
X281800Y875717D01*
X281217Y875383D01*
X280717Y875300D01*
X280217Y875383D01*
X279717Y875633D01*
X279300Y876050D01*
G01X286400Y878633D02*
Y875300D01*
G01Y879967D02*
X286233Y880050D01*
Y880217D01*
X286400Y880300D01*
X286567Y880217D01*
Y880050D01*
X286400Y879967D01*
G01X292000Y875300D02*
Y880300D01*
G01X297600Y878633D02*
Y875300D01*
G01Y879967D02*
X297433Y880050D01*
Y880217D01*
X297600Y880300D01*
X297767Y880217D01*
Y880050D01*
X297600Y879967D01*
G01X303200Y880300D02*
Y875300D01*
G01X302033Y878633D02*
X304367D01*
G01X307050Y873800D02*
X307550Y873633D01*
X308217Y873800D01*
X308633Y874133D01*
X308967Y874550D01*
X309467Y875883D01*
X310550Y878633D01*
G01X307883D02*
X309467Y875883D01*
G01X320000Y875300D02*
X319500Y875383D01*
X319000Y875717D01*
X318667Y876300D01*
X318500Y876967D01*
X318667Y877633D01*
X319000Y878217D01*
X319500Y878550D01*
X320000Y878633D01*
X320500Y878550D01*
X321000Y878217D01*
X321333Y877633D01*
X321417Y876967D01*
X321333Y876300D01*
X321000Y875717D01*
X320500Y875383D01*
X320000Y875300D01*
G01X325100D02*
Y879550D01*
X325267Y879967D01*
X325600Y880217D01*
X326100Y880300D01*
X326600Y880133D01*
X326850Y879717D01*
G01X325850Y878300D02*
X324183D01*
G01X335133Y875300D02*
Y880300D01*
X337133D01*
X337800Y880050D01*
X338300Y879467D01*
X338467Y878800D01*
X338300Y878133D01*
X337883Y877633D01*
X337133Y877383D01*
X335133D01*
G01X341233Y875300D02*
Y878633D01*
G01Y877967D02*
X341650Y878300D01*
X342067Y878550D01*
X342650Y878633D01*
X343067Y878550D01*
X343567Y878300D01*
G01X348000Y878633D02*
Y875300D01*
G01Y879967D02*
X347833Y880050D01*
Y880217D01*
X348000Y880300D01*
X348167Y880217D01*
Y880050D01*
X348000Y879967D01*
G01X352183Y875300D02*
Y878633D01*
G01Y877800D02*
X352517Y878217D01*
X353017Y878550D01*
X353683Y878633D01*
X354267Y878550D01*
X354767Y878217D01*
X355017Y877633D01*
Y875300D01*
G01X359200Y880300D02*
Y875300D01*
G01X358033Y878633D02*
X360367D01*
G01X363550Y877550D02*
X366217D01*
X365967Y878133D01*
X365550Y878467D01*
X364967Y878633D01*
X364383Y878550D01*
X363883Y878300D01*
X363550Y877717D01*
X363383Y877217D01*
Y876717D01*
X363550Y876217D01*
X363967Y875717D01*
X364467Y875383D01*
X365050Y875300D01*
X365633Y875467D01*
X366217Y875967D01*
G01X371900Y880300D02*
Y875300D01*
G01Y876050D02*
X371567Y875633D01*
X371067Y875383D01*
X370483Y875300D01*
X369817Y875467D01*
X369317Y875883D01*
X368983Y876383D01*
X368900Y876967D01*
X368983Y877550D01*
X369317Y878050D01*
X369817Y878467D01*
X370483Y878633D01*
X371067Y878550D01*
X371483Y878383D01*
X371900Y878050D01*
G01X382267Y877967D02*
X382600Y878217D01*
X382850Y878633D01*
X383017Y879217D01*
X382850Y879717D01*
X382517Y880050D01*
X381933Y880300D01*
X379683D01*
Y875300D01*
X382433D01*
X383017Y875633D01*
X383350Y876133D01*
X383517Y876717D01*
X383350Y877300D01*
X382850Y877800D01*
X382267Y877967D01*
X379683D01*
G01X387200Y875300D02*
X386700Y875383D01*
X386200Y875717D01*
X385867Y876300D01*
X385700Y876967D01*
X385867Y877633D01*
X386200Y878217D01*
X386700Y878550D01*
X387200Y878633D01*
X387700Y878550D01*
X388200Y878217D01*
X388533Y877633D01*
X388617Y876967D01*
X388533Y876300D01*
X388200Y875717D01*
X387700Y875383D01*
X387200Y875300D01*
G01X394300D02*
Y878633D01*
G01Y878050D02*
X393967Y878383D01*
X393467Y878550D01*
X392883Y878633D01*
X392300Y878467D01*
X391800Y878133D01*
X391467Y877633D01*
X391300Y876967D01*
X391467Y876300D01*
X391800Y875800D01*
X392300Y875467D01*
X392883Y875300D01*
X393467Y875383D01*
X393967Y875633D01*
X394300Y875967D01*
G01X397233Y875300D02*
Y878633D01*
G01Y877967D02*
X397650Y878300D01*
X398067Y878550D01*
X398650Y878633D01*
X399067Y878550D01*
X399567Y878300D01*
G01X405500Y880300D02*
Y875300D01*
G01Y876050D02*
X405167Y875633D01*
X404667Y875383D01*
X404083Y875300D01*
X403417Y875467D01*
X402917Y875883D01*
X402583Y876383D01*
X402500Y876967D01*
X402583Y877550D01*
X402917Y878050D01*
X403417Y878467D01*
X404083Y878633D01*
X404667Y878550D01*
X405083Y878383D01*
X405500Y878050D01*
G01X408350Y875883D02*
X408767Y875550D01*
X409350Y875300D01*
X409850D01*
X410350Y875467D01*
X410683Y875717D01*
X410850Y876050D01*
X410767Y876550D01*
X410433Y876800D01*
X408933Y877300D01*
X408600Y877883D01*
X408767Y878300D01*
X409100Y878550D01*
X409600Y878633D01*
X410100Y878550D01*
X410600Y878300D01*
G01X171433Y895300D02*
Y900300D01*
X173433D01*
X174100Y900050D01*
X174600Y899467D01*
X174767Y898800D01*
X174600Y898133D01*
X174183Y897633D01*
X173433Y897383D01*
X171433D01*
G01X178700Y895300D02*
Y900300D01*
G01X183050Y897550D02*
X185717D01*
X185467Y898133D01*
X185050Y898467D01*
X184467Y898633D01*
X183883Y898550D01*
X183383Y898300D01*
X183050Y897717D01*
X182883Y897217D01*
Y896717D01*
X183050Y896217D01*
X183467Y895717D01*
X183967Y895383D01*
X184550Y895300D01*
X185133Y895467D01*
X185717Y895967D01*
G01X191400Y895300D02*
Y898633D01*
G01Y898050D02*
X191067Y898383D01*
X190567Y898550D01*
X189983Y898633D01*
X189400Y898467D01*
X188900Y898133D01*
X188567Y897633D01*
X188400Y896967D01*
X188567Y896300D01*
X188900Y895800D01*
X189400Y895467D01*
X189983Y895300D01*
X190567Y895383D01*
X191067Y895633D01*
X191400Y895967D01*
G01X194250Y895883D02*
X194667Y895550D01*
X195250Y895300D01*
X195750D01*
X196250Y895467D01*
X196583Y895717D01*
X196750Y896050D01*
X196667Y896550D01*
X196333Y896800D01*
X194833Y897300D01*
X194500Y897883D01*
X194667Y898300D01*
X195000Y898550D01*
X195500Y898633D01*
X196000Y898550D01*
X196500Y898300D01*
G01X199850Y897550D02*
X202517D01*
X202267Y898133D01*
X201850Y898467D01*
X201267Y898633D01*
X200683Y898550D01*
X200183Y898300D01*
X199850Y897717D01*
X199683Y897217D01*
Y896717D01*
X199850Y896217D01*
X200267Y895717D01*
X200767Y895383D01*
X201350Y895300D01*
X201933Y895467D01*
X202517Y895967D01*
G01X211800Y895300D02*
Y899550D01*
X211967Y899967D01*
X212300Y900217D01*
X212800Y900300D01*
X213300Y900133D01*
X213550Y899717D01*
G01X212550Y898300D02*
X210883D01*
G01X217900Y895300D02*
X217400Y895383D01*
X216900Y895717D01*
X216567Y896300D01*
X216400Y896967D01*
X216567Y897633D01*
X216900Y898217D01*
X217400Y898550D01*
X217900Y898633D01*
X218400Y898550D01*
X218900Y898217D01*
X219233Y897633D01*
X219317Y896967D01*
X219233Y896300D01*
X218900Y895717D01*
X218400Y895383D01*
X217900Y895300D01*
G01X223500D02*
Y900300D01*
G01X229100Y895300D02*
Y900300D01*
G01X234700Y895300D02*
X234200Y895383D01*
X233700Y895717D01*
X233367Y896300D01*
X233200Y896967D01*
X233367Y897633D01*
X233700Y898217D01*
X234200Y898550D01*
X234700Y898633D01*
X235200Y898550D01*
X235700Y898217D01*
X236033Y897633D01*
X236117Y896967D01*
X236033Y896300D01*
X235700Y895717D01*
X235200Y895383D01*
X234700Y895300D01*
G01X238217Y898633D02*
X239217Y895300D01*
X240300Y898633D01*
X241383Y895300D01*
X242383Y898633D01*
G01X251500Y900300D02*
Y895300D01*
G01X250333Y898633D02*
X252667D01*
G01X255683Y895300D02*
Y900300D01*
G01Y897883D02*
X256100Y898300D01*
X256517Y898550D01*
X257183Y898633D01*
X257683Y898550D01*
X258267Y898217D01*
X258517Y897717D01*
Y895300D01*
G01X261450Y897550D02*
X264117D01*
X263867Y898133D01*
X263450Y898467D01*
X262867Y898633D01*
X262283Y898550D01*
X261783Y898300D01*
X261450Y897717D01*
X261283Y897217D01*
Y896717D01*
X261450Y896217D01*
X261867Y895717D01*
X262367Y895383D01*
X262950Y895300D01*
X263533Y895467D01*
X264117Y895967D01*
G01X272650Y895883D02*
X273067Y895550D01*
X273650Y895300D01*
X274150D01*
X274650Y895467D01*
X274983Y895717D01*
X275150Y896050D01*
X275067Y896550D01*
X274733Y896800D01*
X273233Y897300D01*
X272900Y897883D01*
X273067Y898300D01*
X273400Y898550D01*
X273900Y898633D01*
X274400Y898550D01*
X274900Y898300D01*
G01X278000Y893633D02*
Y898633D01*
G01Y897883D02*
X278417Y898300D01*
X278833Y898550D01*
X279500Y898633D01*
X280083Y898550D01*
X280667Y898133D01*
X280917Y897550D01*
X281000Y896967D01*
X280917Y896383D01*
X280667Y895800D01*
X280167Y895467D01*
X279500Y895300D01*
X278917Y895383D01*
X278333Y895633D01*
X278000Y895967D01*
G01X283850Y897550D02*
X286517D01*
X286267Y898133D01*
X285850Y898467D01*
X285267Y898633D01*
X284683Y898550D01*
X284183Y898300D01*
X283850Y897717D01*
X283683Y897217D01*
Y896717D01*
X283850Y896217D01*
X284267Y895717D01*
X284767Y895383D01*
X285350Y895300D01*
X285933Y895467D01*
X286517Y895967D01*
G01X292033Y898217D02*
X291450Y898550D01*
X290950Y898633D01*
X290283Y898467D01*
X289783Y898133D01*
X289450Y897550D01*
X289367Y896967D01*
X289450Y896383D01*
X289783Y895883D01*
X290283Y895467D01*
X290950Y895300D01*
X291533Y895467D01*
X292033Y895800D01*
G01X296300Y898633D02*
Y895300D01*
G01Y899967D02*
X296133Y900050D01*
Y900217D01*
X296300Y900300D01*
X296467Y900217D01*
Y900050D01*
X296300Y899967D01*
G01X301400Y895300D02*
Y899550D01*
X301567Y899967D01*
X301900Y900217D01*
X302400Y900300D01*
X302900Y900133D01*
X303150Y899717D01*
G01X302150Y898300D02*
X300483D01*
G01X307500Y898633D02*
Y895300D01*
G01Y899967D02*
X307333Y900050D01*
Y900217D01*
X307500Y900300D01*
X307667Y900217D01*
Y900050D01*
X307500Y899967D01*
G01X314433Y898217D02*
X313850Y898550D01*
X313350Y898633D01*
X312683Y898467D01*
X312183Y898133D01*
X311850Y897550D01*
X311767Y896967D01*
X311850Y896383D01*
X312183Y895883D01*
X312683Y895467D01*
X313350Y895300D01*
X313933Y895467D01*
X314433Y895800D01*
G01X320200Y895300D02*
Y898633D01*
G01Y898050D02*
X319867Y898383D01*
X319367Y898550D01*
X318783Y898633D01*
X318200Y898467D01*
X317700Y898133D01*
X317367Y897633D01*
X317200Y896967D01*
X317367Y896300D01*
X317700Y895800D01*
X318200Y895467D01*
X318783Y895300D01*
X319367Y895383D01*
X319867Y895633D01*
X320200Y895967D01*
G01X324300Y900300D02*
Y895300D01*
G01X323133Y898633D02*
X325467D01*
G01X329900D02*
Y895300D01*
G01Y899967D02*
X329733Y900050D01*
Y900217D01*
X329900Y900300D01*
X330067Y900217D01*
Y900050D01*
X329900Y899967D01*
G01X335500Y895300D02*
X335000Y895383D01*
X334500Y895717D01*
X334167Y896300D01*
X334000Y896967D01*
X334167Y897633D01*
X334500Y898217D01*
X335000Y898550D01*
X335500Y898633D01*
X336000Y898550D01*
X336500Y898217D01*
X336833Y897633D01*
X336917Y896967D01*
X336833Y896300D01*
X336500Y895717D01*
X336000Y895383D01*
X335500Y895300D01*
G01X339683D02*
Y898633D01*
G01Y897800D02*
X340017Y898217D01*
X340517Y898550D01*
X341183Y898633D01*
X341767Y898550D01*
X342267Y898217D01*
X342517Y897633D01*
Y895300D01*
G01X353800Y900300D02*
Y895300D01*
G01Y896050D02*
X353467Y895633D01*
X352967Y895383D01*
X352383Y895300D01*
X351717Y895467D01*
X351217Y895883D01*
X350883Y896383D01*
X350800Y896967D01*
X350883Y897550D01*
X351217Y898050D01*
X351717Y898467D01*
X352383Y898633D01*
X352967Y898550D01*
X353383Y898383D01*
X353800Y898050D01*
G01X357900Y895300D02*
X357400Y895383D01*
X356900Y895717D01*
X356567Y896300D01*
X356400Y896967D01*
X356567Y897633D01*
X356900Y898217D01*
X357400Y898550D01*
X357900Y898633D01*
X358400Y898550D01*
X358900Y898217D01*
X359233Y897633D01*
X359317Y896967D01*
X359233Y896300D01*
X358900Y895717D01*
X358400Y895383D01*
X357900Y895300D01*
G01X364833Y898217D02*
X364250Y898550D01*
X363750Y898633D01*
X363083Y898467D01*
X362583Y898133D01*
X362250Y897550D01*
X362167Y896967D01*
X362250Y896383D01*
X362583Y895883D01*
X363083Y895467D01*
X363750Y895300D01*
X364333Y895467D01*
X364833Y895800D01*
G01X367683Y898633D02*
Y896300D01*
X368017Y895717D01*
X368517Y895383D01*
X369100Y895300D01*
X369683Y895383D01*
X370183Y895717D01*
X370517Y896300D01*
G01Y895300D02*
Y898633D01*
G01X372200Y895300D02*
Y898633D01*
G01Y897717D02*
X372450Y898133D01*
X372867Y898467D01*
X373450Y898633D01*
X374033Y898467D01*
X374450Y898133D01*
X374700Y897717D01*
Y895300D01*
G01Y897717D02*
X374950Y898133D01*
X375367Y898467D01*
X375950Y898633D01*
X376533Y898467D01*
X376950Y898133D01*
X377200Y897633D01*
Y895300D01*
G01X379050Y897550D02*
X381717D01*
X381467Y898133D01*
X381050Y898467D01*
X380467Y898633D01*
X379883Y898550D01*
X379383Y898300D01*
X379050Y897717D01*
X378883Y897217D01*
Y896717D01*
X379050Y896217D01*
X379467Y895717D01*
X379967Y895383D01*
X380550Y895300D01*
X381133Y895467D01*
X381717Y895967D01*
G01X384483Y895300D02*
Y898633D01*
G01Y897800D02*
X384817Y898217D01*
X385317Y898550D01*
X385983Y898633D01*
X386567Y898550D01*
X387067Y898217D01*
X387317Y897633D01*
Y895300D01*
G01X391500Y900300D02*
Y895300D01*
G01X390333Y898633D02*
X392667D01*
G01X395850Y895883D02*
X396267Y895550D01*
X396850Y895300D01*
X397350D01*
X397850Y895467D01*
X398183Y895717D01*
X398350Y896050D01*
X398267Y896550D01*
X397933Y896800D01*
X396433Y897300D01*
X396100Y897883D01*
X396267Y898300D01*
X396600Y898550D01*
X397100Y898633D01*
X397600Y898550D01*
X398100Y898300D01*
G01X408300Y898633D02*
Y895300D01*
G01Y899967D02*
X408133Y900050D01*
Y900217D01*
X408300Y900300D01*
X408467Y900217D01*
Y900050D01*
X408300Y899967D01*
G01X412483Y895300D02*
Y898633D01*
G01Y897800D02*
X412817Y898217D01*
X413317Y898550D01*
X413983Y898633D01*
X414567Y898550D01*
X415067Y898217D01*
X415317Y897633D01*
Y895300D01*
G01X426433Y898217D02*
X425850Y898550D01*
X425350Y898633D01*
X424683Y898467D01*
X424183Y898133D01*
X423850Y897550D01*
X423767Y896967D01*
X423850Y896383D01*
X424183Y895883D01*
X424683Y895467D01*
X425350Y895300D01*
X425933Y895467D01*
X426433Y895800D01*
G01X430700Y895300D02*
Y900300D01*
G01X437800Y895300D02*
Y898633D01*
G01Y898050D02*
X437467Y898383D01*
X436967Y898550D01*
X436383Y898633D01*
X435800Y898467D01*
X435300Y898133D01*
X434967Y897633D01*
X434800Y896967D01*
X434967Y896300D01*
X435300Y895800D01*
X435800Y895467D01*
X436383Y895300D01*
X436967Y895383D01*
X437467Y895633D01*
X437800Y895967D01*
G01X440650Y895883D02*
X441067Y895550D01*
X441650Y895300D01*
X442150D01*
X442650Y895467D01*
X442983Y895717D01*
X443150Y896050D01*
X443067Y896550D01*
X442733Y896800D01*
X441233Y897300D01*
X440900Y897883D01*
X441067Y898300D01*
X441400Y898550D01*
X441900Y898633D01*
X442400Y898550D01*
X442900Y898300D01*
G01X446250Y895883D02*
X446667Y895550D01*
X447250Y895300D01*
X447750D01*
X448250Y895467D01*
X448583Y895717D01*
X448750Y896050D01*
X448667Y896550D01*
X448333Y896800D01*
X446833Y897300D01*
X446500Y897883D01*
X446667Y898300D01*
X447000Y898550D01*
X447500Y898633D01*
X448000Y898550D01*
X448500Y898300D01*
G01X457117Y899467D02*
X457617Y899967D01*
X458200Y900217D01*
X458867Y900300D01*
X459700Y900133D01*
X460283Y899717D01*
X460450Y899217D01*
X460367Y898717D01*
X460033Y898300D01*
X458367Y897467D01*
X457617Y896883D01*
X457117Y896050D01*
X456950Y895300D01*
X460450D01*
G01X471400D02*
Y898633D01*
G01Y898050D02*
X471067Y898383D01*
X470567Y898550D01*
X469983Y898633D01*
X469400Y898467D01*
X468900Y898133D01*
X468567Y897633D01*
X468400Y896967D01*
X468567Y896300D01*
X468900Y895800D01*
X469400Y895467D01*
X469983Y895300D01*
X470567Y895383D01*
X471067Y895633D01*
X471400Y895967D01*
G01X474083Y895300D02*
Y898633D01*
G01Y897800D02*
X474417Y898217D01*
X474917Y898550D01*
X475583Y898633D01*
X476167Y898550D01*
X476667Y898217D01*
X476917Y897633D01*
Y895300D01*
G01X482600Y900300D02*
Y895300D01*
G01Y896050D02*
X482267Y895633D01*
X481767Y895383D01*
X481183Y895300D01*
X480517Y895467D01*
X480017Y895883D01*
X479683Y896383D01*
X479600Y896967D01*
X479683Y897550D01*
X480017Y898050D01*
X480517Y898467D01*
X481183Y898633D01*
X481767Y898550D01*
X482183Y898383D01*
X482600Y898050D01*
G01X492300Y900300D02*
Y895300D01*
G01X491133Y898633D02*
X493467D01*
G01X496483Y895300D02*
Y900300D01*
G01Y897883D02*
X496900Y898300D01*
X497317Y898550D01*
X497983Y898633D01*
X498483Y898550D01*
X499067Y898217D01*
X499317Y897717D01*
Y895300D01*
G01X502250Y897550D02*
X504917D01*
X504667Y898133D01*
X504250Y898467D01*
X503667Y898633D01*
X503083Y898550D01*
X502583Y898300D01*
X502250Y897717D01*
X502083Y897217D01*
Y896717D01*
X502250Y896217D01*
X502667Y895717D01*
X503167Y895383D01*
X503750Y895300D01*
X504333Y895467D01*
X504917Y895967D01*
G01X514700Y895300D02*
Y900300D01*
G01X521800Y895300D02*
Y898633D01*
G01Y898050D02*
X521467Y898383D01*
X520967Y898550D01*
X520383Y898633D01*
X519800Y898467D01*
X519300Y898133D01*
X518967Y897633D01*
X518800Y896967D01*
X518967Y896300D01*
X519300Y895800D01*
X519800Y895467D01*
X520383Y895300D01*
X520967Y895383D01*
X521467Y895633D01*
X521800Y895967D01*
G01X525900Y900300D02*
Y895300D01*
G01X524733Y898633D02*
X527067D01*
G01X530250Y897550D02*
X532917D01*
X532667Y898133D01*
X532250Y898467D01*
X531667Y898633D01*
X531083Y898550D01*
X530583Y898300D01*
X530250Y897717D01*
X530083Y897217D01*
Y896717D01*
X530250Y896217D01*
X530667Y895717D01*
X531167Y895383D01*
X531750Y895300D01*
X532333Y895467D01*
X532917Y895967D01*
G01X535850Y895883D02*
X536267Y895550D01*
X536850Y895300D01*
X537350D01*
X537850Y895467D01*
X538183Y895717D01*
X538350Y896050D01*
X538267Y896550D01*
X537933Y896800D01*
X536433Y897300D01*
X536100Y897883D01*
X536267Y898300D01*
X536600Y898550D01*
X537100Y898633D01*
X537600Y898550D01*
X538100Y898300D01*
G01X542700Y900300D02*
Y895300D01*
G01X541533Y898633D02*
X543867D01*
G01X552400D02*
X553900Y895300D01*
X555400Y898633D01*
G01X558250Y897550D02*
X560917D01*
X560667Y898133D01*
X560250Y898467D01*
X559667Y898633D01*
X559083Y898550D01*
X558583Y898300D01*
X558250Y897717D01*
X558083Y897217D01*
Y896717D01*
X558250Y896217D01*
X558667Y895717D01*
X559167Y895383D01*
X559750Y895300D01*
X560333Y895467D01*
X560917Y895967D01*
G01X563933Y895300D02*
Y898633D01*
G01Y897967D02*
X564350Y898300D01*
X564767Y898550D01*
X565350Y898633D01*
X565767Y898550D01*
X566267Y898300D01*
G01X569450Y895883D02*
X569867Y895550D01*
X570450Y895300D01*
X570950D01*
X571450Y895467D01*
X571783Y895717D01*
X571950Y896050D01*
X571867Y896550D01*
X571533Y896800D01*
X570033Y897300D01*
X569700Y897883D01*
X569867Y898300D01*
X570200Y898550D01*
X570700Y898633D01*
X571200Y898550D01*
X571700Y898300D01*
G01X576300Y898633D02*
Y895300D01*
G01Y899967D02*
X576133Y900050D01*
Y900217D01*
X576300Y900300D01*
X576467Y900217D01*
Y900050D01*
X576300Y899967D01*
G01X581900Y895300D02*
X581400Y895383D01*
X580900Y895717D01*
X580567Y896300D01*
X580400Y896967D01*
X580567Y897633D01*
X580900Y898217D01*
X581400Y898550D01*
X581900Y898633D01*
X582400Y898550D01*
X582900Y898217D01*
X583233Y897633D01*
X583317Y896967D01*
X583233Y896300D01*
X582900Y895717D01*
X582400Y895383D01*
X581900Y895300D01*
G01X586083D02*
Y898633D01*
G01Y897800D02*
X586417Y898217D01*
X586917Y898550D01*
X587583Y898633D01*
X588167Y898550D01*
X588667Y898217D01*
X588917Y897633D01*
Y895300D01*
G01X598700Y898633D02*
Y895300D01*
G01Y899967D02*
X598533Y900050D01*
Y900217D01*
X598700Y900300D01*
X598867Y900217D01*
Y900050D01*
X598700Y899967D01*
G01X603050Y895883D02*
X603467Y895550D01*
X604050Y895300D01*
X604550D01*
X605050Y895467D01*
X605383Y895717D01*
X605550Y896050D01*
X605467Y896550D01*
X605133Y896800D01*
X603633Y897300D01*
X603300Y897883D01*
X603467Y898300D01*
X603800Y898550D01*
X604300Y898633D01*
X604800Y898550D01*
X605300Y898300D01*
G01X614333Y895300D02*
Y898633D01*
G01Y897967D02*
X614750Y898300D01*
X615167Y898550D01*
X615750Y898633D01*
X616167Y898550D01*
X616667Y898300D01*
G01X619850Y897550D02*
X622517D01*
X622267Y898133D01*
X621850Y898467D01*
X621267Y898633D01*
X620683Y898550D01*
X620183Y898300D01*
X619850Y897717D01*
X619683Y897217D01*
Y896717D01*
X619850Y896217D01*
X620267Y895717D01*
X620767Y895383D01*
X621350Y895300D01*
X621933Y895467D01*
X622517Y895967D01*
G01X628200Y893633D02*
Y898633D01*
G01Y897883D02*
X627783Y898300D01*
X627283Y898550D01*
X626700Y898633D01*
X626200Y898550D01*
X625617Y898133D01*
X625283Y897550D01*
X625200Y896967D01*
X625283Y896383D01*
X625617Y895800D01*
X626200Y895383D01*
X626700Y895300D01*
X627283Y895383D01*
X627783Y895633D01*
X628200Y896050D01*
G01X630883Y898633D02*
Y896300D01*
X631217Y895717D01*
X631717Y895383D01*
X632300Y895300D01*
X632883Y895383D01*
X633383Y895717D01*
X633717Y896300D01*
G01Y895300D02*
Y898633D01*
G01X637900D02*
Y895300D01*
G01Y899967D02*
X637733Y900050D01*
Y900217D01*
X637900Y900300D01*
X638067Y900217D01*
Y900050D01*
X637900Y899967D01*
G01X642333Y895300D02*
Y898633D01*
G01Y897967D02*
X642750Y898300D01*
X643167Y898550D01*
X643750Y898633D01*
X644167Y898550D01*
X644667Y898300D01*
G01X647850Y897550D02*
X650517D01*
X650267Y898133D01*
X649850Y898467D01*
X649267Y898633D01*
X648683Y898550D01*
X648183Y898300D01*
X647850Y897717D01*
X647683Y897217D01*
Y896717D01*
X647850Y896217D01*
X648267Y895717D01*
X648767Y895383D01*
X649350Y895300D01*
X649933Y895467D01*
X650517Y895967D01*
G01X656200Y900300D02*
Y895300D01*
G01Y896050D02*
X655867Y895633D01*
X655367Y895383D01*
X654783Y895300D01*
X654117Y895467D01*
X653617Y895883D01*
X653283Y896383D01*
X653200Y896967D01*
X653283Y897550D01*
X653617Y898050D01*
X654117Y898467D01*
X654783Y898633D01*
X655367Y898550D01*
X655783Y898383D01*
X656200Y898050D01*
G01X660133Y894383D02*
X660467Y895467D01*
G01X225933Y28800D02*
Y23800D01*
X229267D01*
G01X233200D02*
X232700Y23883D01*
X232200Y24217D01*
X231867Y24800D01*
X231700Y25467D01*
X231867Y26133D01*
X232200Y26717D01*
X232700Y27050D01*
X233200Y27133D01*
X233700Y27050D01*
X234200Y26717D01*
X234533Y26133D01*
X234617Y25467D01*
X234533Y24800D01*
X234200Y24217D01*
X233700Y23883D01*
X233200Y23800D01*
G01X237633Y22550D02*
X238217Y22217D01*
X238883Y22133D01*
X239467Y22217D01*
X239967Y22633D01*
X240300Y23217D01*
Y27133D01*
G01Y26467D02*
X239967Y26800D01*
X239467Y27050D01*
X238883Y27133D01*
X238217Y26967D01*
X237800Y26633D01*
X237467Y26050D01*
X237300Y25467D01*
X237383Y24967D01*
X237717Y24383D01*
X238217Y23967D01*
X238883Y23800D01*
X239383Y23883D01*
X239967Y24217D01*
X240300Y24550D01*
G01X244400Y23800D02*
X243900Y23883D01*
X243400Y24217D01*
X243067Y24800D01*
X242900Y25467D01*
X243067Y26133D01*
X243400Y26717D01*
X243900Y27050D01*
X244400Y27133D01*
X244900Y27050D01*
X245400Y26717D01*
X245733Y26133D01*
X245817Y25467D01*
X245733Y24800D01*
X245400Y24217D01*
X244900Y23883D01*
X244400Y23800D01*
G01X227600Y52800D02*
Y47800D01*
G01X226433Y51133D02*
X228767D01*
G01X231783Y47800D02*
Y52800D01*
G01Y50383D02*
X232200Y50800D01*
X232617Y51050D01*
X233283Y51133D01*
X233783Y51050D01*
X234367Y50717D01*
X234617Y50217D01*
Y47800D01*
G01X238800Y51133D02*
Y47800D01*
G01Y52467D02*
X238633Y52550D01*
Y52717D01*
X238800Y52800D01*
X238967Y52717D01*
Y52550D01*
X238800Y52467D01*
G01X245733Y50717D02*
X245150Y51050D01*
X244650Y51133D01*
X243983Y50967D01*
X243483Y50633D01*
X243150Y50050D01*
X243067Y49467D01*
X243150Y48883D01*
X243483Y48383D01*
X243983Y47967D01*
X244650Y47800D01*
X245233Y47967D01*
X245733Y48300D01*
G01X248583Y47800D02*
Y52800D01*
G01X251250Y51133D02*
X248583Y49217D01*
G01X249667Y49967D02*
X251417Y47800D01*
G01X254183D02*
Y51133D01*
G01Y50300D02*
X254517Y50717D01*
X255017Y51050D01*
X255683Y51133D01*
X256267Y51050D01*
X256767Y50717D01*
X257017Y50133D01*
Y47800D01*
G01X259950Y50050D02*
X262617D01*
X262367Y50633D01*
X261950Y50967D01*
X261367Y51133D01*
X260783Y51050D01*
X260283Y50800D01*
X259950Y50217D01*
X259783Y49717D01*
Y49217D01*
X259950Y48717D01*
X260367Y48217D01*
X260867Y47883D01*
X261450Y47800D01*
X262033Y47967D01*
X262617Y48467D01*
G01X265550Y48383D02*
X265967Y48050D01*
X266550Y47800D01*
X267050D01*
X267550Y47967D01*
X267883Y48217D01*
X268050Y48550D01*
X267967Y49050D01*
X267633Y49300D01*
X266133Y49800D01*
X265800Y50383D01*
X265967Y50800D01*
X266300Y51050D01*
X266800Y51133D01*
X267300Y51050D01*
X267800Y50800D01*
G01X271150Y48383D02*
X271567Y48050D01*
X272150Y47800D01*
X272650D01*
X273150Y47967D01*
X273483Y48217D01*
X273650Y48550D01*
X273567Y49050D01*
X273233Y49300D01*
X271733Y49800D01*
X271400Y50383D01*
X271567Y50800D01*
X271900Y51050D01*
X272400Y51133D01*
X272900Y51050D01*
X273400Y50800D01*
G01X227600Y73800D02*
Y68800D01*
G01X226433Y72133D02*
X228767D01*
G01X231783Y68800D02*
Y73800D01*
G01Y71383D02*
X232200Y71800D01*
X232617Y72050D01*
X233283Y72133D01*
X233783Y72050D01*
X234367Y71717D01*
X234617Y71217D01*
Y68800D01*
G01X238800Y72133D02*
Y68800D01*
G01Y73467D02*
X238633Y73550D01*
Y73717D01*
X238800Y73800D01*
X238967Y73717D01*
Y73550D01*
X238800Y73467D01*
G01X245733Y71717D02*
X245150Y72050D01*
X244650Y72133D01*
X243983Y71967D01*
X243483Y71633D01*
X243150Y71050D01*
X243067Y70467D01*
X243150Y69883D01*
X243483Y69383D01*
X243983Y68967D01*
X244650Y68800D01*
X245233Y68967D01*
X245733Y69300D01*
G01X248583Y68800D02*
Y73800D01*
G01X251250Y72133D02*
X248583Y70217D01*
G01X249667Y70967D02*
X251417Y68800D01*
G01X254183D02*
Y72133D01*
G01Y71300D02*
X254517Y71717D01*
X255017Y72050D01*
X255683Y72133D01*
X256267Y72050D01*
X256767Y71717D01*
X257017Y71133D01*
Y68800D01*
G01X259950Y71050D02*
X262617D01*
X262367Y71633D01*
X261950Y71967D01*
X261367Y72133D01*
X260783Y72050D01*
X260283Y71800D01*
X259950Y71217D01*
X259783Y70717D01*
Y70217D01*
X259950Y69717D01*
X260367Y69217D01*
X260867Y68883D01*
X261450Y68800D01*
X262033Y68967D01*
X262617Y69467D01*
G01X265550Y69383D02*
X265967Y69050D01*
X266550Y68800D01*
X267050D01*
X267550Y68967D01*
X267883Y69217D01*
X268050Y69550D01*
X267967Y70050D01*
X267633Y70300D01*
X266133Y70800D01*
X265800Y71383D01*
X265967Y71800D01*
X266300Y72050D01*
X266800Y72133D01*
X267300Y72050D01*
X267800Y71800D01*
G01X271150Y69383D02*
X271567Y69050D01*
X272150Y68800D01*
X272650D01*
X273150Y68967D01*
X273483Y69217D01*
X273650Y69550D01*
X273567Y70050D01*
X273233Y70300D01*
X271733Y70800D01*
X271400Y71383D01*
X271567Y71800D01*
X271900Y72050D01*
X272400Y72133D01*
X272900Y72050D01*
X273400Y71800D01*
G01X226083Y113500D02*
Y118500D01*
X228250Y114333D01*
X230417Y118500D01*
Y113500D01*
G01X235350D02*
Y116833D01*
G01Y116250D02*
X235017Y116583D01*
X234517Y116750D01*
X233933Y116833D01*
X233350Y116667D01*
X232850Y116333D01*
X232517Y115833D01*
X232350Y115167D01*
X232517Y114500D01*
X232850Y114000D01*
X233350Y113667D01*
X233933Y113500D01*
X234517Y113583D01*
X235017Y113833D01*
X235350Y114167D01*
G01X238283Y113500D02*
Y116833D01*
G01Y116167D02*
X238700Y116500D01*
X239117Y116750D01*
X239700Y116833D01*
X240117Y116750D01*
X240617Y116500D01*
G01X243633Y113500D02*
Y118500D01*
G01X246300Y116833D02*
X243633Y114917D01*
G01X244717Y115667D02*
X246467Y113500D01*
G01X251067Y111833D02*
X251900Y112667D01*
X252317Y113500D01*
Y116833D01*
X251900Y117667D01*
X251067Y118500D01*
G01X232783Y86633D02*
X231950Y87467D01*
X231533Y88300D01*
Y91633D01*
X231950Y92467D01*
X232783Y93300D01*
G01X237050Y88967D02*
X237717Y88550D01*
X238467Y88300D01*
X239133D01*
X239800Y88550D01*
X240300Y88967D01*
X240550Y89550D01*
X240383Y90133D01*
X239967Y90633D01*
X239217Y90967D01*
X238217Y91133D01*
X237633Y91467D01*
X237383Y92050D01*
X237550Y92633D01*
X237967Y93050D01*
X238550Y93300D01*
X239133D01*
X239717Y93133D01*
X240217Y92717D01*
G01X242233Y88300D02*
Y93300D01*
X244400Y89133D01*
X246567Y93300D01*
Y88300D01*
G01X248167D02*
Y93300D01*
X249833D01*
X250500Y93050D01*
X251000Y92717D01*
X251417Y92217D01*
X251750Y91633D01*
X251833Y90800D01*
X251750Y89967D01*
X251417Y89383D01*
X251000Y88883D01*
X250500Y88550D01*
X249833Y88300D01*
X248167D01*
G01X256017Y86633D02*
X256850Y87467D01*
X257267Y88300D01*
Y91633D01*
X256850Y92467D01*
X256017Y93300D01*
G01X225850Y100967D02*
X226517Y100550D01*
X227267Y100300D01*
X227933D01*
X228600Y100550D01*
X229100Y100967D01*
X229350Y101550D01*
X229183Y102133D01*
X228767Y102633D01*
X228017Y102967D01*
X227017Y103133D01*
X226433Y103467D01*
X226183Y104050D01*
X226350Y104633D01*
X226767Y105050D01*
X227350Y105300D01*
X227933D01*
X228517Y105133D01*
X229017Y104717D01*
G01X233200Y100300D02*
X232700Y100383D01*
X232200Y100717D01*
X231867Y101300D01*
X231700Y101967D01*
X231867Y102633D01*
X232200Y103217D01*
X232700Y103550D01*
X233200Y103633D01*
X233700Y103550D01*
X234200Y103217D01*
X234533Y102633D01*
X234617Y101967D01*
X234533Y101300D01*
X234200Y100717D01*
X233700Y100383D01*
X233200Y100300D01*
G01X238800D02*
Y105300D01*
G01X245900D02*
Y100300D01*
G01Y101050D02*
X245567Y100633D01*
X245067Y100383D01*
X244483Y100300D01*
X243817Y100467D01*
X243317Y100883D01*
X242983Y101383D01*
X242900Y101967D01*
X242983Y102550D01*
X243317Y103050D01*
X243817Y103467D01*
X244483Y103633D01*
X245067Y103550D01*
X245483Y103383D01*
X245900Y103050D01*
G01X248750Y102550D02*
X251417D01*
X251167Y103133D01*
X250750Y103467D01*
X250167Y103633D01*
X249583Y103550D01*
X249083Y103300D01*
X248750Y102717D01*
X248583Y102217D01*
Y101717D01*
X248750Y101217D01*
X249167Y100717D01*
X249667Y100383D01*
X250250Y100300D01*
X250833Y100467D01*
X251417Y100967D01*
G01X254433Y100300D02*
Y103633D01*
G01Y102967D02*
X254850Y103300D01*
X255267Y103550D01*
X255850Y103633D01*
X256267Y103550D01*
X256767Y103300D01*
G01X264300Y100300D02*
Y103633D01*
G01Y102717D02*
X264550Y103133D01*
X264967Y103467D01*
X265550Y103633D01*
X266133Y103467D01*
X266550Y103133D01*
X266800Y102717D01*
Y100300D01*
G01Y102717D02*
X267050Y103133D01*
X267467Y103467D01*
X268050Y103633D01*
X268633Y103467D01*
X269050Y103133D01*
X269300Y102633D01*
Y100300D01*
G01X273900D02*
Y103633D01*
G01Y103050D02*
X273567Y103383D01*
X273067Y103550D01*
X272483Y103633D01*
X271900Y103467D01*
X271400Y103133D01*
X271067Y102633D01*
X270900Y101967D01*
X271067Y101300D01*
X271400Y100800D01*
X271900Y100467D01*
X272483Y100300D01*
X273067Y100383D01*
X273567Y100633D01*
X273900Y100967D01*
G01X276750Y100883D02*
X277167Y100550D01*
X277750Y100300D01*
X278250D01*
X278750Y100467D01*
X279083Y100717D01*
X279250Y101050D01*
X279167Y101550D01*
X278833Y101800D01*
X277333Y102300D01*
X277000Y102883D01*
X277167Y103300D01*
X277500Y103550D01*
X278000Y103633D01*
X278500Y103550D01*
X279000Y103300D01*
G01X282183Y100300D02*
Y105300D01*
G01X284850Y103633D02*
X282183Y101717D01*
G01X283267Y102467D02*
X285017Y100300D01*
G01X296300Y105300D02*
Y100300D01*
G01Y101050D02*
X295967Y100633D01*
X295467Y100383D01*
X294883Y100300D01*
X294217Y100467D01*
X293717Y100883D01*
X293383Y101383D01*
X293300Y101967D01*
X293383Y102550D01*
X293717Y103050D01*
X294217Y103467D01*
X294883Y103633D01*
X295467Y103550D01*
X295883Y103383D01*
X296300Y103050D01*
G01X299150Y102550D02*
X301817D01*
X301567Y103133D01*
X301150Y103467D01*
X300567Y103633D01*
X299983Y103550D01*
X299483Y103300D01*
X299150Y102717D01*
X298983Y102217D01*
Y101717D01*
X299150Y101217D01*
X299567Y100717D01*
X300067Y100383D01*
X300650Y100300D01*
X301233Y100467D01*
X301817Y100967D01*
G01X305500Y100300D02*
Y104550D01*
X305667Y104967D01*
X306000Y105217D01*
X306500Y105300D01*
X307000Y105133D01*
X307250Y104717D01*
G01X306250Y103300D02*
X304583D01*
G01X311600Y103633D02*
Y100300D01*
G01Y104967D02*
X311433Y105050D01*
Y105217D01*
X311600Y105300D01*
X311767Y105217D01*
Y105050D01*
X311600Y104967D01*
G01X315783Y100300D02*
Y103633D01*
G01Y102800D02*
X316117Y103217D01*
X316617Y103550D01*
X317283Y103633D01*
X317867Y103550D01*
X318367Y103217D01*
X318617Y102633D01*
Y100300D01*
G01X321550Y102550D02*
X324217D01*
X323967Y103133D01*
X323550Y103467D01*
X322967Y103633D01*
X322383Y103550D01*
X321883Y103300D01*
X321550Y102717D01*
X321383Y102217D01*
Y101717D01*
X321550Y101217D01*
X321967Y100717D01*
X322467Y100383D01*
X323050Y100300D01*
X323633Y100467D01*
X324217Y100967D01*
G01X332500Y98633D02*
Y103633D01*
G01Y102883D02*
X332917Y103300D01*
X333333Y103550D01*
X334000Y103633D01*
X334583Y103550D01*
X335167Y103133D01*
X335417Y102550D01*
X335500Y101967D01*
X335417Y101383D01*
X335167Y100800D01*
X334667Y100467D01*
X334000Y100300D01*
X333417Y100383D01*
X332833Y100633D01*
X332500Y100967D01*
G01X341100Y100300D02*
Y103633D01*
G01Y103050D02*
X340767Y103383D01*
X340267Y103550D01*
X339683Y103633D01*
X339100Y103467D01*
X338600Y103133D01*
X338267Y102633D01*
X338100Y101967D01*
X338267Y101300D01*
X338600Y100800D01*
X339100Y100467D01*
X339683Y100300D01*
X340267Y100383D01*
X340767Y100633D01*
X341100Y100967D01*
G01X346700Y105300D02*
Y100300D01*
G01Y101050D02*
X346367Y100633D01*
X345867Y100383D01*
X345283Y100300D01*
X344617Y100467D01*
X344117Y100883D01*
X343783Y101383D01*
X343700Y101967D01*
X343783Y102550D01*
X344117Y103050D01*
X344617Y103467D01*
X345283Y103633D01*
X345867Y103550D01*
X346283Y103383D01*
X346700Y103050D01*
G01X226670Y124930D02*
X228337D01*
Y123430D01*
X227837Y122930D01*
X227253Y122597D01*
X226420Y122430D01*
X225587Y122597D01*
X225003Y122930D01*
X224503Y123430D01*
X224170Y124013D01*
X224003Y124680D01*
Y125263D01*
X224170Y125763D01*
X224503Y126347D01*
X225003Y126847D01*
X225503Y127180D01*
X226170Y127430D01*
X226753D01*
X227420Y127263D01*
X227920Y126930D01*
G01X231770Y122430D02*
X231270Y122513D01*
X230770Y122847D01*
X230437Y123430D01*
X230270Y124097D01*
X230437Y124763D01*
X230770Y125347D01*
X231270Y125680D01*
X231770Y125763D01*
X232270Y125680D01*
X232770Y125347D01*
X233103Y124763D01*
X233187Y124097D01*
X233103Y123430D01*
X232770Y122847D01*
X232270Y122513D01*
X231770Y122430D01*
G01X237370D02*
Y127430D01*
G01X244470D02*
Y122430D01*
G01Y123180D02*
X244137Y122763D01*
X243637Y122513D01*
X243053Y122430D01*
X242387Y122597D01*
X241887Y123013D01*
X241553Y123513D01*
X241470Y124097D01*
X241553Y124680D01*
X241887Y125180D01*
X242387Y125597D01*
X243053Y125763D01*
X243637Y125680D01*
X244053Y125513D01*
X244470Y125180D01*
G01X247320Y124680D02*
X249987D01*
X249737Y125263D01*
X249320Y125597D01*
X248737Y125763D01*
X248153Y125680D01*
X247653Y125430D01*
X247320Y124847D01*
X247153Y124347D01*
Y123847D01*
X247320Y123347D01*
X247737Y122847D01*
X248237Y122513D01*
X248820Y122430D01*
X249403Y122597D01*
X249987Y123097D01*
G01X252753Y122430D02*
Y125763D01*
G01Y124930D02*
X253087Y125347D01*
X253587Y125680D01*
X254253Y125763D01*
X254837Y125680D01*
X255337Y125347D01*
X255587Y124763D01*
Y122430D01*
G01X264870D02*
Y126680D01*
X265037Y127097D01*
X265370Y127347D01*
X265870Y127430D01*
X266370Y127263D01*
X266620Y126847D01*
G01X265620Y125430D02*
X263953D01*
G01X270970Y125763D02*
Y122430D01*
G01Y127097D02*
X270803Y127180D01*
Y127347D01*
X270970Y127430D01*
X271137Y127347D01*
Y127180D01*
X270970Y127097D01*
G01X275153Y122430D02*
Y125763D01*
G01Y124930D02*
X275487Y125347D01*
X275987Y125680D01*
X276653Y125763D01*
X277237Y125680D01*
X277737Y125347D01*
X277987Y124763D01*
Y122430D01*
G01X281003Y121180D02*
X281587Y120847D01*
X282253Y120763D01*
X282837Y120847D01*
X283337Y121263D01*
X283670Y121847D01*
Y125763D01*
G01Y125097D02*
X283337Y125430D01*
X282837Y125680D01*
X282253Y125763D01*
X281587Y125597D01*
X281170Y125263D01*
X280837Y124680D01*
X280670Y124097D01*
X280753Y123597D01*
X281087Y123013D01*
X281587Y122597D01*
X282253Y122430D01*
X282753Y122513D01*
X283337Y122847D01*
X283670Y123180D01*
G01X286520Y124680D02*
X289187D01*
X288937Y125263D01*
X288520Y125597D01*
X287937Y125763D01*
X287353Y125680D01*
X286853Y125430D01*
X286520Y124847D01*
X286353Y124347D01*
Y123847D01*
X286520Y123347D01*
X286937Y122847D01*
X287437Y122513D01*
X288020Y122430D01*
X288603Y122597D01*
X289187Y123097D01*
G01X292203Y122430D02*
Y125763D01*
G01Y125097D02*
X292620Y125430D01*
X293037Y125680D01*
X293620Y125763D01*
X294037Y125680D01*
X294537Y125430D01*
G01X302903Y122430D02*
Y127430D01*
X304903D01*
X305570Y127180D01*
X306070Y126597D01*
X306237Y125930D01*
X306070Y125263D01*
X305653Y124763D01*
X304903Y124513D01*
X302903D01*
G01X308087Y122430D02*
X310170Y127430D01*
X312253Y122430D01*
G01X311503Y124180D02*
X308837D01*
G01X313937Y122430D02*
Y127430D01*
X315603D01*
X316270Y127180D01*
X316770Y126847D01*
X317187Y126347D01*
X317520Y125763D01*
X317603Y124930D01*
X317520Y124097D01*
X317187Y123513D01*
X316770Y123013D01*
X316270Y122680D01*
X315603Y122430D01*
X313937D01*
G01X325470Y122263D02*
X328470Y127430D01*
G01X330987Y122430D02*
Y127430D01*
X334153D01*
G01X332987Y125013D02*
X330987D01*
G01X338170Y125763D02*
Y122430D01*
G01Y127097D02*
X338003Y127180D01*
Y127347D01*
X338170Y127430D01*
X338337Y127347D01*
Y127180D01*
X338170Y127097D01*
G01X345270Y127430D02*
Y122430D01*
G01Y123180D02*
X344937Y122763D01*
X344437Y122513D01*
X343853Y122430D01*
X343187Y122597D01*
X342687Y123013D01*
X342353Y123513D01*
X342270Y124097D01*
X342353Y124680D01*
X342687Y125180D01*
X343187Y125597D01*
X343853Y125763D01*
X344437Y125680D01*
X344853Y125513D01*
X345270Y125180D01*
G01X347953Y125763D02*
Y123430D01*
X348287Y122847D01*
X348787Y122513D01*
X349370Y122430D01*
X349953Y122513D01*
X350453Y122847D01*
X350787Y123430D01*
G01Y122430D02*
Y125763D01*
G01X356303Y125347D02*
X355720Y125680D01*
X355220Y125763D01*
X354553Y125597D01*
X354053Y125263D01*
X353720Y124680D01*
X353637Y124097D01*
X353720Y123513D01*
X354053Y123013D01*
X354553Y122597D01*
X355220Y122430D01*
X355803Y122597D01*
X356303Y122930D01*
G01X360570Y125763D02*
Y122430D01*
G01Y127097D02*
X360403Y127180D01*
Y127347D01*
X360570Y127430D01*
X360737Y127347D01*
Y127180D01*
X360570Y127097D01*
G01X367670Y122430D02*
Y125763D01*
G01Y125180D02*
X367337Y125513D01*
X366837Y125680D01*
X366253Y125763D01*
X365670Y125597D01*
X365170Y125263D01*
X364837Y124763D01*
X364670Y124097D01*
X364837Y123430D01*
X365170Y122930D01*
X365670Y122597D01*
X366253Y122430D01*
X366837Y122513D01*
X367337Y122763D01*
X367670Y123097D01*
G01X371770Y122430D02*
Y127430D01*
G01X226343Y131473D02*
X225510Y132307D01*
X225093Y133140D01*
Y136473D01*
X225510Y137307D01*
X226343Y138140D01*
G01X229860Y133140D02*
Y136473D01*
G01Y135557D02*
X230110Y135973D01*
X230527Y136307D01*
X231110Y136473D01*
X231693Y136307D01*
X232110Y135973D01*
X232360Y135557D01*
Y133140D01*
G01Y135557D02*
X232610Y135973D01*
X233027Y136307D01*
X233610Y136473D01*
X234193Y136307D01*
X234610Y135973D01*
X234860Y135473D01*
Y133140D01*
G01X236710Y135390D02*
X239377D01*
X239127Y135973D01*
X238710Y136307D01*
X238127Y136473D01*
X237543Y136390D01*
X237043Y136140D01*
X236710Y135557D01*
X236543Y135057D01*
Y134557D01*
X236710Y134057D01*
X237127Y133557D01*
X237627Y133223D01*
X238210Y133140D01*
X238793Y133307D01*
X239377Y133807D01*
G01X245060Y133140D02*
Y136473D01*
G01Y135890D02*
X244727Y136223D01*
X244227Y136390D01*
X243643Y136473D01*
X243060Y136307D01*
X242560Y135973D01*
X242227Y135473D01*
X242060Y134807D01*
X242227Y134140D01*
X242560Y133640D01*
X243060Y133307D01*
X243643Y133140D01*
X244227Y133223D01*
X244727Y133473D01*
X245060Y133807D01*
G01X247910Y133723D02*
X248327Y133390D01*
X248910Y133140D01*
X249410D01*
X249910Y133307D01*
X250243Y133557D01*
X250410Y133890D01*
X250327Y134390D01*
X249993Y134640D01*
X248493Y135140D01*
X248160Y135723D01*
X248327Y136140D01*
X248660Y136390D01*
X249160Y136473D01*
X249660Y136390D01*
X250160Y136140D01*
G01X253343Y136473D02*
Y134140D01*
X253677Y133557D01*
X254177Y133223D01*
X254760Y133140D01*
X255343Y133223D01*
X255843Y133557D01*
X256177Y134140D01*
G01Y133140D02*
Y136473D01*
G01X259193Y133140D02*
Y136473D01*
G01Y135807D02*
X259610Y136140D01*
X260027Y136390D01*
X260610Y136473D01*
X261027Y136390D01*
X261527Y136140D01*
G01X264710Y135390D02*
X267377D01*
X267127Y135973D01*
X266710Y136307D01*
X266127Y136473D01*
X265543Y136390D01*
X265043Y136140D01*
X264710Y135557D01*
X264543Y135057D01*
Y134557D01*
X264710Y134057D01*
X265127Y133557D01*
X265627Y133223D01*
X266210Y133140D01*
X266793Y133307D01*
X267377Y133807D01*
G01X277160Y138140D02*
Y133140D01*
G01X275993Y136473D02*
X278327D01*
G01X282760Y133140D02*
X282260Y133223D01*
X281760Y133557D01*
X281427Y134140D01*
X281260Y134807D01*
X281427Y135473D01*
X281760Y136057D01*
X282260Y136390D01*
X282760Y136473D01*
X283260Y136390D01*
X283760Y136057D01*
X284093Y135473D01*
X284177Y134807D01*
X284093Y134140D01*
X283760Y133557D01*
X283260Y133223D01*
X282760Y133140D01*
G01X286860Y131473D02*
Y136473D01*
G01Y135723D02*
X287277Y136140D01*
X287693Y136390D01*
X288360Y136473D01*
X288943Y136390D01*
X289527Y135973D01*
X289777Y135390D01*
X289860Y134807D01*
X289777Y134223D01*
X289527Y133640D01*
X289027Y133307D01*
X288360Y133140D01*
X287777Y133223D01*
X287193Y133473D01*
X286860Y133807D01*
G01X298310Y133723D02*
X298727Y133390D01*
X299310Y133140D01*
X299810D01*
X300310Y133307D01*
X300643Y133557D01*
X300810Y133890D01*
X300727Y134390D01*
X300393Y134640D01*
X298893Y135140D01*
X298560Y135723D01*
X298727Y136140D01*
X299060Y136390D01*
X299560Y136473D01*
X300060Y136390D01*
X300560Y136140D01*
G01X305160Y136473D02*
Y133140D01*
G01Y137807D02*
X304993Y137890D01*
Y138057D01*
X305160Y138140D01*
X305327Y138057D01*
Y137890D01*
X305160Y137807D01*
G01X309510Y136473D02*
X312010D01*
X309510Y133140D01*
X312010D01*
G01X315110Y135390D02*
X317777D01*
X317527Y135973D01*
X317110Y136307D01*
X316527Y136473D01*
X315943Y136390D01*
X315443Y136140D01*
X315110Y135557D01*
X314943Y135057D01*
Y134557D01*
X315110Y134057D01*
X315527Y133557D01*
X316027Y133223D01*
X316610Y133140D01*
X317193Y133307D01*
X317777Y133807D01*
G01X327560Y133140D02*
X327060Y133223D01*
X326560Y133557D01*
X326227Y134140D01*
X326060Y134807D01*
X326227Y135473D01*
X326560Y136057D01*
X327060Y136390D01*
X327560Y136473D01*
X328060Y136390D01*
X328560Y136057D01*
X328893Y135473D01*
X328977Y134807D01*
X328893Y134140D01*
X328560Y133557D01*
X328060Y133223D01*
X327560Y133140D01*
G01X332660D02*
Y137390D01*
X332827Y137807D01*
X333160Y138057D01*
X333660Y138140D01*
X334160Y137973D01*
X334410Y137557D01*
G01X333410Y136140D02*
X331743D01*
G01X342693Y133140D02*
Y138140D01*
X344693D01*
X345360Y137890D01*
X345860Y137307D01*
X346027Y136640D01*
X345860Y135973D01*
X345443Y135473D01*
X344693Y135223D01*
X342693D01*
G01X347877Y133140D02*
X349960Y138140D01*
X352043Y133140D01*
G01X351293Y134890D02*
X348627D01*
G01X353727Y133140D02*
Y138140D01*
X355393D01*
X356060Y137890D01*
X356560Y137557D01*
X356977Y137057D01*
X357310Y136473D01*
X357393Y135640D01*
X357310Y134807D01*
X356977Y134223D01*
X356560Y133723D01*
X356060Y133390D01*
X355393Y133140D01*
X353727D01*
G01X365260Y132973D02*
X368260Y138140D01*
G01X225933Y140300D02*
Y145300D01*
X227933D01*
X228600Y145050D01*
X229100Y144467D01*
X229267Y143800D01*
X229100Y143133D01*
X228683Y142633D01*
X227933Y142383D01*
X225933D01*
G01X231117Y140300D02*
X233200Y145300D01*
X235283Y140300D01*
G01X234533Y142050D02*
X231867D01*
G01X236967Y140300D02*
Y145300D01*
X238633D01*
X239300Y145050D01*
X239800Y144717D01*
X240217Y144217D01*
X240550Y143633D01*
X240633Y142800D01*
X240550Y141967D01*
X240217Y141383D01*
X239800Y140883D01*
X239300Y140550D01*
X238633Y140300D01*
X236967D01*
G01X248750Y140883D02*
X249167Y140550D01*
X249750Y140300D01*
X250250D01*
X250750Y140467D01*
X251083Y140717D01*
X251250Y141050D01*
X251167Y141550D01*
X250833Y141800D01*
X249333Y142300D01*
X249000Y142883D01*
X249167Y143300D01*
X249500Y143550D01*
X250000Y143633D01*
X250500Y143550D01*
X251000Y143300D01*
G01X255600Y143633D02*
Y140300D01*
G01Y144967D02*
X255433Y145050D01*
Y145217D01*
X255600Y145300D01*
X255767Y145217D01*
Y145050D01*
X255600Y144967D01*
G01X259950Y143633D02*
X262450D01*
X259950Y140300D01*
X262450D01*
G01X265550Y142550D02*
X268217D01*
X267967Y143133D01*
X267550Y143467D01*
X266967Y143633D01*
X266383Y143550D01*
X265883Y143300D01*
X265550Y142717D01*
X265383Y142217D01*
Y141717D01*
X265550Y141217D01*
X265967Y140717D01*
X266467Y140383D01*
X267050Y140300D01*
X267633Y140467D01*
X268217Y140967D01*
G01X227600Y173800D02*
Y168800D01*
G01X225683Y173800D02*
X229517D01*
G01X232033Y168800D02*
Y172133D01*
G01Y171467D02*
X232450Y171800D01*
X232867Y172050D01*
X233450Y172133D01*
X233867Y172050D01*
X234367Y171800D01*
G01X240300Y168800D02*
Y172133D01*
G01Y171550D02*
X239967Y171883D01*
X239467Y172050D01*
X238883Y172133D01*
X238300Y171967D01*
X237800Y171633D01*
X237467Y171133D01*
X237300Y170467D01*
X237467Y169800D01*
X237800Y169300D01*
X238300Y168967D01*
X238883Y168800D01*
X239467Y168883D01*
X239967Y169133D01*
X240300Y169467D01*
G01X245733Y171717D02*
X245150Y172050D01*
X244650Y172133D01*
X243983Y171967D01*
X243483Y171633D01*
X243150Y171050D01*
X243067Y170467D01*
X243150Y169883D01*
X243483Y169383D01*
X243983Y168967D01*
X244650Y168800D01*
X245233Y168967D01*
X245733Y169300D01*
G01X248750Y171050D02*
X251417D01*
X251167Y171633D01*
X250750Y171967D01*
X250167Y172133D01*
X249583Y172050D01*
X249083Y171800D01*
X248750Y171217D01*
X248583Y170717D01*
Y170217D01*
X248750Y169717D01*
X249167Y169217D01*
X249667Y168883D01*
X250250Y168800D01*
X250833Y168967D01*
X251417Y169467D01*
G01X259117Y172133D02*
X260117Y168800D01*
X261200Y172133D01*
X262283Y168800D01*
X263283Y172133D01*
G01X266800D02*
Y168800D01*
G01Y173467D02*
X266633Y173550D01*
Y173717D01*
X266800Y173800D01*
X266967Y173717D01*
Y173550D01*
X266800Y173467D01*
G01X273900Y173800D02*
Y168800D01*
G01Y169550D02*
X273567Y169133D01*
X273067Y168883D01*
X272483Y168800D01*
X271817Y168967D01*
X271317Y169383D01*
X270983Y169883D01*
X270900Y170467D01*
X270983Y171050D01*
X271317Y171550D01*
X271817Y171967D01*
X272483Y172133D01*
X273067Y172050D01*
X273483Y171883D01*
X273900Y171550D01*
G01X278000Y173800D02*
Y168800D01*
G01X276833Y172133D02*
X279167D01*
G01X282183Y168800D02*
Y173800D01*
G01Y171383D02*
X282600Y171800D01*
X283017Y172050D01*
X283683Y172133D01*
X284183Y172050D01*
X284767Y171717D01*
X285017Y171217D01*
Y168800D01*
G01X225933Y200300D02*
Y205300D01*
X228017D01*
X228683Y205050D01*
X229100Y204717D01*
X229267Y204050D01*
X229100Y203383D01*
X228600Y202967D01*
X228017Y202717D01*
X225933D01*
G01X228017D02*
X229267Y200300D01*
G01X231950Y202550D02*
X234617D01*
X234367Y203133D01*
X233950Y203467D01*
X233367Y203633D01*
X232783Y203550D01*
X232283Y203300D01*
X231950Y202717D01*
X231783Y202217D01*
Y201717D01*
X231950Y201217D01*
X232367Y200717D01*
X232867Y200383D01*
X233450Y200300D01*
X234033Y200467D01*
X234617Y200967D01*
G01X238800Y200300D02*
Y205300D01*
G01X245900Y200300D02*
Y203633D01*
G01Y203050D02*
X245567Y203383D01*
X245067Y203550D01*
X244483Y203633D01*
X243900Y203467D01*
X243400Y203133D01*
X243067Y202633D01*
X242900Y201967D01*
X243067Y201300D01*
X243400Y200800D01*
X243900Y200467D01*
X244483Y200300D01*
X245067Y200383D01*
X245567Y200633D01*
X245900Y200967D01*
G01X250000Y205300D02*
Y200300D01*
G01X248833Y203633D02*
X251167D01*
G01X255600D02*
Y200300D01*
G01Y204967D02*
X255433Y205050D01*
Y205217D01*
X255600Y205300D01*
X255767Y205217D01*
Y205050D01*
X255600Y204967D01*
G01X259700Y203633D02*
X261200Y200300D01*
X262700Y203633D01*
G01X265550Y202550D02*
X268217D01*
X267967Y203133D01*
X267550Y203467D01*
X266967Y203633D01*
X266383Y203550D01*
X265883Y203300D01*
X265550Y202717D01*
X265383Y202217D01*
Y201717D01*
X265550Y201217D01*
X265967Y200717D01*
X266467Y200383D01*
X267050Y200300D01*
X267633Y200467D01*
X268217Y200967D01*
G01X276500Y198633D02*
Y203633D01*
G01Y202883D02*
X276917Y203300D01*
X277333Y203550D01*
X278000Y203633D01*
X278583Y203550D01*
X279167Y203133D01*
X279417Y202550D01*
X279500Y201967D01*
X279417Y201383D01*
X279167Y200800D01*
X278667Y200467D01*
X278000Y200300D01*
X277417Y200383D01*
X276833Y200633D01*
X276500Y200967D01*
G01X283600Y200300D02*
X283100Y200383D01*
X282600Y200717D01*
X282267Y201300D01*
X282100Y201967D01*
X282267Y202633D01*
X282600Y203217D01*
X283100Y203550D01*
X283600Y203633D01*
X284100Y203550D01*
X284600Y203217D01*
X284933Y202633D01*
X285017Y201967D01*
X284933Y201300D01*
X284600Y200717D01*
X284100Y200383D01*
X283600Y200300D01*
G01X287950Y200883D02*
X288367Y200550D01*
X288950Y200300D01*
X289450D01*
X289950Y200467D01*
X290283Y200717D01*
X290450Y201050D01*
X290367Y201550D01*
X290033Y201800D01*
X288533Y202300D01*
X288200Y202883D01*
X288367Y203300D01*
X288700Y203550D01*
X289200Y203633D01*
X289700Y203550D01*
X290200Y203300D01*
G01X294800Y203633D02*
Y200300D01*
G01Y204967D02*
X294633Y205050D01*
Y205217D01*
X294800Y205300D01*
X294967Y205217D01*
Y205050D01*
X294800Y204967D01*
G01X300400Y205300D02*
Y200300D01*
G01X299233Y203633D02*
X301567D01*
G01X306000D02*
Y200300D01*
G01Y204967D02*
X305833Y205050D01*
Y205217D01*
X306000Y205300D01*
X306167Y205217D01*
Y205050D01*
X306000Y204967D01*
G01X311600Y200300D02*
X311100Y200383D01*
X310600Y200717D01*
X310267Y201300D01*
X310100Y201967D01*
X310267Y202633D01*
X310600Y203217D01*
X311100Y203550D01*
X311600Y203633D01*
X312100Y203550D01*
X312600Y203217D01*
X312933Y202633D01*
X313017Y201967D01*
X312933Y201300D01*
X312600Y200717D01*
X312100Y200383D01*
X311600Y200300D01*
G01X315783D02*
Y203633D01*
G01Y202800D02*
X316117Y203217D01*
X316617Y203550D01*
X317283Y203633D01*
X317867Y203550D01*
X318367Y203217D01*
X318617Y202633D01*
Y200300D01*
G01X227600Y232300D02*
Y227300D01*
G01X226433Y230633D02*
X228767D01*
G01X231783Y227300D02*
Y232300D01*
G01Y229883D02*
X232200Y230300D01*
X232617Y230550D01*
X233283Y230633D01*
X233783Y230550D01*
X234367Y230217D01*
X234617Y229717D01*
Y227300D01*
G01X238800Y230633D02*
Y227300D01*
G01Y231967D02*
X238633Y232050D01*
Y232217D01*
X238800Y232300D01*
X238967Y232217D01*
Y232050D01*
X238800Y231967D01*
G01X245733Y230217D02*
X245150Y230550D01*
X244650Y230633D01*
X243983Y230467D01*
X243483Y230133D01*
X243150Y229550D01*
X243067Y228967D01*
X243150Y228383D01*
X243483Y227883D01*
X243983Y227467D01*
X244650Y227300D01*
X245233Y227467D01*
X245733Y227800D01*
G01X248583Y227300D02*
Y232300D01*
G01X251250Y230633D02*
X248583Y228717D01*
G01X249667Y229467D02*
X251417Y227300D01*
G01X254183D02*
Y230633D01*
G01Y229800D02*
X254517Y230217D01*
X255017Y230550D01*
X255683Y230633D01*
X256267Y230550D01*
X256767Y230217D01*
X257017Y229633D01*
Y227300D01*
G01X259950Y229550D02*
X262617D01*
X262367Y230133D01*
X261950Y230467D01*
X261367Y230633D01*
X260783Y230550D01*
X260283Y230300D01*
X259950Y229717D01*
X259783Y229217D01*
Y228717D01*
X259950Y228217D01*
X260367Y227717D01*
X260867Y227383D01*
X261450Y227300D01*
X262033Y227467D01*
X262617Y227967D01*
G01X265550Y227883D02*
X265967Y227550D01*
X266550Y227300D01*
X267050D01*
X267550Y227467D01*
X267883Y227717D01*
X268050Y228050D01*
X267967Y228550D01*
X267633Y228800D01*
X266133Y229300D01*
X265800Y229883D01*
X265967Y230300D01*
X266300Y230550D01*
X266800Y230633D01*
X267300Y230550D01*
X267800Y230300D01*
G01X271150Y227883D02*
X271567Y227550D01*
X272150Y227300D01*
X272650D01*
X273150Y227467D01*
X273483Y227717D01*
X273650Y228050D01*
X273567Y228550D01*
X273233Y228800D01*
X271733Y229300D01*
X271400Y229883D01*
X271567Y230300D01*
X271900Y230550D01*
X272400Y230633D01*
X272900Y230550D01*
X273400Y230300D01*
G01X285100Y227300D02*
Y230633D01*
G01Y230050D02*
X284767Y230383D01*
X284267Y230550D01*
X283683Y230633D01*
X283100Y230467D01*
X282600Y230133D01*
X282267Y229633D01*
X282100Y228967D01*
X282267Y228300D01*
X282600Y227800D01*
X283100Y227467D01*
X283683Y227300D01*
X284267Y227383D01*
X284767Y227633D01*
X285100Y227967D01*
G01X288700Y227300D02*
Y231550D01*
X288867Y231967D01*
X289200Y232217D01*
X289700Y232300D01*
X290200Y232133D01*
X290450Y231717D01*
G01X289450Y230300D02*
X287783D01*
G01X294800Y232300D02*
Y227300D01*
G01X293633Y230633D02*
X295967D01*
G01X299150Y229550D02*
X301817D01*
X301567Y230133D01*
X301150Y230467D01*
X300567Y230633D01*
X299983Y230550D01*
X299483Y230300D01*
X299150Y229717D01*
X298983Y229217D01*
Y228717D01*
X299150Y228217D01*
X299567Y227717D01*
X300067Y227383D01*
X300650Y227300D01*
X301233Y227467D01*
X301817Y227967D01*
G01X304833Y227300D02*
Y230633D01*
G01Y229967D02*
X305250Y230300D01*
X305667Y230550D01*
X306250Y230633D01*
X306667Y230550D01*
X307167Y230300D01*
G01X315700Y225633D02*
Y230633D01*
G01Y229883D02*
X316117Y230300D01*
X316533Y230550D01*
X317200Y230633D01*
X317783Y230550D01*
X318367Y230133D01*
X318617Y229550D01*
X318700Y228967D01*
X318617Y228383D01*
X318367Y227800D01*
X317867Y227467D01*
X317200Y227300D01*
X316617Y227383D01*
X316033Y227633D01*
X315700Y227967D01*
G01X322800Y227300D02*
Y232300D01*
G01X329900Y227300D02*
Y230633D01*
G01Y230050D02*
X329567Y230383D01*
X329067Y230550D01*
X328483Y230633D01*
X327900Y230467D01*
X327400Y230133D01*
X327067Y229633D01*
X326900Y228967D01*
X327067Y228300D01*
X327400Y227800D01*
X327900Y227467D01*
X328483Y227300D01*
X329067Y227383D01*
X329567Y227633D01*
X329900Y227967D01*
G01X334000Y232300D02*
Y227300D01*
G01X332833Y230633D02*
X335167D01*
G01X339600D02*
Y227300D01*
G01Y231967D02*
X339433Y232050D01*
Y232217D01*
X339600Y232300D01*
X339767Y232217D01*
Y232050D01*
X339600Y231967D01*
G01X343783Y227300D02*
Y230633D01*
G01Y229800D02*
X344117Y230217D01*
X344617Y230550D01*
X345283Y230633D01*
X345867Y230550D01*
X346367Y230217D01*
X346617Y229633D01*
Y227300D01*
G01X349633Y226050D02*
X350217Y225717D01*
X350883Y225633D01*
X351467Y225717D01*
X351967Y226133D01*
X352300Y226717D01*
Y230633D01*
G01Y229967D02*
X351967Y230300D01*
X351467Y230550D01*
X350883Y230633D01*
X350217Y230467D01*
X349800Y230133D01*
X349467Y229550D01*
X349300Y228967D01*
X349383Y228467D01*
X349717Y227883D01*
X350217Y227467D01*
X350883Y227300D01*
X351383Y227383D01*
X351967Y227717D01*
X352300Y228050D01*
G01X229267Y237300D02*
X225933D01*
Y242300D01*
X229267D01*
G01X227933Y239883D02*
X225933D01*
G01X231950Y240633D02*
X234450Y237300D01*
G01Y240633D02*
X231950Y237300D01*
G01X238800Y242300D02*
Y237300D01*
G01X237633Y240633D02*
X239967D01*
G01X243150Y239550D02*
X245817D01*
X245567Y240133D01*
X245150Y240467D01*
X244567Y240633D01*
X243983Y240550D01*
X243483Y240300D01*
X243150Y239717D01*
X242983Y239217D01*
Y238717D01*
X243150Y238217D01*
X243567Y237717D01*
X244067Y237383D01*
X244650Y237300D01*
X245233Y237467D01*
X245817Y237967D01*
G01X248833Y237300D02*
Y240633D01*
G01Y239967D02*
X249250Y240300D01*
X249667Y240550D01*
X250250Y240633D01*
X250667Y240550D01*
X251167Y240300D01*
G01X254183Y237300D02*
Y240633D01*
G01Y239800D02*
X254517Y240217D01*
X255017Y240550D01*
X255683Y240633D01*
X256267Y240550D01*
X256767Y240217D01*
X257017Y239633D01*
Y237300D01*
G01X262700D02*
Y240633D01*
G01Y240050D02*
X262367Y240383D01*
X261867Y240550D01*
X261283Y240633D01*
X260700Y240467D01*
X260200Y240133D01*
X259867Y239633D01*
X259700Y238967D01*
X259867Y238300D01*
X260200Y237800D01*
X260700Y237467D01*
X261283Y237300D01*
X261867Y237383D01*
X262367Y237633D01*
X262700Y237967D01*
G01X266800Y237300D02*
Y242300D01*
G01X279333Y240217D02*
X278750Y240550D01*
X278250Y240633D01*
X277583Y240467D01*
X277083Y240133D01*
X276750Y239550D01*
X276667Y238967D01*
X276750Y238383D01*
X277083Y237883D01*
X277583Y237467D01*
X278250Y237300D01*
X278833Y237467D01*
X279333Y237800D01*
G01X283600Y237300D02*
X283100Y237383D01*
X282600Y237717D01*
X282267Y238300D01*
X282100Y238967D01*
X282267Y239633D01*
X282600Y240217D01*
X283100Y240550D01*
X283600Y240633D01*
X284100Y240550D01*
X284600Y240217D01*
X284933Y239633D01*
X285017Y238967D01*
X284933Y238300D01*
X284600Y237717D01*
X284100Y237383D01*
X283600Y237300D01*
G01X287783D02*
Y240633D01*
G01Y239800D02*
X288117Y240217D01*
X288617Y240550D01*
X289283Y240633D01*
X289867Y240550D01*
X290367Y240217D01*
X290617Y239633D01*
Y237300D01*
G01X296300Y242300D02*
Y237300D01*
G01Y238050D02*
X295967Y237633D01*
X295467Y237383D01*
X294883Y237300D01*
X294217Y237467D01*
X293717Y237883D01*
X293383Y238383D01*
X293300Y238967D01*
X293383Y239550D01*
X293717Y240050D01*
X294217Y240467D01*
X294883Y240633D01*
X295467Y240550D01*
X295883Y240383D01*
X296300Y240050D01*
G01X298983Y240633D02*
Y238300D01*
X299317Y237717D01*
X299817Y237383D01*
X300400Y237300D01*
X300983Y237383D01*
X301483Y237717D01*
X301817Y238300D01*
G01Y237300D02*
Y240633D01*
G01X307333Y240217D02*
X306750Y240550D01*
X306250Y240633D01*
X305583Y240467D01*
X305083Y240133D01*
X304750Y239550D01*
X304667Y238967D01*
X304750Y238383D01*
X305083Y237883D01*
X305583Y237467D01*
X306250Y237300D01*
X306833Y237467D01*
X307333Y237800D01*
G01X311600Y242300D02*
Y237300D01*
G01X310433Y240633D02*
X312767D01*
G01X317200Y237300D02*
X316700Y237383D01*
X316200Y237717D01*
X315867Y238300D01*
X315700Y238967D01*
X315867Y239633D01*
X316200Y240217D01*
X316700Y240550D01*
X317200Y240633D01*
X317700Y240550D01*
X318200Y240217D01*
X318533Y239633D01*
X318617Y238967D01*
X318533Y238300D01*
X318200Y237717D01*
X317700Y237383D01*
X317200Y237300D01*
G01X321633D02*
Y240633D01*
G01Y239967D02*
X322050Y240300D01*
X322467Y240550D01*
X323050Y240633D01*
X323467Y240550D01*
X323967Y240300D01*
G01X225933Y445300D02*
Y440300D01*
X229267D01*
G01X234700D02*
Y443633D01*
G01Y443050D02*
X234367Y443383D01*
X233867Y443550D01*
X233283Y443633D01*
X232700Y443467D01*
X232200Y443133D01*
X231867Y442633D01*
X231700Y441967D01*
X231867Y441300D01*
X232200Y440800D01*
X232700Y440467D01*
X233283Y440300D01*
X233867Y440383D01*
X234367Y440633D01*
X234700Y440967D01*
G01X237550Y440883D02*
X237967Y440550D01*
X238550Y440300D01*
X239050D01*
X239550Y440467D01*
X239883Y440717D01*
X240050Y441050D01*
X239967Y441550D01*
X239633Y441800D01*
X238133Y442300D01*
X237800Y442883D01*
X237967Y443300D01*
X238300Y443550D01*
X238800Y443633D01*
X239300Y443550D01*
X239800Y443300D01*
G01X243150Y442550D02*
X245817D01*
X245567Y443133D01*
X245150Y443467D01*
X244567Y443633D01*
X243983Y443550D01*
X243483Y443300D01*
X243150Y442717D01*
X242983Y442217D01*
Y441717D01*
X243150Y441217D01*
X243567Y440717D01*
X244067Y440383D01*
X244650Y440300D01*
X245233Y440467D01*
X245817Y440967D01*
G01X248833Y440300D02*
Y443633D01*
G01Y442967D02*
X249250Y443300D01*
X249667Y443550D01*
X250250Y443633D01*
X250667Y443550D01*
X251167Y443300D01*
G01X259700Y443633D02*
X261200Y440300D01*
X262700Y443633D01*
G01X266800D02*
Y440300D01*
G01Y444967D02*
X266633Y445050D01*
Y445217D01*
X266800Y445300D01*
X266967Y445217D01*
Y445050D01*
X266800Y444967D01*
G01X273900Y440300D02*
Y443633D01*
G01Y443050D02*
X273567Y443383D01*
X273067Y443550D01*
X272483Y443633D01*
X271900Y443467D01*
X271400Y443133D01*
X271067Y442633D01*
X270900Y441967D01*
X271067Y441300D01*
X271400Y440800D01*
X271900Y440467D01*
X272483Y440300D01*
X273067Y440383D01*
X273567Y440633D01*
X273900Y440967D01*
G01X281767Y440133D02*
X285433Y443800D01*
G01X283600Y444467D02*
Y439467D01*
G01X285433Y440133D02*
X281767Y443800D01*
G01X281100Y441967D02*
X286100D01*
G01X288783Y438633D02*
X287950Y439467D01*
X287533Y440300D01*
Y443633D01*
X287950Y444467D01*
X288783Y445300D01*
G01X292967Y441050D02*
X293467Y440633D01*
X294050Y440383D01*
X294800Y440300D01*
X295550Y440467D01*
X296133Y440800D01*
X296550Y441383D01*
X296633Y442050D01*
X296467Y442717D01*
X296050Y443133D01*
X295467Y443467D01*
X294883Y443550D01*
X294300Y443467D01*
X293550Y443133D01*
X293800Y445300D01*
X296050D01*
G01X300400Y440133D02*
X300233Y440217D01*
Y440383D01*
X300400Y440467D01*
X300567Y440383D01*
Y440217D01*
X300400Y440133D01*
G01X306000Y440300D02*
Y445300D01*
X305000Y444300D01*
G01Y440300D02*
X307000D01*
G01X312017Y438633D02*
X312850Y439467D01*
X313267Y440300D01*
Y443633D01*
X312850Y444467D01*
X312017Y445300D01*
G01X218600Y453300D02*
X808100D01*
G01X225933Y495300D02*
Y500300D01*
X227933D01*
X228600Y500050D01*
X229100Y499467D01*
X229267Y498800D01*
X229100Y498133D01*
X228683Y497633D01*
X227933Y497383D01*
X225933D01*
G01X233200Y500300D02*
Y495300D01*
G01X231283Y500300D02*
X235117D01*
G01X237050Y495300D02*
Y500300D01*
G01X240550D02*
Y495300D01*
G01Y497800D02*
X237050D01*
G01X248833Y495300D02*
Y498633D01*
G01Y497967D02*
X249250Y498300D01*
X249667Y498550D01*
X250250Y498633D01*
X250667Y498550D01*
X251167Y498300D01*
G01X254350Y497550D02*
X257017D01*
X256767Y498133D01*
X256350Y498467D01*
X255767Y498633D01*
X255183Y498550D01*
X254683Y498300D01*
X254350Y497717D01*
X254183Y497217D01*
Y496717D01*
X254350Y496217D01*
X254767Y495717D01*
X255267Y495383D01*
X255850Y495300D01*
X256433Y495467D01*
X257017Y495967D01*
G01X260033Y494050D02*
X260617Y493717D01*
X261283Y493633D01*
X261867Y493717D01*
X262367Y494133D01*
X262700Y494717D01*
Y498633D01*
G01Y497967D02*
X262367Y498300D01*
X261867Y498550D01*
X261283Y498633D01*
X260617Y498467D01*
X260200Y498133D01*
X259867Y497550D01*
X259700Y496967D01*
X259783Y496467D01*
X260117Y495883D01*
X260617Y495467D01*
X261283Y495300D01*
X261783Y495383D01*
X262367Y495717D01*
X262700Y496050D01*
G01X266800Y498633D02*
Y495300D01*
G01Y499967D02*
X266633Y500050D01*
Y500217D01*
X266800Y500300D01*
X266967Y500217D01*
Y500050D01*
X266800Y499967D01*
G01X271150Y495883D02*
X271567Y495550D01*
X272150Y495300D01*
X272650D01*
X273150Y495467D01*
X273483Y495717D01*
X273650Y496050D01*
X273567Y496550D01*
X273233Y496800D01*
X271733Y497300D01*
X271400Y497883D01*
X271567Y498300D01*
X271900Y498550D01*
X272400Y498633D01*
X272900Y498550D01*
X273400Y498300D01*
G01X278000Y500300D02*
Y495300D01*
G01X276833Y498633D02*
X279167D01*
G01X282433Y495300D02*
Y498633D01*
G01Y497967D02*
X282850Y498300D01*
X283267Y498550D01*
X283850Y498633D01*
X284267Y498550D01*
X284767Y498300D01*
G01X290700Y495300D02*
Y498633D01*
G01Y498050D02*
X290367Y498383D01*
X289867Y498550D01*
X289283Y498633D01*
X288700Y498467D01*
X288200Y498133D01*
X287867Y497633D01*
X287700Y496967D01*
X287867Y496300D01*
X288200Y495800D01*
X288700Y495467D01*
X289283Y495300D01*
X289867Y495383D01*
X290367Y495633D01*
X290700Y495967D01*
G01X294800Y500300D02*
Y495300D01*
G01X293633Y498633D02*
X295967D01*
G01X300400D02*
Y495300D01*
G01Y499967D02*
X300233Y500050D01*
Y500217D01*
X300400Y500300D01*
X300567Y500217D01*
Y500050D01*
X300400Y499967D01*
G01X306000Y495300D02*
X305500Y495383D01*
X305000Y495717D01*
X304667Y496300D01*
X304500Y496967D01*
X304667Y497633D01*
X305000Y498217D01*
X305500Y498550D01*
X306000Y498633D01*
X306500Y498550D01*
X307000Y498217D01*
X307333Y497633D01*
X307417Y496967D01*
X307333Y496300D01*
X307000Y495717D01*
X306500Y495383D01*
X306000Y495300D01*
G01X310183D02*
Y498633D01*
G01Y497800D02*
X310517Y498217D01*
X311017Y498550D01*
X311683Y498633D01*
X312267Y498550D01*
X312767Y498217D01*
X313017Y497633D01*
Y495300D01*
G01X225767Y521800D02*
Y526800D01*
X227433D01*
X228100Y526550D01*
X228600Y526217D01*
X229017Y525717D01*
X229350Y525133D01*
X229433Y524300D01*
X229350Y523467D01*
X229017Y522883D01*
X228600Y522383D01*
X228100Y522050D01*
X227433Y521800D01*
X225767D01*
G01X231950Y524050D02*
X234617D01*
X234367Y524633D01*
X233950Y524967D01*
X233367Y525133D01*
X232783Y525050D01*
X232283Y524800D01*
X231950Y524217D01*
X231783Y523717D01*
Y523217D01*
X231950Y522717D01*
X232367Y522217D01*
X232867Y521883D01*
X233450Y521800D01*
X234033Y521967D01*
X234617Y522467D01*
G01X237300Y520133D02*
Y525133D01*
G01Y524383D02*
X237717Y524800D01*
X238133Y525050D01*
X238800Y525133D01*
X239383Y525050D01*
X239967Y524633D01*
X240217Y524050D01*
X240300Y523467D01*
X240217Y522883D01*
X239967Y522300D01*
X239467Y521967D01*
X238800Y521800D01*
X238217Y521883D01*
X237633Y522133D01*
X237300Y522467D01*
G01X244400Y526800D02*
Y521800D01*
G01X243233Y525133D02*
X245567D01*
G01X248583Y521800D02*
Y526800D01*
G01Y524383D02*
X249000Y524800D01*
X249417Y525050D01*
X250083Y525133D01*
X250583Y525050D01*
X251167Y524717D01*
X251417Y524217D01*
Y521800D01*
G01X262533Y524717D02*
X261950Y525050D01*
X261450Y525133D01*
X260783Y524967D01*
X260283Y524633D01*
X259950Y524050D01*
X259867Y523467D01*
X259950Y522883D01*
X260283Y522383D01*
X260783Y521967D01*
X261450Y521800D01*
X262033Y521967D01*
X262533Y522300D01*
G01X266800Y521800D02*
X266300Y521883D01*
X265800Y522217D01*
X265467Y522800D01*
X265300Y523467D01*
X265467Y524133D01*
X265800Y524717D01*
X266300Y525050D01*
X266800Y525133D01*
X267300Y525050D01*
X267800Y524717D01*
X268133Y524133D01*
X268217Y523467D01*
X268133Y522800D01*
X267800Y522217D01*
X267300Y521883D01*
X266800Y521800D01*
G01X270983D02*
Y525133D01*
G01Y524300D02*
X271317Y524717D01*
X271817Y525050D01*
X272483Y525133D01*
X273067Y525050D01*
X273567Y524717D01*
X273817Y524133D01*
Y521800D01*
G01X278000Y526800D02*
Y521800D01*
G01X276833Y525133D02*
X279167D01*
G01X282433Y521800D02*
Y525133D01*
G01Y524467D02*
X282850Y524800D01*
X283267Y525050D01*
X283850Y525133D01*
X284267Y525050D01*
X284767Y524800D01*
G01X289200Y521800D02*
X288700Y521883D01*
X288200Y522217D01*
X287867Y522800D01*
X287700Y523467D01*
X287867Y524133D01*
X288200Y524717D01*
X288700Y525050D01*
X289200Y525133D01*
X289700Y525050D01*
X290200Y524717D01*
X290533Y524133D01*
X290617Y523467D01*
X290533Y522800D01*
X290200Y522217D01*
X289700Y521883D01*
X289200Y521800D01*
G01X294800D02*
Y526800D01*
G01X304583Y521800D02*
Y526800D01*
G01Y524383D02*
X305000Y524800D01*
X305417Y525050D01*
X306083Y525133D01*
X306583Y525050D01*
X307167Y524717D01*
X307417Y524217D01*
Y521800D01*
G01X311600D02*
X311100Y521883D01*
X310600Y522217D01*
X310267Y522800D01*
X310100Y523467D01*
X310267Y524133D01*
X310600Y524717D01*
X311100Y525050D01*
X311600Y525133D01*
X312100Y525050D01*
X312600Y524717D01*
X312933Y524133D01*
X313017Y523467D01*
X312933Y522800D01*
X312600Y522217D01*
X312100Y521883D01*
X311600Y521800D01*
G01X317200D02*
Y526800D01*
G01X321550Y524050D02*
X324217D01*
X323967Y524633D01*
X323550Y524967D01*
X322967Y525133D01*
X322383Y525050D01*
X321883Y524800D01*
X321550Y524217D01*
X321383Y523717D01*
Y523217D01*
X321550Y522717D01*
X321967Y522217D01*
X322467Y521883D01*
X323050Y521800D01*
X323633Y521967D01*
X324217Y522467D01*
G01X225933Y543800D02*
Y548800D01*
X228017D01*
X228683Y548550D01*
X229100Y548217D01*
X229267Y547550D01*
X229100Y546883D01*
X228600Y546467D01*
X228017Y546217D01*
X225933D01*
G01X228017D02*
X229267Y543800D01*
G01X233200D02*
X232700Y543883D01*
X232200Y544217D01*
X231867Y544800D01*
X231700Y545467D01*
X231867Y546133D01*
X232200Y546717D01*
X232700Y547050D01*
X233200Y547133D01*
X233700Y547050D01*
X234200Y546717D01*
X234533Y546133D01*
X234617Y545467D01*
X234533Y544800D01*
X234200Y544217D01*
X233700Y543883D01*
X233200Y543800D01*
G01X237383Y547133D02*
Y544800D01*
X237717Y544217D01*
X238217Y543883D01*
X238800Y543800D01*
X239383Y543883D01*
X239883Y544217D01*
X240217Y544800D01*
G01Y543800D02*
Y547133D01*
G01X243233Y542550D02*
X243817Y542217D01*
X244483Y542133D01*
X245067Y542217D01*
X245567Y542633D01*
X245900Y543217D01*
Y547133D01*
G01Y546467D02*
X245567Y546800D01*
X245067Y547050D01*
X244483Y547133D01*
X243817Y546967D01*
X243400Y546633D01*
X243067Y546050D01*
X242900Y545467D01*
X242983Y544967D01*
X243317Y544383D01*
X243817Y543967D01*
X244483Y543800D01*
X244983Y543883D01*
X245567Y544217D01*
X245900Y544550D01*
G01X248583Y543800D02*
Y548800D01*
G01Y546383D02*
X249000Y546800D01*
X249417Y547050D01*
X250083Y547133D01*
X250583Y547050D01*
X251167Y546717D01*
X251417Y546217D01*
Y543800D01*
G01X254183D02*
Y547133D01*
G01Y546300D02*
X254517Y546717D01*
X255017Y547050D01*
X255683Y547133D01*
X256267Y547050D01*
X256767Y546717D01*
X257017Y546133D01*
Y543800D01*
G01X259950Y546050D02*
X262617D01*
X262367Y546633D01*
X261950Y546967D01*
X261367Y547133D01*
X260783Y547050D01*
X260283Y546800D01*
X259950Y546217D01*
X259783Y545717D01*
Y545217D01*
X259950Y544717D01*
X260367Y544217D01*
X260867Y543883D01*
X261450Y543800D01*
X262033Y543967D01*
X262617Y544467D01*
G01X265550Y544383D02*
X265967Y544050D01*
X266550Y543800D01*
X267050D01*
X267550Y543967D01*
X267883Y544217D01*
X268050Y544550D01*
X267967Y545050D01*
X267633Y545300D01*
X266133Y545800D01*
X265800Y546383D01*
X265967Y546800D01*
X266300Y547050D01*
X266800Y547133D01*
X267300Y547050D01*
X267800Y546800D01*
G01X271150Y544383D02*
X271567Y544050D01*
X272150Y543800D01*
X272650D01*
X273150Y543967D01*
X273483Y544217D01*
X273650Y544550D01*
X273567Y545050D01*
X273233Y545300D01*
X271733Y545800D01*
X271400Y546383D01*
X271567Y546800D01*
X271900Y547050D01*
X272400Y547133D01*
X272900Y547050D01*
X273400Y546800D01*
G01X217600Y552800D02*
X808100D01*
G01X225850Y602300D02*
Y607300D01*
G01X229350D02*
Y602300D01*
G01Y604800D02*
X225850D01*
G01X233200Y602300D02*
X232700Y602383D01*
X232200Y602717D01*
X231867Y603300D01*
X231700Y603967D01*
X231867Y604633D01*
X232200Y605217D01*
X232700Y605550D01*
X233200Y605633D01*
X233700Y605550D01*
X234200Y605217D01*
X234533Y604633D01*
X234617Y603967D01*
X234533Y603300D01*
X234200Y602717D01*
X233700Y602383D01*
X233200Y602300D01*
G01X238800D02*
Y607300D01*
G01X243150Y604550D02*
X245817D01*
X245567Y605133D01*
X245150Y605467D01*
X244567Y605633D01*
X243983Y605550D01*
X243483Y605300D01*
X243150Y604717D01*
X242983Y604217D01*
Y603717D01*
X243150Y603217D01*
X243567Y602717D01*
X244067Y602383D01*
X244650Y602300D01*
X245233Y602467D01*
X245817Y602967D01*
G01X254350Y602883D02*
X254767Y602550D01*
X255350Y602300D01*
X255850D01*
X256350Y602467D01*
X256683Y602717D01*
X256850Y603050D01*
X256767Y603550D01*
X256433Y603800D01*
X254933Y604300D01*
X254600Y604883D01*
X254767Y605300D01*
X255100Y605550D01*
X255600Y605633D01*
X256100Y605550D01*
X256600Y605300D01*
G01X261200Y605633D02*
Y602300D01*
G01Y606967D02*
X261033Y607050D01*
Y607217D01*
X261200Y607300D01*
X261367Y607217D01*
Y607050D01*
X261200Y606967D01*
G01X265550Y605633D02*
X268050D01*
X265550Y602300D01*
X268050D01*
G01X271150Y604550D02*
X273817D01*
X273567Y605133D01*
X273150Y605467D01*
X272567Y605633D01*
X271983Y605550D01*
X271483Y605300D01*
X271150Y604717D01*
X270983Y604217D01*
Y603717D01*
X271150Y603217D01*
X271567Y602717D01*
X272067Y602383D01*
X272650Y602300D01*
X273233Y602467D01*
X273817Y602967D01*
G01X225517Y698800D02*
X227600Y693800D01*
X229683Y698800D01*
G01X233200Y697133D02*
Y693800D01*
G01Y698467D02*
X233033Y698550D01*
Y698717D01*
X233200Y698800D01*
X233367Y698717D01*
Y698550D01*
X233200Y698467D01*
G01X240300Y693800D02*
Y697133D01*
G01Y696550D02*
X239967Y696883D01*
X239467Y697050D01*
X238883Y697133D01*
X238300Y696967D01*
X237800Y696633D01*
X237467Y696133D01*
X237300Y695467D01*
X237467Y694800D01*
X237800Y694300D01*
X238300Y693967D01*
X238883Y693800D01*
X239467Y693883D01*
X239967Y694133D01*
X240300Y694467D01*
G01X248583Y693800D02*
Y698800D01*
G01Y696383D02*
X249000Y696800D01*
X249417Y697050D01*
X250083Y697133D01*
X250583Y697050D01*
X251167Y696717D01*
X251417Y696217D01*
Y693800D01*
G01X255600D02*
X255100Y693883D01*
X254600Y694217D01*
X254267Y694800D01*
X254100Y695467D01*
X254267Y696133D01*
X254600Y696717D01*
X255100Y697050D01*
X255600Y697133D01*
X256100Y697050D01*
X256600Y696717D01*
X256933Y696133D01*
X257017Y695467D01*
X256933Y694800D01*
X256600Y694217D01*
X256100Y693883D01*
X255600Y693800D01*
G01X261200D02*
Y698800D01*
G01X265550Y696050D02*
X268217D01*
X267967Y696633D01*
X267550Y696967D01*
X266967Y697133D01*
X266383Y697050D01*
X265883Y696800D01*
X265550Y696217D01*
X265383Y695717D01*
Y695217D01*
X265550Y694717D01*
X265967Y694217D01*
X266467Y693883D01*
X267050Y693800D01*
X267633Y693967D01*
X268217Y694467D01*
G01X278000Y698800D02*
Y693800D01*
G01X276833Y697133D02*
X279167D01*
G01X282183Y693800D02*
Y698800D01*
G01Y696383D02*
X282600Y696800D01*
X283017Y697050D01*
X283683Y697133D01*
X284183Y697050D01*
X284767Y696717D01*
X285017Y696217D01*
Y693800D01*
G01X287950Y696050D02*
X290617D01*
X290367Y696633D01*
X289950Y696967D01*
X289367Y697133D01*
X288783Y697050D01*
X288283Y696800D01*
X287950Y696217D01*
X287783Y695717D01*
Y695217D01*
X287950Y694717D01*
X288367Y694217D01*
X288867Y693883D01*
X289450Y693800D01*
X290033Y693967D01*
X290617Y694467D01*
G01X293633Y693800D02*
Y697133D01*
G01Y696467D02*
X294050Y696800D01*
X294467Y697050D01*
X295050Y697133D01*
X295467Y697050D01*
X295967Y696800D01*
G01X297900Y693800D02*
Y697133D01*
G01Y696217D02*
X298150Y696633D01*
X298567Y696967D01*
X299150Y697133D01*
X299733Y696967D01*
X300150Y696633D01*
X300400Y696217D01*
Y693800D01*
G01Y696217D02*
X300650Y696633D01*
X301067Y696967D01*
X301650Y697133D01*
X302233Y696967D01*
X302650Y696633D01*
X302900Y696133D01*
Y693800D01*
G01X307500D02*
Y697133D01*
G01Y696550D02*
X307167Y696883D01*
X306667Y697050D01*
X306083Y697133D01*
X305500Y696967D01*
X305000Y696633D01*
X304667Y696133D01*
X304500Y695467D01*
X304667Y694800D01*
X305000Y694300D01*
X305500Y693967D01*
X306083Y693800D01*
X306667Y693883D01*
X307167Y694133D01*
X307500Y694467D01*
G01X311600Y693800D02*
Y698800D01*
G01X321300Y692133D02*
Y697133D01*
G01Y696383D02*
X321717Y696800D01*
X322133Y697050D01*
X322800Y697133D01*
X323383Y697050D01*
X323967Y696633D01*
X324217Y696050D01*
X324300Y695467D01*
X324217Y694883D01*
X323967Y694300D01*
X323467Y693967D01*
X322800Y693800D01*
X322217Y693883D01*
X321633Y694133D01*
X321300Y694467D01*
G01X329900Y693800D02*
Y697133D01*
G01Y696550D02*
X329567Y696883D01*
X329067Y697050D01*
X328483Y697133D01*
X327900Y696967D01*
X327400Y696633D01*
X327067Y696133D01*
X326900Y695467D01*
X327067Y694800D01*
X327400Y694300D01*
X327900Y693967D01*
X328483Y693800D01*
X329067Y693883D01*
X329567Y694133D01*
X329900Y694467D01*
G01X335500Y698800D02*
Y693800D01*
G01Y694550D02*
X335167Y694133D01*
X334667Y693883D01*
X334083Y693800D01*
X333417Y693967D01*
X332917Y694383D01*
X332583Y694883D01*
X332500Y695467D01*
X332583Y696050D01*
X332917Y696550D01*
X333417Y696967D01*
X334083Y697133D01*
X334667Y697050D01*
X335083Y696883D01*
X335500Y696550D01*
G01X225850Y677300D02*
Y682300D01*
G01X229350D02*
Y677300D01*
G01Y679800D02*
X225850D01*
G01X233200Y677300D02*
X232700Y677383D01*
X232200Y677717D01*
X231867Y678300D01*
X231700Y678967D01*
X231867Y679633D01*
X232200Y680217D01*
X232700Y680550D01*
X233200Y680633D01*
X233700Y680550D01*
X234200Y680217D01*
X234533Y679633D01*
X234617Y678967D01*
X234533Y678300D01*
X234200Y677717D01*
X233700Y677383D01*
X233200Y677300D01*
G01X238800D02*
Y682300D01*
G01X243150Y679550D02*
X245817D01*
X245567Y680133D01*
X245150Y680467D01*
X244567Y680633D01*
X243983Y680550D01*
X243483Y680300D01*
X243150Y679717D01*
X242983Y679217D01*
Y678717D01*
X243150Y678217D01*
X243567Y677717D01*
X244067Y677383D01*
X244650Y677300D01*
X245233Y677467D01*
X245817Y677967D01*
G01X254100Y675633D02*
Y680633D01*
G01Y679883D02*
X254517Y680300D01*
X254933Y680550D01*
X255600Y680633D01*
X256183Y680550D01*
X256767Y680133D01*
X257017Y679550D01*
X257100Y678967D01*
X257017Y678383D01*
X256767Y677800D01*
X256267Y677467D01*
X255600Y677300D01*
X255017Y677383D01*
X254433Y677633D01*
X254100Y677967D01*
G01X261200Y677300D02*
X260700Y677383D01*
X260200Y677717D01*
X259867Y678300D01*
X259700Y678967D01*
X259867Y679633D01*
X260200Y680217D01*
X260700Y680550D01*
X261200Y680633D01*
X261700Y680550D01*
X262200Y680217D01*
X262533Y679633D01*
X262617Y678967D01*
X262533Y678300D01*
X262200Y677717D01*
X261700Y677383D01*
X261200Y677300D01*
G01X265550Y677883D02*
X265967Y677550D01*
X266550Y677300D01*
X267050D01*
X267550Y677467D01*
X267883Y677717D01*
X268050Y678050D01*
X267967Y678550D01*
X267633Y678800D01*
X266133Y679300D01*
X265800Y679883D01*
X265967Y680300D01*
X266300Y680550D01*
X266800Y680633D01*
X267300Y680550D01*
X267800Y680300D01*
G01X272400Y680633D02*
Y677300D01*
G01Y681967D02*
X272233Y682050D01*
Y682217D01*
X272400Y682300D01*
X272567Y682217D01*
Y682050D01*
X272400Y681967D01*
G01X278000Y682300D02*
Y677300D01*
G01X276833Y680633D02*
X279167D01*
G01X283600D02*
Y677300D01*
G01Y681967D02*
X283433Y682050D01*
Y682217D01*
X283600Y682300D01*
X283767Y682217D01*
Y682050D01*
X283600Y681967D01*
G01X289200Y677300D02*
X288700Y677383D01*
X288200Y677717D01*
X287867Y678300D01*
X287700Y678967D01*
X287867Y679633D01*
X288200Y680217D01*
X288700Y680550D01*
X289200Y680633D01*
X289700Y680550D01*
X290200Y680217D01*
X290533Y679633D01*
X290617Y678967D01*
X290533Y678300D01*
X290200Y677717D01*
X289700Y677383D01*
X289200Y677300D01*
G01X293383D02*
Y680633D01*
G01Y679800D02*
X293717Y680217D01*
X294217Y680550D01*
X294883Y680633D01*
X295467Y680550D01*
X295967Y680217D01*
X296217Y679633D01*
Y677300D01*
G01X306000Y682300D02*
Y677300D01*
G01X304833Y680633D02*
X307167D01*
G01X311600Y677300D02*
X311100Y677383D01*
X310600Y677717D01*
X310267Y678300D01*
X310100Y678967D01*
X310267Y679633D01*
X310600Y680217D01*
X311100Y680550D01*
X311600Y680633D01*
X312100Y680550D01*
X312600Y680217D01*
X312933Y679633D01*
X313017Y678967D01*
X312933Y678300D01*
X312600Y677717D01*
X312100Y677383D01*
X311600Y677300D01*
G01X317200D02*
Y682300D01*
G01X321550Y679550D02*
X324217D01*
X323967Y680133D01*
X323550Y680467D01*
X322967Y680633D01*
X322383Y680550D01*
X321883Y680300D01*
X321550Y679717D01*
X321383Y679217D01*
Y678717D01*
X321550Y678217D01*
X321967Y677717D01*
X322467Y677383D01*
X323050Y677300D01*
X323633Y677467D01*
X324217Y677967D01*
G01X327233Y677300D02*
Y680633D01*
G01Y679967D02*
X327650Y680300D01*
X328067Y680550D01*
X328650Y680633D01*
X329067Y680550D01*
X329567Y680300D01*
G01X335500Y677300D02*
Y680633D01*
G01Y680050D02*
X335167Y680383D01*
X334667Y680550D01*
X334083Y680633D01*
X333500Y680467D01*
X333000Y680133D01*
X332667Y679633D01*
X332500Y678967D01*
X332667Y678300D01*
X333000Y677800D01*
X333500Y677467D01*
X334083Y677300D01*
X334667Y677383D01*
X335167Y677633D01*
X335500Y677967D01*
G01X338183Y677300D02*
Y680633D01*
G01Y679800D02*
X338517Y680217D01*
X339017Y680550D01*
X339683Y680633D01*
X340267Y680550D01*
X340767Y680217D01*
X341017Y679633D01*
Y677300D01*
G01X346533Y680217D02*
X345950Y680550D01*
X345450Y680633D01*
X344783Y680467D01*
X344283Y680133D01*
X343950Y679550D01*
X343867Y678967D01*
X343950Y678383D01*
X344283Y677883D01*
X344783Y677467D01*
X345450Y677300D01*
X346033Y677467D01*
X346533Y677800D01*
G01X349550Y679550D02*
X352217D01*
X351967Y680133D01*
X351550Y680467D01*
X350967Y680633D01*
X350383Y680550D01*
X349883Y680300D01*
X349550Y679717D01*
X349383Y679217D01*
Y678717D01*
X349550Y678217D01*
X349967Y677717D01*
X350467Y677383D01*
X351050Y677300D01*
X351633Y677467D01*
X352217Y677967D01*
G01X225517Y708800D02*
X227600Y713800D01*
X229683Y708800D01*
G01X228933Y710550D02*
X226267D01*
G01X231783Y708800D02*
Y712133D01*
G01Y711300D02*
X232117Y711717D01*
X232617Y712050D01*
X233283Y712133D01*
X233867Y712050D01*
X234367Y711717D01*
X234617Y711133D01*
Y708800D01*
G01X238800Y713800D02*
Y708800D01*
G01X237633Y712133D02*
X239967D01*
G01X244400D02*
Y708800D01*
G01Y713467D02*
X244233Y713550D01*
Y713717D01*
X244400Y713800D01*
X244567Y713717D01*
Y713550D01*
X244400Y713467D01*
G01X248917Y710467D02*
X251083D01*
G01X259700Y707133D02*
Y712133D01*
G01Y711383D02*
X260117Y711800D01*
X260533Y712050D01*
X261200Y712133D01*
X261783Y712050D01*
X262367Y711633D01*
X262617Y711050D01*
X262700Y710467D01*
X262617Y709883D01*
X262367Y709300D01*
X261867Y708967D01*
X261200Y708800D01*
X260617Y708883D01*
X260033Y709133D01*
X259700Y709467D01*
G01X268300Y708800D02*
Y712133D01*
G01Y711550D02*
X267967Y711883D01*
X267467Y712050D01*
X266883Y712133D01*
X266300Y711967D01*
X265800Y711633D01*
X265467Y711133D01*
X265300Y710467D01*
X265467Y709800D01*
X265800Y709300D01*
X266300Y708967D01*
X266883Y708800D01*
X267467Y708883D01*
X267967Y709133D01*
X268300Y709467D01*
G01X273900Y713800D02*
Y708800D01*
G01Y709550D02*
X273567Y709133D01*
X273067Y708883D01*
X272483Y708800D01*
X271817Y708967D01*
X271317Y709383D01*
X270983Y709883D01*
X270900Y710467D01*
X270983Y711050D01*
X271317Y711550D01*
X271817Y711967D01*
X272483Y712133D01*
X273067Y712050D01*
X273483Y711883D01*
X273900Y711550D01*
G01X225443Y728390D02*
Y733390D01*
X229277Y728390D01*
Y733390D01*
G01X232960Y728390D02*
X232460Y728473D01*
X231960Y728807D01*
X231627Y729390D01*
X231460Y730057D01*
X231627Y730723D01*
X231960Y731307D01*
X232460Y731640D01*
X232960Y731723D01*
X233460Y731640D01*
X233960Y731307D01*
X234293Y730723D01*
X234377Y730057D01*
X234293Y729390D01*
X233960Y728807D01*
X233460Y728473D01*
X232960Y728390D01*
G01X237143D02*
Y731723D01*
G01Y730890D02*
X237477Y731307D01*
X237977Y731640D01*
X238643Y731723D01*
X239227Y731640D01*
X239727Y731307D01*
X239977Y730723D01*
Y728390D01*
G01X243077Y730057D02*
X245243D01*
G01X249260Y728390D02*
Y732640D01*
X249427Y733057D01*
X249760Y733307D01*
X250260Y733390D01*
X250760Y733223D01*
X251010Y732807D01*
G01X250010Y731390D02*
X248343D01*
G01X253943Y731723D02*
Y729390D01*
X254277Y728807D01*
X254777Y728473D01*
X255360Y728390D01*
X255943Y728473D01*
X256443Y728807D01*
X256777Y729390D01*
G01Y728390D02*
Y731723D01*
G01X259543Y728390D02*
Y731723D01*
G01Y730890D02*
X259877Y731307D01*
X260377Y731640D01*
X261043Y731723D01*
X261627Y731640D01*
X262127Y731307D01*
X262377Y730723D01*
Y728390D01*
G01X267893Y731307D02*
X267310Y731640D01*
X266810Y731723D01*
X266143Y731557D01*
X265643Y731223D01*
X265310Y730640D01*
X265227Y730057D01*
X265310Y729473D01*
X265643Y728973D01*
X266143Y728557D01*
X266810Y728390D01*
X267393Y728557D01*
X267893Y728890D01*
G01X272160Y733390D02*
Y728390D01*
G01X270993Y731723D02*
X273327D01*
G01X277760D02*
Y728390D01*
G01Y733057D02*
X277593Y733140D01*
Y733307D01*
X277760Y733390D01*
X277927Y733307D01*
Y733140D01*
X277760Y733057D01*
G01X283360Y728390D02*
X282860Y728473D01*
X282360Y728807D01*
X282027Y729390D01*
X281860Y730057D01*
X282027Y730723D01*
X282360Y731307D01*
X282860Y731640D01*
X283360Y731723D01*
X283860Y731640D01*
X284360Y731307D01*
X284693Y730723D01*
X284777Y730057D01*
X284693Y729390D01*
X284360Y728807D01*
X283860Y728473D01*
X283360Y728390D01*
G01X287543D02*
Y731723D01*
G01Y730890D02*
X287877Y731307D01*
X288377Y731640D01*
X289043Y731723D01*
X289627Y731640D01*
X290127Y731307D01*
X290377Y730723D01*
Y728390D01*
G01X296060D02*
Y731723D01*
G01Y731140D02*
X295727Y731473D01*
X295227Y731640D01*
X294643Y731723D01*
X294060Y731557D01*
X293560Y731223D01*
X293227Y730723D01*
X293060Y730057D01*
X293227Y729390D01*
X293560Y728890D01*
X294060Y728557D01*
X294643Y728390D01*
X295227Y728473D01*
X295727Y728723D01*
X296060Y729057D01*
G01X300160Y728390D02*
Y733390D01*
G01X309860Y726723D02*
Y731723D01*
G01Y730973D02*
X310277Y731390D01*
X310693Y731640D01*
X311360Y731723D01*
X311943Y731640D01*
X312527Y731223D01*
X312777Y730640D01*
X312860Y730057D01*
X312777Y729473D01*
X312527Y728890D01*
X312027Y728557D01*
X311360Y728390D01*
X310777Y728473D01*
X310193Y728723D01*
X309860Y729057D01*
G01X318460Y728390D02*
Y731723D01*
G01Y731140D02*
X318127Y731473D01*
X317627Y731640D01*
X317043Y731723D01*
X316460Y731557D01*
X315960Y731223D01*
X315627Y730723D01*
X315460Y730057D01*
X315627Y729390D01*
X315960Y728890D01*
X316460Y728557D01*
X317043Y728390D01*
X317627Y728473D01*
X318127Y728723D01*
X318460Y729057D01*
G01X324060Y733390D02*
Y728390D01*
G01Y729140D02*
X323727Y728723D01*
X323227Y728473D01*
X322643Y728390D01*
X321977Y728557D01*
X321477Y728973D01*
X321143Y729473D01*
X321060Y730057D01*
X321143Y730640D01*
X321477Y731140D01*
X321977Y731557D01*
X322643Y731723D01*
X323227Y731640D01*
X323643Y731473D01*
X324060Y731140D01*
G01X273933Y756883D02*
X273433Y757133D01*
X272850Y757300D01*
X272183D01*
X271433Y757050D01*
X270850Y756633D01*
X270433Y756133D01*
X270100Y755300D01*
X270017Y754550D01*
X270183Y753800D01*
X270433Y753300D01*
X270933Y752800D01*
X271517Y752467D01*
X272100Y752300D01*
X272683D01*
X273267Y752467D01*
X273767Y752717D01*
X274183Y753050D01*
G01X277700Y752300D02*
Y757300D01*
G01X284800Y752300D02*
Y755633D01*
G01Y755050D02*
X284467Y755383D01*
X283967Y755550D01*
X283383Y755633D01*
X282800Y755467D01*
X282300Y755133D01*
X281967Y754633D01*
X281800Y753967D01*
X281967Y753300D01*
X282300Y752800D01*
X282800Y752467D01*
X283383Y752300D01*
X283967Y752383D01*
X284467Y752633D01*
X284800Y752967D01*
G01X287650Y752883D02*
X288067Y752550D01*
X288650Y752300D01*
X289150D01*
X289650Y752467D01*
X289983Y752717D01*
X290150Y753050D01*
X290067Y753550D01*
X289733Y753800D01*
X288233Y754300D01*
X287900Y754883D01*
X288067Y755300D01*
X288400Y755550D01*
X288900Y755633D01*
X289400Y755550D01*
X289900Y755300D01*
G01X293250Y752883D02*
X293667Y752550D01*
X294250Y752300D01*
X294750D01*
X295250Y752467D01*
X295583Y752717D01*
X295750Y753050D01*
X295667Y753550D01*
X295333Y753800D01*
X293833Y754300D01*
X293500Y754883D01*
X293667Y755300D01*
X294000Y755550D01*
X294500Y755633D01*
X295000Y755550D01*
X295500Y755300D01*
G01X300100Y755633D02*
Y752300D01*
G01Y756967D02*
X299933Y757050D01*
Y757217D01*
X300100Y757300D01*
X300267Y757217D01*
Y757050D01*
X300100Y756967D01*
G01X305200Y752300D02*
Y756550D01*
X305367Y756967D01*
X305700Y757217D01*
X306200Y757300D01*
X306700Y757133D01*
X306950Y756717D01*
G01X305950Y755300D02*
X304283D01*
G01X309550Y750800D02*
X310050Y750633D01*
X310717Y750800D01*
X311133Y751133D01*
X311467Y751550D01*
X311967Y752883D01*
X313050Y755633D01*
G01X310383D02*
X311967Y752883D01*
G01X387600Y25300D02*
Y28633D01*
G01Y28050D02*
X387267Y28383D01*
X386767Y28550D01*
X386183Y28633D01*
X385600Y28467D01*
X385100Y28133D01*
X384767Y27633D01*
X384600Y26967D01*
X384767Y26300D01*
X385100Y25800D01*
X385600Y25467D01*
X386183Y25300D01*
X386767Y25383D01*
X387267Y25633D01*
X387600Y25967D01*
G01X393200Y30300D02*
Y25300D01*
G01Y26050D02*
X392867Y25633D01*
X392367Y25383D01*
X391783Y25300D01*
X391117Y25467D01*
X390617Y25883D01*
X390283Y26383D01*
X390200Y26967D01*
X390283Y27550D01*
X390617Y28050D01*
X391117Y28467D01*
X391783Y28633D01*
X392367Y28550D01*
X392783Y28383D01*
X393200Y28050D01*
G01X398800Y30300D02*
Y25300D01*
G01Y26050D02*
X398467Y25633D01*
X397967Y25383D01*
X397383Y25300D01*
X396717Y25467D01*
X396217Y25883D01*
X395883Y26383D01*
X395800Y26967D01*
X395883Y27550D01*
X396217Y28050D01*
X396717Y28467D01*
X397383Y28633D01*
X397967Y28550D01*
X398383Y28383D01*
X398800Y28050D01*
G01X407250Y25883D02*
X407667Y25550D01*
X408250Y25300D01*
X408750D01*
X409250Y25467D01*
X409583Y25717D01*
X409750Y26050D01*
X409667Y26550D01*
X409333Y26800D01*
X407833Y27300D01*
X407500Y27883D01*
X407667Y28300D01*
X408000Y28550D01*
X408500Y28633D01*
X409000Y28550D01*
X409500Y28300D01*
G01X412683Y28633D02*
Y26300D01*
X413017Y25717D01*
X413517Y25383D01*
X414100Y25300D01*
X414683Y25383D01*
X415183Y25717D01*
X415517Y26300D01*
G01Y25300D02*
Y28633D01*
G01X418200Y23633D02*
Y28633D01*
G01Y27883D02*
X418617Y28300D01*
X419033Y28550D01*
X419700Y28633D01*
X420283Y28550D01*
X420867Y28133D01*
X421117Y27550D01*
X421200Y26967D01*
X421117Y26383D01*
X420867Y25800D01*
X420367Y25467D01*
X419700Y25300D01*
X419117Y25383D01*
X418533Y25633D01*
X418200Y25967D01*
G01X423800Y23633D02*
Y28633D01*
G01Y27883D02*
X424217Y28300D01*
X424633Y28550D01*
X425300Y28633D01*
X425883Y28550D01*
X426467Y28133D01*
X426717Y27550D01*
X426800Y26967D01*
X426717Y26383D01*
X426467Y25800D01*
X425967Y25467D01*
X425300Y25300D01*
X424717Y25383D01*
X424133Y25633D01*
X423800Y25967D01*
G01X430900Y25300D02*
Y30300D01*
G01X436500Y28633D02*
Y25300D01*
G01Y29967D02*
X436333Y30050D01*
Y30217D01*
X436500Y30300D01*
X436667Y30217D01*
Y30050D01*
X436500Y29967D01*
G01X440850Y27550D02*
X443517D01*
X443267Y28133D01*
X442850Y28467D01*
X442267Y28633D01*
X441683Y28550D01*
X441183Y28300D01*
X440850Y27717D01*
X440683Y27217D01*
Y26717D01*
X440850Y26217D01*
X441267Y25717D01*
X441767Y25383D01*
X442350Y25300D01*
X442933Y25467D01*
X443517Y25967D01*
G01X446533Y25300D02*
Y28633D01*
G01Y27967D02*
X446950Y28300D01*
X447367Y28550D01*
X447950Y28633D01*
X448367Y28550D01*
X448867Y28300D01*
G01X453300Y28633D02*
X454133Y29675D01*
Y30300D01*
X453508D01*
Y29675D01*
X454133D01*
G01X457650Y25883D02*
X458067Y25550D01*
X458650Y25300D01*
X459150D01*
X459650Y25467D01*
X459983Y25717D01*
X460150Y26050D01*
X460067Y26550D01*
X459733Y26800D01*
X458233Y27300D01*
X457900Y27883D01*
X458067Y28300D01*
X458400Y28550D01*
X458900Y28633D01*
X459400Y28550D01*
X459900Y28300D01*
G01X468433Y30300D02*
Y25300D01*
X471767D01*
G01X475700D02*
X475200Y25383D01*
X474700Y25717D01*
X474367Y26300D01*
X474200Y26967D01*
X474367Y27633D01*
X474700Y28217D01*
X475200Y28550D01*
X475700Y28633D01*
X476200Y28550D01*
X476700Y28217D01*
X477033Y27633D01*
X477117Y26967D01*
X477033Y26300D01*
X476700Y25717D01*
X476200Y25383D01*
X475700Y25300D01*
G01X480133Y24050D02*
X480717Y23717D01*
X481383Y23633D01*
X481967Y23717D01*
X482467Y24133D01*
X482800Y24717D01*
Y28633D01*
G01Y27967D02*
X482467Y28300D01*
X481967Y28550D01*
X481383Y28633D01*
X480717Y28467D01*
X480300Y28133D01*
X479967Y27550D01*
X479800Y26967D01*
X479883Y26467D01*
X480217Y25883D01*
X480717Y25467D01*
X481383Y25300D01*
X481883Y25383D01*
X482467Y25717D01*
X482800Y26050D01*
G01X486900Y25300D02*
X486400Y25383D01*
X485900Y25717D01*
X485567Y26300D01*
X485400Y26967D01*
X485567Y27633D01*
X485900Y28217D01*
X486400Y28550D01*
X486900Y28633D01*
X487400Y28550D01*
X487900Y28217D01*
X488233Y27633D01*
X488317Y26967D01*
X488233Y26300D01*
X487900Y25717D01*
X487400Y25383D01*
X486900Y25300D01*
G01X499600D02*
Y28633D01*
G01Y28050D02*
X499267Y28383D01*
X498767Y28550D01*
X498183Y28633D01*
X497600Y28467D01*
X497100Y28133D01*
X496767Y27633D01*
X496600Y26967D01*
X496767Y26300D01*
X497100Y25800D01*
X497600Y25467D01*
X498183Y25300D01*
X498767Y25383D01*
X499267Y25633D01*
X499600Y25967D01*
G01X502283Y25300D02*
Y28633D01*
G01Y27800D02*
X502617Y28217D01*
X503117Y28550D01*
X503783Y28633D01*
X504367Y28550D01*
X504867Y28217D01*
X505117Y27633D01*
Y25300D01*
G01X510800Y30300D02*
Y25300D01*
G01Y26050D02*
X510467Y25633D01*
X509967Y25383D01*
X509383Y25300D01*
X508717Y25467D01*
X508217Y25883D01*
X507883Y26383D01*
X507800Y26967D01*
X507883Y27550D01*
X508217Y28050D01*
X508717Y28467D01*
X509383Y28633D01*
X509967Y28550D01*
X510383Y28383D01*
X510800Y28050D01*
G01X518667Y30300D02*
Y26717D01*
X519000Y25967D01*
X519667Y25467D01*
X520500Y25300D01*
X521333Y25467D01*
X522000Y25967D01*
X522333Y26717D01*
Y30300D01*
G01X524433D02*
Y25300D01*
X527767D01*
G01X536800D02*
Y29550D01*
X536967Y29967D01*
X537300Y30217D01*
X537800Y30300D01*
X538300Y30133D01*
X538550Y29717D01*
G01X537550Y28300D02*
X535883D01*
G01X542900Y28633D02*
Y25300D01*
G01Y29967D02*
X542733Y30050D01*
Y30217D01*
X542900Y30300D01*
X543067Y30217D01*
Y30050D01*
X542900Y29967D01*
G01X548500Y25300D02*
Y30300D01*
G01X552850Y27550D02*
X555517D01*
X555267Y28133D01*
X554850Y28467D01*
X554267Y28633D01*
X553683Y28550D01*
X553183Y28300D01*
X552850Y27717D01*
X552683Y27217D01*
Y26717D01*
X552850Y26217D01*
X553267Y25717D01*
X553767Y25383D01*
X554350Y25300D01*
X554933Y25467D01*
X555517Y25967D01*
G01X563383Y25300D02*
Y30300D01*
X567217Y25300D01*
Y30300D01*
G01X569483Y28633D02*
Y26300D01*
X569817Y25717D01*
X570317Y25383D01*
X570900Y25300D01*
X571483Y25383D01*
X571983Y25717D01*
X572317Y26300D01*
G01Y25300D02*
Y28633D01*
G01X574000Y25300D02*
Y28633D01*
G01Y27717D02*
X574250Y28133D01*
X574667Y28467D01*
X575250Y28633D01*
X575833Y28467D01*
X576250Y28133D01*
X576500Y27717D01*
Y25300D01*
G01Y27717D02*
X576750Y28133D01*
X577167Y28467D01*
X577750Y28633D01*
X578333Y28467D01*
X578750Y28133D01*
X579000Y27633D01*
Y25300D01*
G01X580600D02*
Y30300D01*
G01Y27800D02*
X581017Y28300D01*
X581517Y28550D01*
X582017Y28633D01*
X582767Y28467D01*
X583267Y28133D01*
X583600Y27550D01*
Y26883D01*
X583433Y26217D01*
X583100Y25717D01*
X582517Y25383D01*
X582017Y25300D01*
X581517Y25383D01*
X581017Y25633D01*
X580600Y26050D01*
G01X586450Y27550D02*
X589117D01*
X588867Y28133D01*
X588450Y28467D01*
X587867Y28633D01*
X587283Y28550D01*
X586783Y28300D01*
X586450Y27717D01*
X586283Y27217D01*
Y26717D01*
X586450Y26217D01*
X586867Y25717D01*
X587367Y25383D01*
X587950Y25300D01*
X588533Y25467D01*
X589117Y25967D01*
G01X592133Y25300D02*
Y28633D01*
G01Y27967D02*
X592550Y28300D01*
X592967Y28550D01*
X593550Y28633D01*
X593967Y28550D01*
X594467Y28300D01*
G01X604500Y28633D02*
Y25300D01*
G01Y29967D02*
X604333Y30050D01*
Y30217D01*
X604500Y30300D01*
X604667Y30217D01*
Y30050D01*
X604500Y29967D01*
G01X608683Y25300D02*
Y28633D01*
G01Y27800D02*
X609017Y28217D01*
X609517Y28550D01*
X610183Y28633D01*
X610767Y28550D01*
X611267Y28217D01*
X611517Y27633D01*
Y25300D01*
G01X620050Y25883D02*
X620467Y25550D01*
X621050Y25300D01*
X621550D01*
X622050Y25467D01*
X622383Y25717D01*
X622550Y26050D01*
X622467Y26550D01*
X622133Y26800D01*
X620633Y27300D01*
X620300Y27883D01*
X620467Y28300D01*
X620800Y28550D01*
X621300Y28633D01*
X621800Y28550D01*
X622300Y28300D01*
G01X626900Y28633D02*
Y25300D01*
G01Y29967D02*
X626733Y30050D01*
Y30217D01*
X626900Y30300D01*
X627067Y30217D01*
Y30050D01*
X626900Y29967D01*
G01X632500Y25300D02*
Y30300D01*
G01X636683Y25300D02*
Y30300D01*
G01X639350Y28633D02*
X636683Y26717D01*
G01X637767Y27467D02*
X639517Y25300D01*
G01X642450Y25883D02*
X642867Y25550D01*
X643450Y25300D01*
X643950D01*
X644450Y25467D01*
X644783Y25717D01*
X644950Y26050D01*
X644867Y26550D01*
X644533Y26800D01*
X643033Y27300D01*
X642700Y27883D01*
X642867Y28300D01*
X643200Y28550D01*
X643700Y28633D01*
X644200Y28550D01*
X644700Y28300D01*
G01X650633Y28217D02*
X650050Y28550D01*
X649550Y28633D01*
X648883Y28467D01*
X648383Y28133D01*
X648050Y27550D01*
X647967Y26967D01*
X648050Y26383D01*
X648383Y25883D01*
X648883Y25467D01*
X649550Y25300D01*
X650133Y25467D01*
X650633Y25800D01*
G01X653733Y25300D02*
Y28633D01*
G01Y27967D02*
X654150Y28300D01*
X654567Y28550D01*
X655150Y28633D01*
X655567Y28550D01*
X656067Y28300D01*
G01X659250Y27550D02*
X661917D01*
X661667Y28133D01*
X661250Y28467D01*
X660667Y28633D01*
X660083Y28550D01*
X659583Y28300D01*
X659250Y27717D01*
X659083Y27217D01*
Y26717D01*
X659250Y26217D01*
X659667Y25717D01*
X660167Y25383D01*
X660750Y25300D01*
X661333Y25467D01*
X661917Y25967D01*
G01X664850Y27550D02*
X667517D01*
X667267Y28133D01*
X666850Y28467D01*
X666267Y28633D01*
X665683Y28550D01*
X665183Y28300D01*
X664850Y27717D01*
X664683Y27217D01*
Y26717D01*
X664850Y26217D01*
X665267Y25717D01*
X665767Y25383D01*
X666350Y25300D01*
X666933Y25467D01*
X667517Y25967D01*
G01X670283Y25300D02*
Y28633D01*
G01Y27800D02*
X670617Y28217D01*
X671117Y28550D01*
X671783Y28633D01*
X672367Y28550D01*
X672867Y28217D01*
X673117Y27633D01*
Y25300D01*
G01X384350Y40967D02*
X385017Y40550D01*
X385767Y40300D01*
X386433D01*
X387100Y40550D01*
X387600Y40967D01*
X387850Y41550D01*
X387683Y42133D01*
X387267Y42633D01*
X386517Y42967D01*
X385517Y43133D01*
X384933Y43467D01*
X384683Y44050D01*
X384850Y44633D01*
X385267Y45050D01*
X385850Y45300D01*
X386433D01*
X387017Y45133D01*
X387517Y44717D01*
G01X391700Y40300D02*
X391200Y40383D01*
X390700Y40717D01*
X390367Y41300D01*
X390200Y41967D01*
X390367Y42633D01*
X390700Y43217D01*
X391200Y43550D01*
X391700Y43633D01*
X392200Y43550D01*
X392700Y43217D01*
X393033Y42633D01*
X393117Y41967D01*
X393033Y41300D01*
X392700Y40717D01*
X392200Y40383D01*
X391700Y40300D01*
G01X397300D02*
Y45300D01*
G01X404400D02*
Y40300D01*
G01Y41050D02*
X404067Y40633D01*
X403567Y40383D01*
X402983Y40300D01*
X402317Y40467D01*
X401817Y40883D01*
X401483Y41383D01*
X401400Y41967D01*
X401483Y42550D01*
X401817Y43050D01*
X402317Y43467D01*
X402983Y43633D01*
X403567Y43550D01*
X403983Y43383D01*
X404400Y43050D01*
G01X407250Y42550D02*
X409917D01*
X409667Y43133D01*
X409250Y43467D01*
X408667Y43633D01*
X408083Y43550D01*
X407583Y43300D01*
X407250Y42717D01*
X407083Y42217D01*
Y41717D01*
X407250Y41217D01*
X407667Y40717D01*
X408167Y40383D01*
X408750Y40300D01*
X409333Y40467D01*
X409917Y40967D01*
G01X412933Y40300D02*
Y43633D01*
G01Y42967D02*
X413350Y43300D01*
X413767Y43550D01*
X414350Y43633D01*
X414767Y43550D01*
X415267Y43300D01*
G01X422800Y40300D02*
Y43633D01*
G01Y42717D02*
X423050Y43133D01*
X423467Y43467D01*
X424050Y43633D01*
X424633Y43467D01*
X425050Y43133D01*
X425300Y42717D01*
Y40300D01*
G01Y42717D02*
X425550Y43133D01*
X425967Y43467D01*
X426550Y43633D01*
X427133Y43467D01*
X427550Y43133D01*
X427800Y42633D01*
Y40300D01*
G01X432400D02*
Y43633D01*
G01Y43050D02*
X432067Y43383D01*
X431567Y43550D01*
X430983Y43633D01*
X430400Y43467D01*
X429900Y43133D01*
X429567Y42633D01*
X429400Y41967D01*
X429567Y41300D01*
X429900Y40800D01*
X430400Y40467D01*
X430983Y40300D01*
X431567Y40383D01*
X432067Y40633D01*
X432400Y40967D01*
G01X435250Y40883D02*
X435667Y40550D01*
X436250Y40300D01*
X436750D01*
X437250Y40467D01*
X437583Y40717D01*
X437750Y41050D01*
X437667Y41550D01*
X437333Y41800D01*
X435833Y42300D01*
X435500Y42883D01*
X435667Y43300D01*
X436000Y43550D01*
X436500Y43633D01*
X437000Y43550D01*
X437500Y43300D01*
G01X440683Y40300D02*
Y45300D01*
G01X443350Y43633D02*
X440683Y41717D01*
G01X441767Y42467D02*
X443517Y40300D01*
G01X453300Y45300D02*
Y40300D01*
G01X452133Y43633D02*
X454467D01*
G01X457483Y40300D02*
Y45300D01*
G01Y42883D02*
X457900Y43300D01*
X458317Y43550D01*
X458983Y43633D01*
X459483Y43550D01*
X460067Y43217D01*
X460317Y42717D01*
Y40300D01*
G01X464500Y43633D02*
Y40300D01*
G01Y44967D02*
X464333Y45050D01*
Y45217D01*
X464500Y45300D01*
X464667Y45217D01*
Y45050D01*
X464500Y44967D01*
G01X471433Y43217D02*
X470850Y43550D01*
X470350Y43633D01*
X469683Y43467D01*
X469183Y43133D01*
X468850Y42550D01*
X468767Y41967D01*
X468850Y41383D01*
X469183Y40883D01*
X469683Y40467D01*
X470350Y40300D01*
X470933Y40467D01*
X471433Y40800D01*
G01X474283Y40300D02*
Y45300D01*
G01X476950Y43633D02*
X474283Y41717D01*
G01X475367Y42467D02*
X477117Y40300D01*
G01X479883D02*
Y43633D01*
G01Y42800D02*
X480217Y43217D01*
X480717Y43550D01*
X481383Y43633D01*
X481967Y43550D01*
X482467Y43217D01*
X482717Y42633D01*
Y40300D01*
G01X485650Y42550D02*
X488317D01*
X488067Y43133D01*
X487650Y43467D01*
X487067Y43633D01*
X486483Y43550D01*
X485983Y43300D01*
X485650Y42717D01*
X485483Y42217D01*
Y41717D01*
X485650Y41217D01*
X486067Y40717D01*
X486567Y40383D01*
X487150Y40300D01*
X487733Y40467D01*
X488317Y40967D01*
G01X491250Y40883D02*
X491667Y40550D01*
X492250Y40300D01*
X492750D01*
X493250Y40467D01*
X493583Y40717D01*
X493750Y41050D01*
X493667Y41550D01*
X493333Y41800D01*
X491833Y42300D01*
X491500Y42883D01*
X491667Y43300D01*
X492000Y43550D01*
X492500Y43633D01*
X493000Y43550D01*
X493500Y43300D01*
G01X496850Y40883D02*
X497267Y40550D01*
X497850Y40300D01*
X498350D01*
X498850Y40467D01*
X499183Y40717D01*
X499350Y41050D01*
X499267Y41550D01*
X498933Y41800D01*
X497433Y42300D01*
X497100Y42883D01*
X497267Y43300D01*
X497600Y43550D01*
X498100Y43633D01*
X498600Y43550D01*
X499100Y43300D01*
G01X507800Y38633D02*
Y43633D01*
G01Y42883D02*
X508217Y43300D01*
X508633Y43550D01*
X509300Y43633D01*
X509883Y43550D01*
X510467Y43133D01*
X510717Y42550D01*
X510800Y41967D01*
X510717Y41383D01*
X510467Y40800D01*
X509967Y40467D01*
X509300Y40300D01*
X508717Y40383D01*
X508133Y40633D01*
X507800Y40967D01*
G01X514900Y40300D02*
Y45300D01*
G01X519083Y43633D02*
Y41300D01*
X519417Y40717D01*
X519917Y40383D01*
X520500Y40300D01*
X521083Y40383D01*
X521583Y40717D01*
X521917Y41300D01*
G01Y40300D02*
Y43633D01*
G01X524850Y40883D02*
X525267Y40550D01*
X525850Y40300D01*
X526350D01*
X526850Y40467D01*
X527183Y40717D01*
X527350Y41050D01*
X527267Y41550D01*
X526933Y41800D01*
X525433Y42300D01*
X525100Y42883D01*
X525267Y43300D01*
X525600Y43550D01*
X526100Y43633D01*
X526600Y43550D01*
X527100Y43300D01*
G01X537300Y40300D02*
Y45300D01*
G01X541650Y42550D02*
X544317D01*
X544067Y43133D01*
X543650Y43467D01*
X543067Y43633D01*
X542483Y43550D01*
X541983Y43300D01*
X541650Y42717D01*
X541483Y42217D01*
Y41717D01*
X541650Y41217D01*
X542067Y40717D01*
X542567Y40383D01*
X543150Y40300D01*
X543733Y40467D01*
X544317Y40967D01*
G01X547333Y39050D02*
X547917Y38717D01*
X548583Y38633D01*
X549167Y38717D01*
X549667Y39133D01*
X550000Y39717D01*
Y43633D01*
G01Y42967D02*
X549667Y43300D01*
X549167Y43550D01*
X548583Y43633D01*
X547917Y43467D01*
X547500Y43133D01*
X547167Y42550D01*
X547000Y41967D01*
X547083Y41467D01*
X547417Y40883D01*
X547917Y40467D01*
X548583Y40300D01*
X549083Y40383D01*
X549667Y40717D01*
X550000Y41050D01*
G01X552850Y42550D02*
X555517D01*
X555267Y43133D01*
X554850Y43467D01*
X554267Y43633D01*
X553683Y43550D01*
X553183Y43300D01*
X552850Y42717D01*
X552683Y42217D01*
Y41717D01*
X552850Y41217D01*
X553267Y40717D01*
X553767Y40383D01*
X554350Y40300D01*
X554933Y40467D01*
X555517Y40967D01*
G01X558283Y40300D02*
Y43633D01*
G01Y42800D02*
X558617Y43217D01*
X559117Y43550D01*
X559783Y43633D01*
X560367Y43550D01*
X560867Y43217D01*
X561117Y42633D01*
Y40300D01*
G01X566800Y45300D02*
Y40300D01*
G01Y41050D02*
X566467Y40633D01*
X565967Y40383D01*
X565383Y40300D01*
X564717Y40467D01*
X564217Y40883D01*
X563883Y41383D01*
X563800Y41967D01*
X563883Y42550D01*
X564217Y43050D01*
X564717Y43467D01*
X565383Y43633D01*
X565967Y43550D01*
X566383Y43383D01*
X566800Y43050D01*
G01X576500Y45300D02*
Y40300D01*
G01X575333Y43633D02*
X577667D01*
G01X580683Y40300D02*
Y45300D01*
G01Y42883D02*
X581100Y43300D01*
X581517Y43550D01*
X582183Y43633D01*
X582683Y43550D01*
X583267Y43217D01*
X583517Y42717D01*
Y40300D01*
G01X587700Y43633D02*
Y40300D01*
G01Y44967D02*
X587533Y45050D01*
Y45217D01*
X587700Y45300D01*
X587867Y45217D01*
Y45050D01*
X587700Y44967D01*
G01X594633Y43217D02*
X594050Y43550D01*
X593550Y43633D01*
X592883Y43467D01*
X592383Y43133D01*
X592050Y42550D01*
X591967Y41967D01*
X592050Y41383D01*
X592383Y40883D01*
X592883Y40467D01*
X593550Y40300D01*
X594133Y40467D01*
X594633Y40800D01*
G01X597483Y40300D02*
Y45300D01*
G01X600150Y43633D02*
X597483Y41717D01*
G01X598567Y42467D02*
X600317Y40300D01*
G01X603083D02*
Y43633D01*
G01Y42800D02*
X603417Y43217D01*
X603917Y43550D01*
X604583Y43633D01*
X605167Y43550D01*
X605667Y43217D01*
X605917Y42633D01*
Y40300D01*
G01X608850Y42550D02*
X611517D01*
X611267Y43133D01*
X610850Y43467D01*
X610267Y43633D01*
X609683Y43550D01*
X609183Y43300D01*
X608850Y42717D01*
X608683Y42217D01*
Y41717D01*
X608850Y41217D01*
X609267Y40717D01*
X609767Y40383D01*
X610350Y40300D01*
X610933Y40467D01*
X611517Y40967D01*
G01X614450Y40883D02*
X614867Y40550D01*
X615450Y40300D01*
X615950D01*
X616450Y40467D01*
X616783Y40717D01*
X616950Y41050D01*
X616867Y41550D01*
X616533Y41800D01*
X615033Y42300D01*
X614700Y42883D01*
X614867Y43300D01*
X615200Y43550D01*
X615700Y43633D01*
X616200Y43550D01*
X616700Y43300D01*
G01X620050Y40883D02*
X620467Y40550D01*
X621050Y40300D01*
X621550D01*
X622050Y40467D01*
X622383Y40717D01*
X622550Y41050D01*
X622467Y41550D01*
X622133Y41800D01*
X620633Y42300D01*
X620300Y42883D01*
X620467Y43300D01*
X620800Y43550D01*
X621300Y43633D01*
X621800Y43550D01*
X622300Y43300D01*
G01X632500Y40300D02*
X632000Y40383D01*
X631500Y40717D01*
X631167Y41300D01*
X631000Y41967D01*
X631167Y42633D01*
X631500Y43217D01*
X632000Y43550D01*
X632500Y43633D01*
X633000Y43550D01*
X633500Y43217D01*
X633833Y42633D01*
X633917Y41967D01*
X633833Y41300D01*
X633500Y40717D01*
X633000Y40383D01*
X632500Y40300D01*
G01X636683D02*
Y43633D01*
G01Y42800D02*
X637017Y43217D01*
X637517Y43550D01*
X638183Y43633D01*
X638767Y43550D01*
X639267Y43217D01*
X639517Y42633D01*
Y40300D01*
G01X649300Y45300D02*
Y40300D01*
G01X648133Y43633D02*
X650467D01*
G01X653733Y40300D02*
Y43633D01*
G01Y42967D02*
X654150Y43300D01*
X654567Y43550D01*
X655150Y43633D01*
X655567Y43550D01*
X656067Y43300D01*
G01X662000Y40300D02*
Y43633D01*
G01Y43050D02*
X661667Y43383D01*
X661167Y43550D01*
X660583Y43633D01*
X660000Y43467D01*
X659500Y43133D01*
X659167Y42633D01*
X659000Y41967D01*
X659167Y41300D01*
X659500Y40800D01*
X660000Y40467D01*
X660583Y40300D01*
X661167Y40383D01*
X661667Y40633D01*
X662000Y40967D01*
G01X667433Y43217D02*
X666850Y43550D01*
X666350Y43633D01*
X665683Y43467D01*
X665183Y43133D01*
X664850Y42550D01*
X664767Y41967D01*
X664850Y41383D01*
X665183Y40883D01*
X665683Y40467D01*
X666350Y40300D01*
X666933Y40467D01*
X667433Y40800D01*
G01X670450Y42550D02*
X673117D01*
X672867Y43133D01*
X672450Y43467D01*
X671867Y43633D01*
X671283Y43550D01*
X670783Y43300D01*
X670450Y42717D01*
X670283Y42217D01*
Y41717D01*
X670450Y41217D01*
X670867Y40717D01*
X671367Y40383D01*
X671950Y40300D01*
X672533Y40467D01*
X673117Y40967D01*
G01X677300Y40133D02*
X677133Y40217D01*
Y40383D01*
X677300Y40467D01*
X677467Y40383D01*
Y40217D01*
X677300Y40133D01*
G01X386100Y55300D02*
Y60300D01*
G01X390450Y57550D02*
X393117D01*
X392867Y58133D01*
X392450Y58467D01*
X391867Y58633D01*
X391283Y58550D01*
X390783Y58300D01*
X390450Y57717D01*
X390283Y57217D01*
Y56717D01*
X390450Y56217D01*
X390867Y55717D01*
X391367Y55383D01*
X391950Y55300D01*
X392533Y55467D01*
X393117Y55967D01*
G01X396133Y54050D02*
X396717Y53717D01*
X397383Y53633D01*
X397967Y53717D01*
X398467Y54133D01*
X398800Y54717D01*
Y58633D01*
G01Y57967D02*
X398467Y58300D01*
X397967Y58550D01*
X397383Y58633D01*
X396717Y58467D01*
X396300Y58133D01*
X395967Y57550D01*
X395800Y56967D01*
X395883Y56467D01*
X396217Y55883D01*
X396717Y55467D01*
X397383Y55300D01*
X397883Y55383D01*
X398467Y55717D01*
X398800Y56050D01*
G01X401650Y57550D02*
X404317D01*
X404067Y58133D01*
X403650Y58467D01*
X403067Y58633D01*
X402483Y58550D01*
X401983Y58300D01*
X401650Y57717D01*
X401483Y57217D01*
Y56717D01*
X401650Y56217D01*
X402067Y55717D01*
X402567Y55383D01*
X403150Y55300D01*
X403733Y55467D01*
X404317Y55967D01*
G01X407083Y55300D02*
Y58633D01*
G01Y57800D02*
X407417Y58217D01*
X407917Y58550D01*
X408583Y58633D01*
X409167Y58550D01*
X409667Y58217D01*
X409917Y57633D01*
Y55300D01*
G01X415600Y60300D02*
Y55300D01*
G01Y56050D02*
X415267Y55633D01*
X414767Y55383D01*
X414183Y55300D01*
X413517Y55467D01*
X413017Y55883D01*
X412683Y56383D01*
X412600Y56967D01*
X412683Y57550D01*
X413017Y58050D01*
X413517Y58467D01*
X414183Y58633D01*
X414767Y58550D01*
X415183Y58383D01*
X415600Y58050D01*
G01X425300Y60300D02*
Y55300D01*
G01X424133Y58633D02*
X426467D01*
G01X429483Y55300D02*
Y60300D01*
G01Y57883D02*
X429900Y58300D01*
X430317Y58550D01*
X430983Y58633D01*
X431483Y58550D01*
X432067Y58217D01*
X432317Y57717D01*
Y55300D01*
G01X436500Y58633D02*
Y55300D01*
G01Y59967D02*
X436333Y60050D01*
Y60217D01*
X436500Y60300D01*
X436667Y60217D01*
Y60050D01*
X436500Y59967D01*
G01X443433Y58217D02*
X442850Y58550D01*
X442350Y58633D01*
X441683Y58467D01*
X441183Y58133D01*
X440850Y57550D01*
X440767Y56967D01*
X440850Y56383D01*
X441183Y55883D01*
X441683Y55467D01*
X442350Y55300D01*
X442933Y55467D01*
X443433Y55800D01*
G01X446283Y55300D02*
Y60300D01*
G01X448950Y58633D02*
X446283Y56717D01*
G01X447367Y57467D02*
X449117Y55300D01*
G01X451883D02*
Y58633D01*
G01Y57800D02*
X452217Y58217D01*
X452717Y58550D01*
X453383Y58633D01*
X453967Y58550D01*
X454467Y58217D01*
X454717Y57633D01*
Y55300D01*
G01X457650Y57550D02*
X460317D01*
X460067Y58133D01*
X459650Y58467D01*
X459067Y58633D01*
X458483Y58550D01*
X457983Y58300D01*
X457650Y57717D01*
X457483Y57217D01*
Y56717D01*
X457650Y56217D01*
X458067Y55717D01*
X458567Y55383D01*
X459150Y55300D01*
X459733Y55467D01*
X460317Y55967D01*
G01X463250Y55883D02*
X463667Y55550D01*
X464250Y55300D01*
X464750D01*
X465250Y55467D01*
X465583Y55717D01*
X465750Y56050D01*
X465667Y56550D01*
X465333Y56800D01*
X463833Y57300D01*
X463500Y57883D01*
X463667Y58300D01*
X464000Y58550D01*
X464500Y58633D01*
X465000Y58550D01*
X465500Y58300D01*
G01X468850Y55883D02*
X469267Y55550D01*
X469850Y55300D01*
X470350D01*
X470850Y55467D01*
X471183Y55717D01*
X471350Y56050D01*
X471267Y56550D01*
X470933Y56800D01*
X469433Y57300D01*
X469100Y57883D01*
X469267Y58300D01*
X469600Y58550D01*
X470100Y58633D01*
X470600Y58550D01*
X471100Y58300D01*
G01X481300Y55300D02*
X480800Y55383D01*
X480300Y55717D01*
X479967Y56300D01*
X479800Y56967D01*
X479967Y57633D01*
X480300Y58217D01*
X480800Y58550D01*
X481300Y58633D01*
X481800Y58550D01*
X482300Y58217D01*
X482633Y57633D01*
X482717Y56967D01*
X482633Y56300D01*
X482300Y55717D01*
X481800Y55383D01*
X481300Y55300D01*
G01X485483D02*
Y58633D01*
G01Y57800D02*
X485817Y58217D01*
X486317Y58550D01*
X486983Y58633D01*
X487567Y58550D01*
X488067Y58217D01*
X488317Y57633D01*
Y55300D01*
G01X499433Y58217D02*
X498850Y58550D01*
X498350Y58633D01*
X497683Y58467D01*
X497183Y58133D01*
X496850Y57550D01*
X496767Y56967D01*
X496850Y56383D01*
X497183Y55883D01*
X497683Y55467D01*
X498350Y55300D01*
X498933Y55467D01*
X499433Y55800D01*
G01X503700Y55300D02*
X503200Y55383D01*
X502700Y55717D01*
X502367Y56300D01*
X502200Y56967D01*
X502367Y57633D01*
X502700Y58217D01*
X503200Y58550D01*
X503700Y58633D01*
X504200Y58550D01*
X504700Y58217D01*
X505033Y57633D01*
X505117Y56967D01*
X505033Y56300D01*
X504700Y55717D01*
X504200Y55383D01*
X503700Y55300D01*
G01X507800Y53633D02*
Y58633D01*
G01Y57883D02*
X508217Y58300D01*
X508633Y58550D01*
X509300Y58633D01*
X509883Y58550D01*
X510467Y58133D01*
X510717Y57550D01*
X510800Y56967D01*
X510717Y56383D01*
X510467Y55800D01*
X509967Y55467D01*
X509300Y55300D01*
X508717Y55383D01*
X508133Y55633D01*
X507800Y55967D01*
G01X513400Y53633D02*
Y58633D01*
G01Y57883D02*
X513817Y58300D01*
X514233Y58550D01*
X514900Y58633D01*
X515483Y58550D01*
X516067Y58133D01*
X516317Y57550D01*
X516400Y56967D01*
X516317Y56383D01*
X516067Y55800D01*
X515567Y55467D01*
X514900Y55300D01*
X514317Y55383D01*
X513733Y55633D01*
X513400Y55967D01*
G01X519250Y57550D02*
X521917D01*
X521667Y58133D01*
X521250Y58467D01*
X520667Y58633D01*
X520083Y58550D01*
X519583Y58300D01*
X519250Y57717D01*
X519083Y57217D01*
Y56717D01*
X519250Y56217D01*
X519667Y55717D01*
X520167Y55383D01*
X520750Y55300D01*
X521333Y55467D01*
X521917Y55967D01*
G01X524933Y55300D02*
Y58633D01*
G01Y57967D02*
X525350Y58300D01*
X525767Y58550D01*
X526350Y58633D01*
X526767Y58550D01*
X527267Y58300D01*
G01X536883Y53633D02*
X536050Y54467D01*
X535633Y55300D01*
Y58633D01*
X536050Y59467D01*
X536883Y60300D01*
G01X540817Y58633D02*
X541817Y55300D01*
X542900Y58633D01*
X543983Y55300D01*
X544983Y58633D01*
G01X547083Y55300D02*
Y60300D01*
G01Y57883D02*
X547500Y58300D01*
X547917Y58550D01*
X548583Y58633D01*
X549083Y58550D01*
X549667Y58217D01*
X549917Y57717D01*
Y55300D01*
G01X554100Y58633D02*
Y55300D01*
G01Y59967D02*
X553933Y60050D01*
Y60217D01*
X554100Y60300D01*
X554267Y60217D01*
Y60050D01*
X554100Y59967D01*
G01X561033Y58217D02*
X560450Y58550D01*
X559950Y58633D01*
X559283Y58467D01*
X558783Y58133D01*
X558450Y57550D01*
X558367Y56967D01*
X558450Y56383D01*
X558783Y55883D01*
X559283Y55467D01*
X559950Y55300D01*
X560533Y55467D01*
X561033Y55800D01*
G01X563883Y55300D02*
Y60300D01*
G01Y57883D02*
X564300Y58300D01*
X564717Y58550D01*
X565383Y58633D01*
X565883Y58550D01*
X566467Y58217D01*
X566717Y57717D01*
Y55300D01*
G01X576500Y58633D02*
Y55300D01*
G01Y59967D02*
X576333Y60050D01*
Y60217D01*
X576500Y60300D01*
X576667Y60217D01*
Y60050D01*
X576500Y59967D01*
G01X580850Y55883D02*
X581267Y55550D01*
X581850Y55300D01*
X582350D01*
X582850Y55467D01*
X583183Y55717D01*
X583350Y56050D01*
X583267Y56550D01*
X582933Y56800D01*
X581433Y57300D01*
X581100Y57883D01*
X581267Y58300D01*
X581600Y58550D01*
X582100Y58633D01*
X582600Y58550D01*
X583100Y58300D01*
G01X591800Y55300D02*
Y60300D01*
G01Y57800D02*
X592217Y58300D01*
X592717Y58550D01*
X593217Y58633D01*
X593967Y58467D01*
X594467Y58133D01*
X594800Y57550D01*
Y56883D01*
X594633Y56217D01*
X594300Y55717D01*
X593717Y55383D01*
X593217Y55300D01*
X592717Y55383D01*
X592217Y55633D01*
X591800Y56050D01*
G01X597650Y57550D02*
X600317D01*
X600067Y58133D01*
X599650Y58467D01*
X599067Y58633D01*
X598483Y58550D01*
X597983Y58300D01*
X597650Y57717D01*
X597483Y57217D01*
Y56717D01*
X597650Y56217D01*
X598067Y55717D01*
X598567Y55383D01*
X599150Y55300D01*
X599733Y55467D01*
X600317Y55967D01*
G01X604500Y60300D02*
Y55300D01*
G01X603333Y58633D02*
X605667D01*
G01X610100Y60300D02*
Y55300D01*
G01X608933Y58633D02*
X611267D01*
G01X614450Y57550D02*
X617117D01*
X616867Y58133D01*
X616450Y58467D01*
X615867Y58633D01*
X615283Y58550D01*
X614783Y58300D01*
X614450Y57717D01*
X614283Y57217D01*
Y56717D01*
X614450Y56217D01*
X614867Y55717D01*
X615367Y55383D01*
X615950Y55300D01*
X616533Y55467D01*
X617117Y55967D01*
G01X620133Y55300D02*
Y58633D01*
G01Y57967D02*
X620550Y58300D01*
X620967Y58550D01*
X621550Y58633D01*
X621967Y58550D01*
X622467Y58300D01*
G01X627317Y53633D02*
X628150Y54467D01*
X628567Y55300D01*
Y58633D01*
X628150Y59467D01*
X627317Y60300D01*
G01X384850Y69383D02*
X385267Y69050D01*
X385850Y68800D01*
X386350D01*
X386850Y68967D01*
X387183Y69217D01*
X387350Y69550D01*
X387267Y70050D01*
X386933Y70300D01*
X385433Y70800D01*
X385100Y71383D01*
X385267Y71800D01*
X385600Y72050D01*
X386100Y72133D01*
X386600Y72050D01*
X387100Y71800D01*
G01X391700Y68800D02*
X391200Y68883D01*
X390700Y69217D01*
X390367Y69800D01*
X390200Y70467D01*
X390367Y71133D01*
X390700Y71717D01*
X391200Y72050D01*
X391700Y72133D01*
X392200Y72050D01*
X392700Y71717D01*
X393033Y71133D01*
X393117Y70467D01*
X393033Y69800D01*
X392700Y69217D01*
X392200Y68883D01*
X391700Y68800D01*
G01X397300D02*
Y73800D01*
G01X404400D02*
Y68800D01*
G01Y69550D02*
X404067Y69133D01*
X403567Y68883D01*
X402983Y68800D01*
X402317Y68967D01*
X401817Y69383D01*
X401483Y69883D01*
X401400Y70467D01*
X401483Y71050D01*
X401817Y71550D01*
X402317Y71967D01*
X402983Y72133D01*
X403567Y72050D01*
X403983Y71883D01*
X404400Y71550D01*
G01X407250Y71050D02*
X409917D01*
X409667Y71633D01*
X409250Y71967D01*
X408667Y72133D01*
X408083Y72050D01*
X407583Y71800D01*
X407250Y71217D01*
X407083Y70717D01*
Y70217D01*
X407250Y69717D01*
X407667Y69217D01*
X408167Y68883D01*
X408750Y68800D01*
X409333Y68967D01*
X409917Y69467D01*
G01X412933Y68800D02*
Y72133D01*
G01Y71467D02*
X413350Y71800D01*
X413767Y72050D01*
X414350Y72133D01*
X414767Y72050D01*
X415267Y71800D01*
G01X422800Y68800D02*
Y72133D01*
G01Y71217D02*
X423050Y71633D01*
X423467Y71967D01*
X424050Y72133D01*
X424633Y71967D01*
X425050Y71633D01*
X425300Y71217D01*
Y68800D01*
G01Y71217D02*
X425550Y71633D01*
X425967Y71967D01*
X426550Y72133D01*
X427133Y71967D01*
X427550Y71633D01*
X427800Y71133D01*
Y68800D01*
G01X432400D02*
Y72133D01*
G01Y71550D02*
X432067Y71883D01*
X431567Y72050D01*
X430983Y72133D01*
X430400Y71967D01*
X429900Y71633D01*
X429567Y71133D01*
X429400Y70467D01*
X429567Y69800D01*
X429900Y69300D01*
X430400Y68967D01*
X430983Y68800D01*
X431567Y68883D01*
X432067Y69133D01*
X432400Y69467D01*
G01X435250Y69383D02*
X435667Y69050D01*
X436250Y68800D01*
X436750D01*
X437250Y68967D01*
X437583Y69217D01*
X437750Y69550D01*
X437667Y70050D01*
X437333Y70300D01*
X435833Y70800D01*
X435500Y71383D01*
X435667Y71800D01*
X436000Y72050D01*
X436500Y72133D01*
X437000Y72050D01*
X437500Y71800D01*
G01X440683Y68800D02*
Y73800D01*
G01X443350Y72133D02*
X440683Y70217D01*
G01X441767Y70967D02*
X443517Y68800D01*
G01X453300Y73800D02*
Y68800D01*
G01X452133Y72133D02*
X454467D01*
G01X457483Y68800D02*
Y73800D01*
G01Y71383D02*
X457900Y71800D01*
X458317Y72050D01*
X458983Y72133D01*
X459483Y72050D01*
X460067Y71717D01*
X460317Y71217D01*
Y68800D01*
G01X464500Y72133D02*
Y68800D01*
G01Y73467D02*
X464333Y73550D01*
Y73717D01*
X464500Y73800D01*
X464667Y73717D01*
Y73550D01*
X464500Y73467D01*
G01X471433Y71717D02*
X470850Y72050D01*
X470350Y72133D01*
X469683Y71967D01*
X469183Y71633D01*
X468850Y71050D01*
X468767Y70467D01*
X468850Y69883D01*
X469183Y69383D01*
X469683Y68967D01*
X470350Y68800D01*
X470933Y68967D01*
X471433Y69300D01*
G01X474283Y68800D02*
Y73800D01*
G01X476950Y72133D02*
X474283Y70217D01*
G01X475367Y70967D02*
X477117Y68800D01*
G01X479883D02*
Y72133D01*
G01Y71300D02*
X480217Y71717D01*
X480717Y72050D01*
X481383Y72133D01*
X481967Y72050D01*
X482467Y71717D01*
X482717Y71133D01*
Y68800D01*
G01X485650Y71050D02*
X488317D01*
X488067Y71633D01*
X487650Y71967D01*
X487067Y72133D01*
X486483Y72050D01*
X485983Y71800D01*
X485650Y71217D01*
X485483Y70717D01*
Y70217D01*
X485650Y69717D01*
X486067Y69217D01*
X486567Y68883D01*
X487150Y68800D01*
X487733Y68967D01*
X488317Y69467D01*
G01X491250Y69383D02*
X491667Y69050D01*
X492250Y68800D01*
X492750D01*
X493250Y68967D01*
X493583Y69217D01*
X493750Y69550D01*
X493667Y70050D01*
X493333Y70300D01*
X491833Y70800D01*
X491500Y71383D01*
X491667Y71800D01*
X492000Y72050D01*
X492500Y72133D01*
X493000Y72050D01*
X493500Y71800D01*
G01X496850Y69383D02*
X497267Y69050D01*
X497850Y68800D01*
X498350D01*
X498850Y68967D01*
X499183Y69217D01*
X499350Y69550D01*
X499267Y70050D01*
X498933Y70300D01*
X497433Y70800D01*
X497100Y71383D01*
X497267Y71800D01*
X497600Y72050D01*
X498100Y72133D01*
X498600Y72050D01*
X499100Y71800D01*
G01X377600Y49300D02*
X808100D01*
G01X376100Y19300D02*
Y527800D01*
G01X386100Y88800D02*
Y83800D01*
G01X384183Y88800D02*
X388017D01*
G01X390283Y83800D02*
Y88800D01*
G01Y86383D02*
X390700Y86800D01*
X391117Y87050D01*
X391783Y87133D01*
X392283Y87050D01*
X392867Y86717D01*
X393117Y86217D01*
Y83800D01*
G01X396050Y86050D02*
X398717D01*
X398467Y86633D01*
X398050Y86967D01*
X397467Y87133D01*
X396883Y87050D01*
X396383Y86800D01*
X396050Y86217D01*
X395883Y85717D01*
Y85217D01*
X396050Y84717D01*
X396467Y84217D01*
X396967Y83883D01*
X397550Y83800D01*
X398133Y83967D01*
X398717Y84467D01*
G01X408500Y83800D02*
Y88800D01*
G01X415600Y83800D02*
Y87133D01*
G01Y86550D02*
X415267Y86883D01*
X414767Y87050D01*
X414183Y87133D01*
X413600Y86967D01*
X413100Y86633D01*
X412767Y86133D01*
X412600Y85467D01*
X412767Y84800D01*
X413100Y84300D01*
X413600Y83967D01*
X414183Y83800D01*
X414767Y83883D01*
X415267Y84133D01*
X415600Y84467D01*
G01X418533Y83800D02*
Y87133D01*
G01Y86467D02*
X418950Y86800D01*
X419367Y87050D01*
X419950Y87133D01*
X420367Y87050D01*
X420867Y86800D01*
G01X424133Y82550D02*
X424717Y82217D01*
X425383Y82133D01*
X425967Y82217D01*
X426467Y82633D01*
X426800Y83217D01*
Y87133D01*
G01Y86467D02*
X426467Y86800D01*
X425967Y87050D01*
X425383Y87133D01*
X424717Y86967D01*
X424300Y86633D01*
X423967Y86050D01*
X423800Y85467D01*
X423883Y84967D01*
X424217Y84383D01*
X424717Y83967D01*
X425383Y83800D01*
X425883Y83883D01*
X426467Y84217D01*
X426800Y84550D01*
G01X429650Y86050D02*
X432317D01*
X432067Y86633D01*
X431650Y86967D01*
X431067Y87133D01*
X430483Y87050D01*
X429983Y86800D01*
X429650Y86217D01*
X429483Y85717D01*
Y85217D01*
X429650Y84717D01*
X430067Y84217D01*
X430567Y83883D01*
X431150Y83800D01*
X431733Y83967D01*
X432317Y84467D01*
G01X435250Y84383D02*
X435667Y84050D01*
X436250Y83800D01*
X436750D01*
X437250Y83967D01*
X437583Y84217D01*
X437750Y84550D01*
X437667Y85050D01*
X437333Y85300D01*
X435833Y85800D01*
X435500Y86383D01*
X435667Y86800D01*
X436000Y87050D01*
X436500Y87133D01*
X437000Y87050D01*
X437500Y86800D01*
G01X442100Y88800D02*
Y83800D01*
G01X440933Y87133D02*
X443267D01*
G01X454800Y88800D02*
Y83800D01*
G01Y84550D02*
X454467Y84133D01*
X453967Y83883D01*
X453383Y83800D01*
X452717Y83967D01*
X452217Y84383D01*
X451883Y84883D01*
X451800Y85467D01*
X451883Y86050D01*
X452217Y86550D01*
X452717Y86967D01*
X453383Y87133D01*
X453967Y87050D01*
X454383Y86883D01*
X454800Y86550D01*
G01X458900Y87133D02*
Y83800D01*
G01Y88467D02*
X458733Y88550D01*
Y88717D01*
X458900Y88800D01*
X459067Y88717D01*
Y88550D01*
X458900Y88467D01*
G01X462000Y83800D02*
Y87133D01*
G01Y86217D02*
X462250Y86633D01*
X462667Y86967D01*
X463250Y87133D01*
X463833Y86967D01*
X464250Y86633D01*
X464500Y86217D01*
Y83800D01*
G01Y86217D02*
X464750Y86633D01*
X465167Y86967D01*
X465750Y87133D01*
X466333Y86967D01*
X466750Y86633D01*
X467000Y86133D01*
Y83800D01*
G01X468850Y86050D02*
X471517D01*
X471267Y86633D01*
X470850Y86967D01*
X470267Y87133D01*
X469683Y87050D01*
X469183Y86800D01*
X468850Y86217D01*
X468683Y85717D01*
Y85217D01*
X468850Y84717D01*
X469267Y84217D01*
X469767Y83883D01*
X470350Y83800D01*
X470933Y83967D01*
X471517Y84467D01*
G01X474283Y83800D02*
Y87133D01*
G01Y86300D02*
X474617Y86717D01*
X475117Y87050D01*
X475783Y87133D01*
X476367Y87050D01*
X476867Y86717D01*
X477117Y86133D01*
Y83800D01*
G01X480050Y84383D02*
X480467Y84050D01*
X481050Y83800D01*
X481550D01*
X482050Y83967D01*
X482383Y84217D01*
X482550Y84550D01*
X482467Y85050D01*
X482133Y85300D01*
X480633Y85800D01*
X480300Y86383D01*
X480467Y86800D01*
X480800Y87050D01*
X481300Y87133D01*
X481800Y87050D01*
X482300Y86800D01*
G01X486900Y87133D02*
Y83800D01*
G01Y88467D02*
X486733Y88550D01*
Y88717D01*
X486900Y88800D01*
X487067Y88717D01*
Y88550D01*
X486900Y88467D01*
G01X492500Y83800D02*
X492000Y83883D01*
X491500Y84217D01*
X491167Y84800D01*
X491000Y85467D01*
X491167Y86133D01*
X491500Y86717D01*
X492000Y87050D01*
X492500Y87133D01*
X493000Y87050D01*
X493500Y86717D01*
X493833Y86133D01*
X493917Y85467D01*
X493833Y84800D01*
X493500Y84217D01*
X493000Y83883D01*
X492500Y83800D01*
G01X496683D02*
Y87133D01*
G01Y86300D02*
X497017Y86717D01*
X497517Y87050D01*
X498183Y87133D01*
X498767Y87050D01*
X499267Y86717D01*
X499517Y86133D01*
Y83800D01*
G01X509300D02*
X508800Y83883D01*
X508300Y84217D01*
X507967Y84800D01*
X507800Y85467D01*
X507967Y86133D01*
X508300Y86717D01*
X508800Y87050D01*
X509300Y87133D01*
X509800Y87050D01*
X510300Y86717D01*
X510633Y86133D01*
X510717Y85467D01*
X510633Y84800D01*
X510300Y84217D01*
X509800Y83883D01*
X509300Y83800D01*
G01X514400D02*
Y88050D01*
X514567Y88467D01*
X514900Y88717D01*
X515400Y88800D01*
X515900Y88633D01*
X516150Y88217D01*
G01X515150Y86800D02*
X513483D01*
G01X524600Y82133D02*
Y87133D01*
G01Y86383D02*
X525017Y86800D01*
X525433Y87050D01*
X526100Y87133D01*
X526683Y87050D01*
X527267Y86633D01*
X527517Y86050D01*
X527600Y85467D01*
X527517Y84883D01*
X527267Y84300D01*
X526767Y83967D01*
X526100Y83800D01*
X525517Y83883D01*
X524933Y84133D01*
X524600Y84467D01*
G01X533200Y83800D02*
Y87133D01*
G01Y86550D02*
X532867Y86883D01*
X532367Y87050D01*
X531783Y87133D01*
X531200Y86967D01*
X530700Y86633D01*
X530367Y86133D01*
X530200Y85467D01*
X530367Y84800D01*
X530700Y84300D01*
X531200Y83967D01*
X531783Y83800D01*
X532367Y83883D01*
X532867Y84133D01*
X533200Y84467D01*
G01X538800Y88800D02*
Y83800D01*
G01Y84550D02*
X538467Y84133D01*
X537967Y83883D01*
X537383Y83800D01*
X536717Y83967D01*
X536217Y84383D01*
X535883Y84883D01*
X535800Y85467D01*
X535883Y86050D01*
X536217Y86550D01*
X536717Y86967D01*
X537383Y87133D01*
X537967Y87050D01*
X538383Y86883D01*
X538800Y86550D01*
G01X548500Y83800D02*
X548000Y83883D01*
X547500Y84217D01*
X547167Y84800D01*
X547000Y85467D01*
X547167Y86133D01*
X547500Y86717D01*
X548000Y87050D01*
X548500Y87133D01*
X549000Y87050D01*
X549500Y86717D01*
X549833Y86133D01*
X549917Y85467D01*
X549833Y84800D01*
X549500Y84217D01*
X549000Y83883D01*
X548500Y83800D01*
G01X552933D02*
Y87133D01*
G01Y86467D02*
X553350Y86800D01*
X553767Y87050D01*
X554350Y87133D01*
X554767Y87050D01*
X555267Y86800D01*
G01X566800Y88800D02*
Y83800D01*
G01Y84550D02*
X566467Y84133D01*
X565967Y83883D01*
X565383Y83800D01*
X564717Y83967D01*
X564217Y84383D01*
X563883Y84883D01*
X563800Y85467D01*
X563883Y86050D01*
X564217Y86550D01*
X564717Y86967D01*
X565383Y87133D01*
X565967Y87050D01*
X566383Y86883D01*
X566800Y86550D01*
G01X570900Y87133D02*
Y83800D01*
G01Y88467D02*
X570733Y88550D01*
Y88717D01*
X570900Y88800D01*
X571067Y88717D01*
Y88550D01*
X570900Y88467D01*
G01X578000Y83800D02*
Y87133D01*
G01Y86550D02*
X577667Y86883D01*
X577167Y87050D01*
X576583Y87133D01*
X576000Y86967D01*
X575500Y86633D01*
X575167Y86133D01*
X575000Y85467D01*
X575167Y84800D01*
X575500Y84300D01*
X576000Y83967D01*
X576583Y83800D01*
X577167Y83883D01*
X577667Y84133D01*
X578000Y84467D01*
G01X579600Y83800D02*
Y87133D01*
G01Y86217D02*
X579850Y86633D01*
X580267Y86967D01*
X580850Y87133D01*
X581433Y86967D01*
X581850Y86633D01*
X582100Y86217D01*
Y83800D01*
G01Y86217D02*
X582350Y86633D01*
X582767Y86967D01*
X583350Y87133D01*
X583933Y86967D01*
X584350Y86633D01*
X584600Y86133D01*
Y83800D01*
G01X586450Y86050D02*
X589117D01*
X588867Y86633D01*
X588450Y86967D01*
X587867Y87133D01*
X587283Y87050D01*
X586783Y86800D01*
X586450Y86217D01*
X586283Y85717D01*
Y85217D01*
X586450Y84717D01*
X586867Y84217D01*
X587367Y83883D01*
X587950Y83800D01*
X588533Y83967D01*
X589117Y84467D01*
G01X593300Y88800D02*
Y83800D01*
G01X592133Y87133D02*
X594467D01*
G01X597650Y86050D02*
X600317D01*
X600067Y86633D01*
X599650Y86967D01*
X599067Y87133D01*
X598483Y87050D01*
X597983Y86800D01*
X597650Y86217D01*
X597483Y85717D01*
Y85217D01*
X597650Y84717D01*
X598067Y84217D01*
X598567Y83883D01*
X599150Y83800D01*
X599733Y83967D01*
X600317Y84467D01*
G01X603333Y83800D02*
Y87133D01*
G01Y86467D02*
X603750Y86800D01*
X604167Y87050D01*
X604750Y87133D01*
X605167Y87050D01*
X605667Y86800D01*
G01X617367Y83800D02*
X614033Y85467D01*
X617367Y87133D01*
G01X620217Y84717D02*
X622383D01*
G01Y86217D02*
X620217D01*
G01X632500Y83800D02*
Y88800D01*
X631500Y87800D01*
G01Y83800D02*
X633500D01*
G01X639100D02*
Y88800D01*
X636017Y85217D01*
X640183D01*
G01X646800Y83800D02*
Y87133D01*
G01Y86217D02*
X647050Y86633D01*
X647467Y86967D01*
X648050Y87133D01*
X648633Y86967D01*
X649050Y86633D01*
X649300Y86217D01*
Y83800D01*
G01Y86217D02*
X649550Y86633D01*
X649967Y86967D01*
X650550Y87133D01*
X651133Y86967D01*
X651550Y86633D01*
X651800Y86133D01*
Y83800D01*
G01X654900Y87133D02*
Y83800D01*
G01Y88467D02*
X654733Y88550D01*
Y88717D01*
X654900Y88800D01*
X655067Y88717D01*
Y88550D01*
X654900Y88467D01*
G01X660500Y83800D02*
Y88800D01*
G01X387180Y121470D02*
Y116470D01*
G01X385263Y121470D02*
X389097D01*
G01X391363Y116470D02*
Y121470D01*
G01Y119053D02*
X391780Y119470D01*
X392197Y119720D01*
X392863Y119803D01*
X393363Y119720D01*
X393947Y119387D01*
X394197Y118887D01*
Y116470D01*
G01X397130Y118720D02*
X399797D01*
X399547Y119303D01*
X399130Y119637D01*
X398547Y119803D01*
X397963Y119720D01*
X397463Y119470D01*
X397130Y118887D01*
X396963Y118387D01*
Y117887D01*
X397130Y117387D01*
X397547Y116887D01*
X398047Y116553D01*
X398630Y116470D01*
X399213Y116637D01*
X399797Y117137D01*
G01X409580Y116470D02*
Y121470D01*
G01X416680Y116470D02*
Y119803D01*
G01Y119220D02*
X416347Y119553D01*
X415847Y119720D01*
X415263Y119803D01*
X414680Y119637D01*
X414180Y119303D01*
X413847Y118803D01*
X413680Y118137D01*
X413847Y117470D01*
X414180Y116970D01*
X414680Y116637D01*
X415263Y116470D01*
X415847Y116553D01*
X416347Y116803D01*
X416680Y117137D01*
G01X419613Y116470D02*
Y119803D01*
G01Y119137D02*
X420030Y119470D01*
X420447Y119720D01*
X421030Y119803D01*
X421447Y119720D01*
X421947Y119470D01*
G01X425213Y115220D02*
X425797Y114887D01*
X426463Y114803D01*
X427047Y114887D01*
X427547Y115303D01*
X427880Y115887D01*
Y119803D01*
G01Y119137D02*
X427547Y119470D01*
X427047Y119720D01*
X426463Y119803D01*
X425797Y119637D01*
X425380Y119303D01*
X425047Y118720D01*
X424880Y118137D01*
X424963Y117637D01*
X425297Y117053D01*
X425797Y116637D01*
X426463Y116470D01*
X426963Y116553D01*
X427547Y116887D01*
X427880Y117220D01*
G01X430730Y118720D02*
X433397D01*
X433147Y119303D01*
X432730Y119637D01*
X432147Y119803D01*
X431563Y119720D01*
X431063Y119470D01*
X430730Y118887D01*
X430563Y118387D01*
Y117887D01*
X430730Y117387D01*
X431147Y116887D01*
X431647Y116553D01*
X432230Y116470D01*
X432813Y116637D01*
X433397Y117137D01*
G01X436330Y117053D02*
X436747Y116720D01*
X437330Y116470D01*
X437830D01*
X438330Y116637D01*
X438663Y116887D01*
X438830Y117220D01*
X438747Y117720D01*
X438413Y117970D01*
X436913Y118470D01*
X436580Y119053D01*
X436747Y119470D01*
X437080Y119720D01*
X437580Y119803D01*
X438080Y119720D01*
X438580Y119470D01*
G01X443180Y121470D02*
Y116470D01*
G01X442013Y119803D02*
X444347D01*
G01X455880Y121470D02*
Y116470D01*
G01Y117220D02*
X455547Y116803D01*
X455047Y116553D01*
X454463Y116470D01*
X453797Y116637D01*
X453297Y117053D01*
X452963Y117553D01*
X452880Y118137D01*
X452963Y118720D01*
X453297Y119220D01*
X453797Y119637D01*
X454463Y119803D01*
X455047Y119720D01*
X455463Y119553D01*
X455880Y119220D01*
G01X459980Y119803D02*
Y116470D01*
G01Y121137D02*
X459813Y121220D01*
Y121387D01*
X459980Y121470D01*
X460147Y121387D01*
Y121220D01*
X459980Y121137D01*
G01X463080Y116470D02*
Y119803D01*
G01Y118887D02*
X463330Y119303D01*
X463747Y119637D01*
X464330Y119803D01*
X464913Y119637D01*
X465330Y119303D01*
X465580Y118887D01*
Y116470D01*
G01Y118887D02*
X465830Y119303D01*
X466247Y119637D01*
X466830Y119803D01*
X467413Y119637D01*
X467830Y119303D01*
X468080Y118803D01*
Y116470D01*
G01X469930Y118720D02*
X472597D01*
X472347Y119303D01*
X471930Y119637D01*
X471347Y119803D01*
X470763Y119720D01*
X470263Y119470D01*
X469930Y118887D01*
X469763Y118387D01*
Y117887D01*
X469930Y117387D01*
X470347Y116887D01*
X470847Y116553D01*
X471430Y116470D01*
X472013Y116637D01*
X472597Y117137D01*
G01X475363Y116470D02*
Y119803D01*
G01Y118970D02*
X475697Y119387D01*
X476197Y119720D01*
X476863Y119803D01*
X477447Y119720D01*
X477947Y119387D01*
X478197Y118803D01*
Y116470D01*
G01X481130Y117053D02*
X481547Y116720D01*
X482130Y116470D01*
X482630D01*
X483130Y116637D01*
X483463Y116887D01*
X483630Y117220D01*
X483547Y117720D01*
X483213Y117970D01*
X481713Y118470D01*
X481380Y119053D01*
X481547Y119470D01*
X481880Y119720D01*
X482380Y119803D01*
X482880Y119720D01*
X483380Y119470D01*
G01X487980Y119803D02*
Y116470D01*
G01Y121137D02*
X487813Y121220D01*
Y121387D01*
X487980Y121470D01*
X488147Y121387D01*
Y121220D01*
X487980Y121137D01*
G01X493580Y116470D02*
X493080Y116553D01*
X492580Y116887D01*
X492247Y117470D01*
X492080Y118137D01*
X492247Y118803D01*
X492580Y119387D01*
X493080Y119720D01*
X493580Y119803D01*
X494080Y119720D01*
X494580Y119387D01*
X494913Y118803D01*
X494997Y118137D01*
X494913Y117470D01*
X494580Y116887D01*
X494080Y116553D01*
X493580Y116470D01*
G01X497763D02*
Y119803D01*
G01Y118970D02*
X498097Y119387D01*
X498597Y119720D01*
X499263Y119803D01*
X499847Y119720D01*
X500347Y119387D01*
X500597Y118803D01*
Y116470D01*
G01X510380D02*
X509880Y116553D01*
X509380Y116887D01*
X509047Y117470D01*
X508880Y118137D01*
X509047Y118803D01*
X509380Y119387D01*
X509880Y119720D01*
X510380Y119803D01*
X510880Y119720D01*
X511380Y119387D01*
X511713Y118803D01*
X511797Y118137D01*
X511713Y117470D01*
X511380Y116887D01*
X510880Y116553D01*
X510380Y116470D01*
G01X515480D02*
Y120720D01*
X515647Y121137D01*
X515980Y121387D01*
X516480Y121470D01*
X516980Y121303D01*
X517230Y120887D01*
G01X516230Y119470D02*
X514563D01*
G01X525680Y114803D02*
Y119803D01*
G01Y119053D02*
X526097Y119470D01*
X526513Y119720D01*
X527180Y119803D01*
X527763Y119720D01*
X528347Y119303D01*
X528597Y118720D01*
X528680Y118137D01*
X528597Y117553D01*
X528347Y116970D01*
X527847Y116637D01*
X527180Y116470D01*
X526597Y116553D01*
X526013Y116803D01*
X525680Y117137D01*
G01X534280Y116470D02*
Y119803D01*
G01Y119220D02*
X533947Y119553D01*
X533447Y119720D01*
X532863Y119803D01*
X532280Y119637D01*
X531780Y119303D01*
X531447Y118803D01*
X531280Y118137D01*
X531447Y117470D01*
X531780Y116970D01*
X532280Y116637D01*
X532863Y116470D01*
X533447Y116553D01*
X533947Y116803D01*
X534280Y117137D01*
G01X539880Y121470D02*
Y116470D01*
G01Y117220D02*
X539547Y116803D01*
X539047Y116553D01*
X538463Y116470D01*
X537797Y116637D01*
X537297Y117053D01*
X536963Y117553D01*
X536880Y118137D01*
X536963Y118720D01*
X537297Y119220D01*
X537797Y119637D01*
X538463Y119803D01*
X539047Y119720D01*
X539463Y119553D01*
X539880Y119220D01*
G01X549580Y116470D02*
X549080Y116553D01*
X548580Y116887D01*
X548247Y117470D01*
X548080Y118137D01*
X548247Y118803D01*
X548580Y119387D01*
X549080Y119720D01*
X549580Y119803D01*
X550080Y119720D01*
X550580Y119387D01*
X550913Y118803D01*
X550997Y118137D01*
X550913Y117470D01*
X550580Y116887D01*
X550080Y116553D01*
X549580Y116470D01*
G01X554013D02*
Y119803D01*
G01Y119137D02*
X554430Y119470D01*
X554847Y119720D01*
X555430Y119803D01*
X555847Y119720D01*
X556347Y119470D01*
G01X567880Y121470D02*
Y116470D01*
G01Y117220D02*
X567547Y116803D01*
X567047Y116553D01*
X566463Y116470D01*
X565797Y116637D01*
X565297Y117053D01*
X564963Y117553D01*
X564880Y118137D01*
X564963Y118720D01*
X565297Y119220D01*
X565797Y119637D01*
X566463Y119803D01*
X567047Y119720D01*
X567463Y119553D01*
X567880Y119220D01*
G01X571980Y119803D02*
Y116470D01*
G01Y121137D02*
X571813Y121220D01*
Y121387D01*
X571980Y121470D01*
X572147Y121387D01*
Y121220D01*
X571980Y121137D01*
G01X579080Y116470D02*
Y119803D01*
G01Y119220D02*
X578747Y119553D01*
X578247Y119720D01*
X577663Y119803D01*
X577080Y119637D01*
X576580Y119303D01*
X576247Y118803D01*
X576080Y118137D01*
X576247Y117470D01*
X576580Y116970D01*
X577080Y116637D01*
X577663Y116470D01*
X578247Y116553D01*
X578747Y116803D01*
X579080Y117137D01*
G01X580680Y116470D02*
Y119803D01*
G01Y118887D02*
X580930Y119303D01*
X581347Y119637D01*
X581930Y119803D01*
X582513Y119637D01*
X582930Y119303D01*
X583180Y118887D01*
Y116470D01*
G01Y118887D02*
X583430Y119303D01*
X583847Y119637D01*
X584430Y119803D01*
X585013Y119637D01*
X585430Y119303D01*
X585680Y118803D01*
Y116470D01*
G01X587530Y118720D02*
X590197D01*
X589947Y119303D01*
X589530Y119637D01*
X588947Y119803D01*
X588363Y119720D01*
X587863Y119470D01*
X587530Y118887D01*
X587363Y118387D01*
Y117887D01*
X587530Y117387D01*
X587947Y116887D01*
X588447Y116553D01*
X589030Y116470D01*
X589613Y116637D01*
X590197Y117137D01*
G01X594380Y121470D02*
Y116470D01*
G01X593213Y119803D02*
X595547D01*
G01X598730Y118720D02*
X601397D01*
X601147Y119303D01*
X600730Y119637D01*
X600147Y119803D01*
X599563Y119720D01*
X599063Y119470D01*
X598730Y118887D01*
X598563Y118387D01*
Y117887D01*
X598730Y117387D01*
X599147Y116887D01*
X599647Y116553D01*
X600230Y116470D01*
X600813Y116637D01*
X601397Y117137D01*
G01X604413Y116470D02*
Y119803D01*
G01Y119137D02*
X604830Y119470D01*
X605247Y119720D01*
X605830Y119803D01*
X606247Y119720D01*
X606747Y119470D01*
G01X618447Y116470D02*
X615113Y118137D01*
X618447Y119803D01*
G01X621297Y117387D02*
X623463D01*
G01Y118887D02*
X621297D01*
G01X633580Y116470D02*
Y121470D01*
X632580Y120470D01*
G01Y116470D02*
X634580D01*
G01X640180D02*
Y121470D01*
X637097Y117887D01*
X641263D01*
G01X647880Y116470D02*
Y119803D01*
G01Y118887D02*
X648130Y119303D01*
X648547Y119637D01*
X649130Y119803D01*
X649713Y119637D01*
X650130Y119303D01*
X650380Y118887D01*
Y116470D01*
G01Y118887D02*
X650630Y119303D01*
X651047Y119637D01*
X651630Y119803D01*
X652213Y119637D01*
X652630Y119303D01*
X652880Y118803D01*
Y116470D01*
G01X655980Y119803D02*
Y116470D01*
G01Y121137D02*
X655813Y121220D01*
Y121387D01*
X655980Y121470D01*
X656147Y121387D01*
Y121220D01*
X655980Y121137D01*
G01X661580Y116470D02*
Y121470D01*
G01X386100Y103800D02*
Y98800D01*
G01X384183Y103800D02*
X388017D01*
G01X390283Y98800D02*
Y103800D01*
G01Y101383D02*
X390700Y101800D01*
X391117Y102050D01*
X391783Y102133D01*
X392283Y102050D01*
X392867Y101717D01*
X393117Y101217D01*
Y98800D01*
G01X396050Y101050D02*
X398717D01*
X398467Y101633D01*
X398050Y101967D01*
X397467Y102133D01*
X396883Y102050D01*
X396383Y101800D01*
X396050Y101217D01*
X395883Y100717D01*
Y100217D01*
X396050Y99717D01*
X396467Y99217D01*
X396967Y98883D01*
X397550Y98800D01*
X398133Y98967D01*
X398717Y99467D01*
G01X408500Y98800D02*
Y103800D01*
G01X415600Y98800D02*
Y102133D01*
G01Y101550D02*
X415267Y101883D01*
X414767Y102050D01*
X414183Y102133D01*
X413600Y101967D01*
X413100Y101633D01*
X412767Y101133D01*
X412600Y100467D01*
X412767Y99800D01*
X413100Y99300D01*
X413600Y98967D01*
X414183Y98800D01*
X414767Y98883D01*
X415267Y99133D01*
X415600Y99467D01*
G01X418533Y98800D02*
Y102133D01*
G01Y101467D02*
X418950Y101800D01*
X419367Y102050D01*
X419950Y102133D01*
X420367Y102050D01*
X420867Y101800D01*
G01X424133Y97550D02*
X424717Y97217D01*
X425383Y97133D01*
X425967Y97217D01*
X426467Y97633D01*
X426800Y98217D01*
Y102133D01*
G01Y101467D02*
X426467Y101800D01*
X425967Y102050D01*
X425383Y102133D01*
X424717Y101967D01*
X424300Y101633D01*
X423967Y101050D01*
X423800Y100467D01*
X423883Y99967D01*
X424217Y99383D01*
X424717Y98967D01*
X425383Y98800D01*
X425883Y98883D01*
X426467Y99217D01*
X426800Y99550D01*
G01X429650Y101050D02*
X432317D01*
X432067Y101633D01*
X431650Y101967D01*
X431067Y102133D01*
X430483Y102050D01*
X429983Y101800D01*
X429650Y101217D01*
X429483Y100717D01*
Y100217D01*
X429650Y99717D01*
X430067Y99217D01*
X430567Y98883D01*
X431150Y98800D01*
X431733Y98967D01*
X432317Y99467D01*
G01X435250Y99383D02*
X435667Y99050D01*
X436250Y98800D01*
X436750D01*
X437250Y98967D01*
X437583Y99217D01*
X437750Y99550D01*
X437667Y100050D01*
X437333Y100300D01*
X435833Y100800D01*
X435500Y101383D01*
X435667Y101800D01*
X436000Y102050D01*
X436500Y102133D01*
X437000Y102050D01*
X437500Y101800D01*
G01X442100Y103800D02*
Y98800D01*
G01X440933Y102133D02*
X443267D01*
G01X454800Y103800D02*
Y98800D01*
G01Y99550D02*
X454467Y99133D01*
X453967Y98883D01*
X453383Y98800D01*
X452717Y98967D01*
X452217Y99383D01*
X451883Y99883D01*
X451800Y100467D01*
X451883Y101050D01*
X452217Y101550D01*
X452717Y101967D01*
X453383Y102133D01*
X453967Y102050D01*
X454383Y101883D01*
X454800Y101550D01*
G01X458900Y102133D02*
Y98800D01*
G01Y103467D02*
X458733Y103550D01*
Y103717D01*
X458900Y103800D01*
X459067Y103717D01*
Y103550D01*
X458900Y103467D01*
G01X462000Y98800D02*
Y102133D01*
G01Y101217D02*
X462250Y101633D01*
X462667Y101967D01*
X463250Y102133D01*
X463833Y101967D01*
X464250Y101633D01*
X464500Y101217D01*
Y98800D01*
G01Y101217D02*
X464750Y101633D01*
X465167Y101967D01*
X465750Y102133D01*
X466333Y101967D01*
X466750Y101633D01*
X467000Y101133D01*
Y98800D01*
G01X468850Y101050D02*
X471517D01*
X471267Y101633D01*
X470850Y101967D01*
X470267Y102133D01*
X469683Y102050D01*
X469183Y101800D01*
X468850Y101217D01*
X468683Y100717D01*
Y100217D01*
X468850Y99717D01*
X469267Y99217D01*
X469767Y98883D01*
X470350Y98800D01*
X470933Y98967D01*
X471517Y99467D01*
G01X474283Y98800D02*
Y102133D01*
G01Y101300D02*
X474617Y101717D01*
X475117Y102050D01*
X475783Y102133D01*
X476367Y102050D01*
X476867Y101717D01*
X477117Y101133D01*
Y98800D01*
G01X480050Y99383D02*
X480467Y99050D01*
X481050Y98800D01*
X481550D01*
X482050Y98967D01*
X482383Y99217D01*
X482550Y99550D01*
X482467Y100050D01*
X482133Y100300D01*
X480633Y100800D01*
X480300Y101383D01*
X480467Y101800D01*
X480800Y102050D01*
X481300Y102133D01*
X481800Y102050D01*
X482300Y101800D01*
G01X486900Y102133D02*
Y98800D01*
G01Y103467D02*
X486733Y103550D01*
Y103717D01*
X486900Y103800D01*
X487067Y103717D01*
Y103550D01*
X486900Y103467D01*
G01X492500Y98800D02*
X492000Y98883D01*
X491500Y99217D01*
X491167Y99800D01*
X491000Y100467D01*
X491167Y101133D01*
X491500Y101717D01*
X492000Y102050D01*
X492500Y102133D01*
X493000Y102050D01*
X493500Y101717D01*
X493833Y101133D01*
X493917Y100467D01*
X493833Y99800D01*
X493500Y99217D01*
X493000Y98883D01*
X492500Y98800D01*
G01X496683D02*
Y102133D01*
G01Y101300D02*
X497017Y101717D01*
X497517Y102050D01*
X498183Y102133D01*
X498767Y102050D01*
X499267Y101717D01*
X499517Y101133D01*
Y98800D01*
G01X509300D02*
X508800Y98883D01*
X508300Y99217D01*
X507967Y99800D01*
X507800Y100467D01*
X507967Y101133D01*
X508300Y101717D01*
X508800Y102050D01*
X509300Y102133D01*
X509800Y102050D01*
X510300Y101717D01*
X510633Y101133D01*
X510717Y100467D01*
X510633Y99800D01*
X510300Y99217D01*
X509800Y98883D01*
X509300Y98800D01*
G01X514400D02*
Y103050D01*
X514567Y103467D01*
X514900Y103717D01*
X515400Y103800D01*
X515900Y103633D01*
X516150Y103217D01*
G01X515150Y101800D02*
X513483D01*
G01X524600Y97133D02*
Y102133D01*
G01Y101383D02*
X525017Y101800D01*
X525433Y102050D01*
X526100Y102133D01*
X526683Y102050D01*
X527267Y101633D01*
X527517Y101050D01*
X527600Y100467D01*
X527517Y99883D01*
X527267Y99300D01*
X526767Y98967D01*
X526100Y98800D01*
X525517Y98883D01*
X524933Y99133D01*
X524600Y99467D01*
G01X533200Y98800D02*
Y102133D01*
G01Y101550D02*
X532867Y101883D01*
X532367Y102050D01*
X531783Y102133D01*
X531200Y101967D01*
X530700Y101633D01*
X530367Y101133D01*
X530200Y100467D01*
X530367Y99800D01*
X530700Y99300D01*
X531200Y98967D01*
X531783Y98800D01*
X532367Y98883D01*
X532867Y99133D01*
X533200Y99467D01*
G01X538800Y103800D02*
Y98800D01*
G01Y99550D02*
X538467Y99133D01*
X537967Y98883D01*
X537383Y98800D01*
X536717Y98967D01*
X536217Y99383D01*
X535883Y99883D01*
X535800Y100467D01*
X535883Y101050D01*
X536217Y101550D01*
X536717Y101967D01*
X537383Y102133D01*
X537967Y102050D01*
X538383Y101883D01*
X538800Y101550D01*
G01X548500Y98800D02*
X548000Y98883D01*
X547500Y99217D01*
X547167Y99800D01*
X547000Y100467D01*
X547167Y101133D01*
X547500Y101717D01*
X548000Y102050D01*
X548500Y102133D01*
X549000Y102050D01*
X549500Y101717D01*
X549833Y101133D01*
X549917Y100467D01*
X549833Y99800D01*
X549500Y99217D01*
X549000Y98883D01*
X548500Y98800D01*
G01X552933D02*
Y102133D01*
G01Y101467D02*
X553350Y101800D01*
X553767Y102050D01*
X554350Y102133D01*
X554767Y102050D01*
X555267Y101800D01*
G01X566800Y103800D02*
Y98800D01*
G01Y99550D02*
X566467Y99133D01*
X565967Y98883D01*
X565383Y98800D01*
X564717Y98967D01*
X564217Y99383D01*
X563883Y99883D01*
X563800Y100467D01*
X563883Y101050D01*
X564217Y101550D01*
X564717Y101967D01*
X565383Y102133D01*
X565967Y102050D01*
X566383Y101883D01*
X566800Y101550D01*
G01X570900Y102133D02*
Y98800D01*
G01Y103467D02*
X570733Y103550D01*
Y103717D01*
X570900Y103800D01*
X571067Y103717D01*
Y103550D01*
X570900Y103467D01*
G01X578000Y98800D02*
Y102133D01*
G01Y101550D02*
X577667Y101883D01*
X577167Y102050D01*
X576583Y102133D01*
X576000Y101967D01*
X575500Y101633D01*
X575167Y101133D01*
X575000Y100467D01*
X575167Y99800D01*
X575500Y99300D01*
X576000Y98967D01*
X576583Y98800D01*
X577167Y98883D01*
X577667Y99133D01*
X578000Y99467D01*
G01X579600Y98800D02*
Y102133D01*
G01Y101217D02*
X579850Y101633D01*
X580267Y101967D01*
X580850Y102133D01*
X581433Y101967D01*
X581850Y101633D01*
X582100Y101217D01*
Y98800D01*
G01Y101217D02*
X582350Y101633D01*
X582767Y101967D01*
X583350Y102133D01*
X583933Y101967D01*
X584350Y101633D01*
X584600Y101133D01*
Y98800D01*
G01X586450Y101050D02*
X589117D01*
X588867Y101633D01*
X588450Y101967D01*
X587867Y102133D01*
X587283Y102050D01*
X586783Y101800D01*
X586450Y101217D01*
X586283Y100717D01*
Y100217D01*
X586450Y99717D01*
X586867Y99217D01*
X587367Y98883D01*
X587950Y98800D01*
X588533Y98967D01*
X589117Y99467D01*
G01X593300Y103800D02*
Y98800D01*
G01X592133Y102133D02*
X594467D01*
G01X597650Y101050D02*
X600317D01*
X600067Y101633D01*
X599650Y101967D01*
X599067Y102133D01*
X598483Y102050D01*
X597983Y101800D01*
X597650Y101217D01*
X597483Y100717D01*
Y100217D01*
X597650Y99717D01*
X598067Y99217D01*
X598567Y98883D01*
X599150Y98800D01*
X599733Y98967D01*
X600317Y99467D01*
G01X603333Y98800D02*
Y102133D01*
G01Y101467D02*
X603750Y101800D01*
X604167Y102050D01*
X604750Y102133D01*
X605167Y102050D01*
X605667Y101800D01*
G01X614033Y98800D02*
X617367Y100467D01*
X614033Y102133D01*
G01X621300Y98800D02*
Y103800D01*
X620300Y102800D01*
G01Y98800D02*
X622300D01*
G01X627900D02*
Y103800D01*
X624817Y100217D01*
X628983D01*
G01X635600Y98800D02*
Y102133D01*
G01Y101217D02*
X635850Y101633D01*
X636267Y101967D01*
X636850Y102133D01*
X637433Y101967D01*
X637850Y101633D01*
X638100Y101217D01*
Y98800D01*
G01Y101217D02*
X638350Y101633D01*
X638767Y101967D01*
X639350Y102133D01*
X639933Y101967D01*
X640350Y101633D01*
X640600Y101133D01*
Y98800D01*
G01X643700Y102133D02*
Y98800D01*
G01Y103467D02*
X643533Y103550D01*
Y103717D01*
X643700Y103800D01*
X643867Y103717D01*
Y103550D01*
X643700Y103467D01*
G01X649300Y98800D02*
Y103800D01*
G01X377600Y94300D02*
X808100D01*
G01X386100Y160300D02*
Y155300D01*
G01X384933Y158633D02*
X387267D01*
G01X390533Y155300D02*
Y158633D01*
G01Y157967D02*
X390950Y158300D01*
X391367Y158550D01*
X391950Y158633D01*
X392367Y158550D01*
X392867Y158300D01*
G01X398800Y155300D02*
Y158633D01*
G01Y158050D02*
X398467Y158383D01*
X397967Y158550D01*
X397383Y158633D01*
X396800Y158467D01*
X396300Y158133D01*
X395967Y157633D01*
X395800Y156967D01*
X395967Y156300D01*
X396300Y155800D01*
X396800Y155467D01*
X397383Y155300D01*
X397967Y155383D01*
X398467Y155633D01*
X398800Y155967D01*
G01X404233Y158217D02*
X403650Y158550D01*
X403150Y158633D01*
X402483Y158467D01*
X401983Y158133D01*
X401650Y157550D01*
X401567Y156967D01*
X401650Y156383D01*
X401983Y155883D01*
X402483Y155467D01*
X403150Y155300D01*
X403733Y155467D01*
X404233Y155800D01*
G01X407250Y157550D02*
X409917D01*
X409667Y158133D01*
X409250Y158467D01*
X408667Y158633D01*
X408083Y158550D01*
X407583Y158300D01*
X407250Y157717D01*
X407083Y157217D01*
Y156717D01*
X407250Y156217D01*
X407667Y155717D01*
X408167Y155383D01*
X408750Y155300D01*
X409333Y155467D01*
X409917Y155967D01*
G01X417617Y158633D02*
X418617Y155300D01*
X419700Y158633D01*
X420783Y155300D01*
X421783Y158633D01*
G01X425300D02*
Y155300D01*
G01Y159967D02*
X425133Y160050D01*
Y160217D01*
X425300Y160300D01*
X425467Y160217D01*
Y160050D01*
X425300Y159967D01*
G01X432400Y160300D02*
Y155300D01*
G01Y156050D02*
X432067Y155633D01*
X431567Y155383D01*
X430983Y155300D01*
X430317Y155467D01*
X429817Y155883D01*
X429483Y156383D01*
X429400Y156967D01*
X429483Y157550D01*
X429817Y158050D01*
X430317Y158467D01*
X430983Y158633D01*
X431567Y158550D01*
X431983Y158383D01*
X432400Y158050D01*
G01X436500Y160300D02*
Y155300D01*
G01X435333Y158633D02*
X437667D01*
G01X440683Y155300D02*
Y160300D01*
G01Y157883D02*
X441100Y158300D01*
X441517Y158550D01*
X442183Y158633D01*
X442683Y158550D01*
X443267Y158217D01*
X443517Y157717D01*
Y155300D01*
G01X451633D02*
X454967Y156967D01*
X451633Y158633D01*
G01X464333Y155300D02*
X464500Y156383D01*
X464750Y157300D01*
X465083Y158133D01*
X465500Y159050D01*
X466167Y160300D01*
X462833D01*
G01X473200Y155300D02*
Y158633D01*
G01Y157717D02*
X473450Y158133D01*
X473867Y158467D01*
X474450Y158633D01*
X475033Y158467D01*
X475450Y158133D01*
X475700Y157717D01*
Y155300D01*
G01Y157717D02*
X475950Y158133D01*
X476367Y158467D01*
X476950Y158633D01*
X477533Y158467D01*
X477950Y158133D01*
X478200Y157633D01*
Y155300D01*
G01X481300Y158633D02*
Y155300D01*
G01Y159967D02*
X481133Y160050D01*
Y160217D01*
X481300Y160300D01*
X481467Y160217D01*
Y160050D01*
X481300Y159967D01*
G01X486900Y155300D02*
Y160300D01*
G01X386100Y140800D02*
Y135800D01*
G01X384183Y140800D02*
X388017D01*
G01X390283Y135800D02*
Y140800D01*
G01Y138383D02*
X390700Y138800D01*
X391117Y139050D01*
X391783Y139133D01*
X392283Y139050D01*
X392867Y138717D01*
X393117Y138217D01*
Y135800D01*
G01X396050Y138050D02*
X398717D01*
X398467Y138633D01*
X398050Y138967D01*
X397467Y139133D01*
X396883Y139050D01*
X396383Y138800D01*
X396050Y138217D01*
X395883Y137717D01*
Y137217D01*
X396050Y136717D01*
X396467Y136217D01*
X396967Y135883D01*
X397550Y135800D01*
X398133Y135967D01*
X398717Y136467D01*
G01X408500Y135800D02*
Y140800D01*
G01X415600Y135800D02*
Y139133D01*
G01Y138550D02*
X415267Y138883D01*
X414767Y139050D01*
X414183Y139133D01*
X413600Y138967D01*
X413100Y138633D01*
X412767Y138133D01*
X412600Y137467D01*
X412767Y136800D01*
X413100Y136300D01*
X413600Y135967D01*
X414183Y135800D01*
X414767Y135883D01*
X415267Y136133D01*
X415600Y136467D01*
G01X418533Y135800D02*
Y139133D01*
G01Y138467D02*
X418950Y138800D01*
X419367Y139050D01*
X419950Y139133D01*
X420367Y139050D01*
X420867Y138800D01*
G01X424133Y134550D02*
X424717Y134217D01*
X425383Y134133D01*
X425967Y134217D01*
X426467Y134633D01*
X426800Y135217D01*
Y139133D01*
G01Y138467D02*
X426467Y138800D01*
X425967Y139050D01*
X425383Y139133D01*
X424717Y138967D01*
X424300Y138633D01*
X423967Y138050D01*
X423800Y137467D01*
X423883Y136967D01*
X424217Y136383D01*
X424717Y135967D01*
X425383Y135800D01*
X425883Y135883D01*
X426467Y136217D01*
X426800Y136550D01*
G01X429650Y138050D02*
X432317D01*
X432067Y138633D01*
X431650Y138967D01*
X431067Y139133D01*
X430483Y139050D01*
X429983Y138800D01*
X429650Y138217D01*
X429483Y137717D01*
Y137217D01*
X429650Y136717D01*
X430067Y136217D01*
X430567Y135883D01*
X431150Y135800D01*
X431733Y135967D01*
X432317Y136467D01*
G01X435250Y136383D02*
X435667Y136050D01*
X436250Y135800D01*
X436750D01*
X437250Y135967D01*
X437583Y136217D01*
X437750Y136550D01*
X437667Y137050D01*
X437333Y137300D01*
X435833Y137800D01*
X435500Y138383D01*
X435667Y138800D01*
X436000Y139050D01*
X436500Y139133D01*
X437000Y139050D01*
X437500Y138800D01*
G01X442100Y140800D02*
Y135800D01*
G01X440933Y139133D02*
X443267D01*
G01X454800Y140800D02*
Y135800D01*
G01Y136550D02*
X454467Y136133D01*
X453967Y135883D01*
X453383Y135800D01*
X452717Y135967D01*
X452217Y136383D01*
X451883Y136883D01*
X451800Y137467D01*
X451883Y138050D01*
X452217Y138550D01*
X452717Y138967D01*
X453383Y139133D01*
X453967Y139050D01*
X454383Y138883D01*
X454800Y138550D01*
G01X458900Y139133D02*
Y135800D01*
G01Y140467D02*
X458733Y140550D01*
Y140717D01*
X458900Y140800D01*
X459067Y140717D01*
Y140550D01*
X458900Y140467D01*
G01X462000Y135800D02*
Y139133D01*
G01Y138217D02*
X462250Y138633D01*
X462667Y138967D01*
X463250Y139133D01*
X463833Y138967D01*
X464250Y138633D01*
X464500Y138217D01*
Y135800D01*
G01Y138217D02*
X464750Y138633D01*
X465167Y138967D01*
X465750Y139133D01*
X466333Y138967D01*
X466750Y138633D01*
X467000Y138133D01*
Y135800D01*
G01X468850Y138050D02*
X471517D01*
X471267Y138633D01*
X470850Y138967D01*
X470267Y139133D01*
X469683Y139050D01*
X469183Y138800D01*
X468850Y138217D01*
X468683Y137717D01*
Y137217D01*
X468850Y136717D01*
X469267Y136217D01*
X469767Y135883D01*
X470350Y135800D01*
X470933Y135967D01*
X471517Y136467D01*
G01X474283Y135800D02*
Y139133D01*
G01Y138300D02*
X474617Y138717D01*
X475117Y139050D01*
X475783Y139133D01*
X476367Y139050D01*
X476867Y138717D01*
X477117Y138133D01*
Y135800D01*
G01X480050Y136383D02*
X480467Y136050D01*
X481050Y135800D01*
X481550D01*
X482050Y135967D01*
X482383Y136217D01*
X482550Y136550D01*
X482467Y137050D01*
X482133Y137300D01*
X480633Y137800D01*
X480300Y138383D01*
X480467Y138800D01*
X480800Y139050D01*
X481300Y139133D01*
X481800Y139050D01*
X482300Y138800D01*
G01X486900Y139133D02*
Y135800D01*
G01Y140467D02*
X486733Y140550D01*
Y140717D01*
X486900Y140800D01*
X487067Y140717D01*
Y140550D01*
X486900Y140467D01*
G01X492500Y135800D02*
X492000Y135883D01*
X491500Y136217D01*
X491167Y136800D01*
X491000Y137467D01*
X491167Y138133D01*
X491500Y138717D01*
X492000Y139050D01*
X492500Y139133D01*
X493000Y139050D01*
X493500Y138717D01*
X493833Y138133D01*
X493917Y137467D01*
X493833Y136800D01*
X493500Y136217D01*
X493000Y135883D01*
X492500Y135800D01*
G01X496683D02*
Y139133D01*
G01Y138300D02*
X497017Y138717D01*
X497517Y139050D01*
X498183Y139133D01*
X498767Y139050D01*
X499267Y138717D01*
X499517Y138133D01*
Y135800D01*
G01X509300D02*
X508800Y135883D01*
X508300Y136217D01*
X507967Y136800D01*
X507800Y137467D01*
X507967Y138133D01*
X508300Y138717D01*
X508800Y139050D01*
X509300Y139133D01*
X509800Y139050D01*
X510300Y138717D01*
X510633Y138133D01*
X510717Y137467D01*
X510633Y136800D01*
X510300Y136217D01*
X509800Y135883D01*
X509300Y135800D01*
G01X514400D02*
Y140050D01*
X514567Y140467D01*
X514900Y140717D01*
X515400Y140800D01*
X515900Y140633D01*
X516150Y140217D01*
G01X515150Y138800D02*
X513483D01*
G01X524600Y134133D02*
Y139133D01*
G01Y138383D02*
X525017Y138800D01*
X525433Y139050D01*
X526100Y139133D01*
X526683Y139050D01*
X527267Y138633D01*
X527517Y138050D01*
X527600Y137467D01*
X527517Y136883D01*
X527267Y136300D01*
X526767Y135967D01*
X526100Y135800D01*
X525517Y135883D01*
X524933Y136133D01*
X524600Y136467D01*
G01X533200Y135800D02*
Y139133D01*
G01Y138550D02*
X532867Y138883D01*
X532367Y139050D01*
X531783Y139133D01*
X531200Y138967D01*
X530700Y138633D01*
X530367Y138133D01*
X530200Y137467D01*
X530367Y136800D01*
X530700Y136300D01*
X531200Y135967D01*
X531783Y135800D01*
X532367Y135883D01*
X532867Y136133D01*
X533200Y136467D01*
G01X538800Y140800D02*
Y135800D01*
G01Y136550D02*
X538467Y136133D01*
X537967Y135883D01*
X537383Y135800D01*
X536717Y135967D01*
X536217Y136383D01*
X535883Y136883D01*
X535800Y137467D01*
X535883Y138050D01*
X536217Y138550D01*
X536717Y138967D01*
X537383Y139133D01*
X537967Y139050D01*
X538383Y138883D01*
X538800Y138550D01*
G01X548500Y135800D02*
X548000Y135883D01*
X547500Y136217D01*
X547167Y136800D01*
X547000Y137467D01*
X547167Y138133D01*
X547500Y138717D01*
X548000Y139050D01*
X548500Y139133D01*
X549000Y139050D01*
X549500Y138717D01*
X549833Y138133D01*
X549917Y137467D01*
X549833Y136800D01*
X549500Y136217D01*
X549000Y135883D01*
X548500Y135800D01*
G01X552933D02*
Y139133D01*
G01Y138467D02*
X553350Y138800D01*
X553767Y139050D01*
X554350Y139133D01*
X554767Y139050D01*
X555267Y138800D01*
G01X566800Y140800D02*
Y135800D01*
G01Y136550D02*
X566467Y136133D01*
X565967Y135883D01*
X565383Y135800D01*
X564717Y135967D01*
X564217Y136383D01*
X563883Y136883D01*
X563800Y137467D01*
X563883Y138050D01*
X564217Y138550D01*
X564717Y138967D01*
X565383Y139133D01*
X565967Y139050D01*
X566383Y138883D01*
X566800Y138550D01*
G01X570900Y139133D02*
Y135800D01*
G01Y140467D02*
X570733Y140550D01*
Y140717D01*
X570900Y140800D01*
X571067Y140717D01*
Y140550D01*
X570900Y140467D01*
G01X578000Y135800D02*
Y139133D01*
G01Y138550D02*
X577667Y138883D01*
X577167Y139050D01*
X576583Y139133D01*
X576000Y138967D01*
X575500Y138633D01*
X575167Y138133D01*
X575000Y137467D01*
X575167Y136800D01*
X575500Y136300D01*
X576000Y135967D01*
X576583Y135800D01*
X577167Y135883D01*
X577667Y136133D01*
X578000Y136467D01*
G01X579600Y135800D02*
Y139133D01*
G01Y138217D02*
X579850Y138633D01*
X580267Y138967D01*
X580850Y139133D01*
X581433Y138967D01*
X581850Y138633D01*
X582100Y138217D01*
Y135800D01*
G01Y138217D02*
X582350Y138633D01*
X582767Y138967D01*
X583350Y139133D01*
X583933Y138967D01*
X584350Y138633D01*
X584600Y138133D01*
Y135800D01*
G01X586450Y138050D02*
X589117D01*
X588867Y138633D01*
X588450Y138967D01*
X587867Y139133D01*
X587283Y139050D01*
X586783Y138800D01*
X586450Y138217D01*
X586283Y137717D01*
Y137217D01*
X586450Y136717D01*
X586867Y136217D01*
X587367Y135883D01*
X587950Y135800D01*
X588533Y135967D01*
X589117Y136467D01*
G01X593300Y140800D02*
Y135800D01*
G01X592133Y139133D02*
X594467D01*
G01X597650Y138050D02*
X600317D01*
X600067Y138633D01*
X599650Y138967D01*
X599067Y139133D01*
X598483Y139050D01*
X597983Y138800D01*
X597650Y138217D01*
X597483Y137717D01*
Y137217D01*
X597650Y136717D01*
X598067Y136217D01*
X598567Y135883D01*
X599150Y135800D01*
X599733Y135967D01*
X600317Y136467D01*
G01X603333Y135800D02*
Y139133D01*
G01Y138467D02*
X603750Y138800D01*
X604167Y139050D01*
X604750Y139133D01*
X605167Y139050D01*
X605667Y138800D01*
G01X614033Y135800D02*
X617367Y137467D01*
X614033Y139133D01*
G01X626900Y135800D02*
Y140800D01*
X625900Y139800D01*
G01Y135800D02*
X627900D01*
G01X633500D02*
Y140800D01*
X630417Y137217D01*
X634583D01*
G01X641200Y135800D02*
Y139133D01*
G01Y138217D02*
X641450Y138633D01*
X641867Y138967D01*
X642450Y139133D01*
X643033Y138967D01*
X643450Y138633D01*
X643700Y138217D01*
Y135800D01*
G01Y138217D02*
X643950Y138633D01*
X644367Y138967D01*
X644950Y139133D01*
X645533Y138967D01*
X645950Y138633D01*
X646200Y138133D01*
Y135800D01*
G01X649300Y139133D02*
Y135800D01*
G01Y140467D02*
X649133Y140550D01*
Y140717D01*
X649300Y140800D01*
X649467Y140717D01*
Y140550D01*
X649300Y140467D01*
G01X654900Y135800D02*
Y140800D01*
G01X377600Y129300D02*
X808100D01*
G01X386100Y190300D02*
Y185300D01*
G01X384933Y188633D02*
X387267D01*
G01X390533Y185300D02*
Y188633D01*
G01Y187967D02*
X390950Y188300D01*
X391367Y188550D01*
X391950Y188633D01*
X392367Y188550D01*
X392867Y188300D01*
G01X398800Y185300D02*
Y188633D01*
G01Y188050D02*
X398467Y188383D01*
X397967Y188550D01*
X397383Y188633D01*
X396800Y188467D01*
X396300Y188133D01*
X395967Y187633D01*
X395800Y186967D01*
X395967Y186300D01*
X396300Y185800D01*
X396800Y185467D01*
X397383Y185300D01*
X397967Y185383D01*
X398467Y185633D01*
X398800Y185967D01*
G01X404233Y188217D02*
X403650Y188550D01*
X403150Y188633D01*
X402483Y188467D01*
X401983Y188133D01*
X401650Y187550D01*
X401567Y186967D01*
X401650Y186383D01*
X401983Y185883D01*
X402483Y185467D01*
X403150Y185300D01*
X403733Y185467D01*
X404233Y185800D01*
G01X407250Y187550D02*
X409917D01*
X409667Y188133D01*
X409250Y188467D01*
X408667Y188633D01*
X408083Y188550D01*
X407583Y188300D01*
X407250Y187717D01*
X407083Y187217D01*
Y186717D01*
X407250Y186217D01*
X407667Y185717D01*
X408167Y185383D01*
X408750Y185300D01*
X409333Y185467D01*
X409917Y185967D01*
G01X417617Y188633D02*
X418617Y185300D01*
X419700Y188633D01*
X420783Y185300D01*
X421783Y188633D01*
G01X425300D02*
Y185300D01*
G01Y189967D02*
X425133Y190050D01*
Y190217D01*
X425300Y190300D01*
X425467Y190217D01*
Y190050D01*
X425300Y189967D01*
G01X432400Y190300D02*
Y185300D01*
G01Y186050D02*
X432067Y185633D01*
X431567Y185383D01*
X430983Y185300D01*
X430317Y185467D01*
X429817Y185883D01*
X429483Y186383D01*
X429400Y186967D01*
X429483Y187550D01*
X429817Y188050D01*
X430317Y188467D01*
X430983Y188633D01*
X431567Y188550D01*
X431983Y188383D01*
X432400Y188050D01*
G01X436500Y190300D02*
Y185300D01*
G01X435333Y188633D02*
X437667D01*
G01X440683Y185300D02*
Y190300D01*
G01Y187883D02*
X441100Y188300D01*
X441517Y188550D01*
X442183Y188633D01*
X442683Y188550D01*
X443267Y188217D01*
X443517Y187717D01*
Y185300D01*
G01X454967D02*
X451633Y186967D01*
X454967Y188633D01*
G01X457817Y186217D02*
X459983D01*
G01Y187717D02*
X457817D01*
G01X468267Y186050D02*
X468767Y185633D01*
X469350Y185383D01*
X470100Y185300D01*
X470850Y185467D01*
X471433Y185800D01*
X471850Y186383D01*
X471933Y187050D01*
X471767Y187717D01*
X471350Y188133D01*
X470767Y188467D01*
X470183Y188550D01*
X469600Y188467D01*
X468850Y188133D01*
X469100Y190300D01*
X471350D01*
G01X478800Y185300D02*
Y188633D01*
G01Y187717D02*
X479050Y188133D01*
X479467Y188467D01*
X480050Y188633D01*
X480633Y188467D01*
X481050Y188133D01*
X481300Y187717D01*
Y185300D01*
G01Y187717D02*
X481550Y188133D01*
X481967Y188467D01*
X482550Y188633D01*
X483133Y188467D01*
X483550Y188133D01*
X483800Y187633D01*
Y185300D01*
G01X486900Y188633D02*
Y185300D01*
G01Y189967D02*
X486733Y190050D01*
Y190217D01*
X486900Y190300D01*
X487067Y190217D01*
Y190050D01*
X486900Y189967D01*
G01X492500Y185300D02*
Y190300D01*
G01X384267Y171050D02*
X384767Y170633D01*
X385350Y170383D01*
X386100Y170300D01*
X386850Y170467D01*
X387433Y170800D01*
X387850Y171383D01*
X387933Y172050D01*
X387767Y172717D01*
X387350Y173133D01*
X386767Y173467D01*
X386183Y173550D01*
X385600Y173467D01*
X384850Y173133D01*
X385100Y175300D01*
X387350D01*
G01X394800Y170300D02*
Y173633D01*
G01Y172717D02*
X395050Y173133D01*
X395467Y173467D01*
X396050Y173633D01*
X396633Y173467D01*
X397050Y173133D01*
X397300Y172717D01*
Y170300D01*
G01Y172717D02*
X397550Y173133D01*
X397967Y173467D01*
X398550Y173633D01*
X399133Y173467D01*
X399550Y173133D01*
X399800Y172633D01*
Y170300D01*
G01X402900Y173633D02*
Y170300D01*
G01Y174967D02*
X402733Y175050D01*
Y175217D01*
X402900Y175300D01*
X403067Y175217D01*
Y175050D01*
X402900Y174967D01*
G01X408500Y170300D02*
Y175300D01*
G01X421367Y170300D02*
X418033Y171967D01*
X421367Y173633D01*
G01X430900Y175300D02*
Y170300D01*
G01X429733Y173633D02*
X432067D01*
G01X435333Y170300D02*
Y173633D01*
G01Y172967D02*
X435750Y173300D01*
X436167Y173550D01*
X436750Y173633D01*
X437167Y173550D01*
X437667Y173300D01*
G01X443600Y170300D02*
Y173633D01*
G01Y173050D02*
X443267Y173383D01*
X442767Y173550D01*
X442183Y173633D01*
X441600Y173467D01*
X441100Y173133D01*
X440767Y172633D01*
X440600Y171967D01*
X440767Y171300D01*
X441100Y170800D01*
X441600Y170467D01*
X442183Y170300D01*
X442767Y170383D01*
X443267Y170633D01*
X443600Y170967D01*
G01X449033Y173217D02*
X448450Y173550D01*
X447950Y173633D01*
X447283Y173467D01*
X446783Y173133D01*
X446450Y172550D01*
X446367Y171967D01*
X446450Y171383D01*
X446783Y170883D01*
X447283Y170467D01*
X447950Y170300D01*
X448533Y170467D01*
X449033Y170800D01*
G01X452050Y172550D02*
X454717D01*
X454467Y173133D01*
X454050Y173467D01*
X453467Y173633D01*
X452883Y173550D01*
X452383Y173300D01*
X452050Y172717D01*
X451883Y172217D01*
Y171717D01*
X452050Y171217D01*
X452467Y170717D01*
X452967Y170383D01*
X453550Y170300D01*
X454133Y170467D01*
X454717Y170967D01*
G01X462417Y173633D02*
X463417Y170300D01*
X464500Y173633D01*
X465583Y170300D01*
X466583Y173633D01*
G01X470100D02*
Y170300D01*
G01Y174967D02*
X469933Y175050D01*
Y175217D01*
X470100Y175300D01*
X470267Y175217D01*
Y175050D01*
X470100Y174967D01*
G01X477200Y175300D02*
Y170300D01*
G01Y171050D02*
X476867Y170633D01*
X476367Y170383D01*
X475783Y170300D01*
X475117Y170467D01*
X474617Y170883D01*
X474283Y171383D01*
X474200Y171967D01*
X474283Y172550D01*
X474617Y173050D01*
X475117Y173467D01*
X475783Y173633D01*
X476367Y173550D01*
X476783Y173383D01*
X477200Y173050D01*
G01X481300Y175300D02*
Y170300D01*
G01X480133Y173633D02*
X482467D01*
G01X485483Y170300D02*
Y175300D01*
G01Y172883D02*
X485900Y173300D01*
X486317Y173550D01*
X486983Y173633D01*
X487483Y173550D01*
X488067Y173217D01*
X488317Y172717D01*
Y170300D01*
G01X499767D02*
X496433Y171967D01*
X499767Y173633D01*
G01X502617Y171217D02*
X504783D01*
G01Y172717D02*
X502617D01*
G01X514733Y170300D02*
X514900Y171383D01*
X515150Y172300D01*
X515483Y173133D01*
X515900Y174050D01*
X516567Y175300D01*
X513233D01*
G01X523600Y170300D02*
Y173633D01*
G01Y172717D02*
X523850Y173133D01*
X524267Y173467D01*
X524850Y173633D01*
X525433Y173467D01*
X525850Y173133D01*
X526100Y172717D01*
Y170300D01*
G01Y172717D02*
X526350Y173133D01*
X526767Y173467D01*
X527350Y173633D01*
X527933Y173467D01*
X528350Y173133D01*
X528600Y172633D01*
Y170300D01*
G01X531700Y173633D02*
Y170300D01*
G01Y174967D02*
X531533Y175050D01*
Y175217D01*
X531700Y175300D01*
X531867Y175217D01*
Y175050D01*
X531700Y174967D01*
G01X537300Y170300D02*
Y175300D01*
G01X384433Y198800D02*
Y203800D01*
X386517D01*
X387183Y203550D01*
X387600Y203217D01*
X387767Y202550D01*
X387600Y201883D01*
X387100Y201467D01*
X386517Y201217D01*
X384433D01*
G01X386517D02*
X387767Y198800D01*
G01X390450Y201050D02*
X393117D01*
X392867Y201633D01*
X392450Y201967D01*
X391867Y202133D01*
X391283Y202050D01*
X390783Y201800D01*
X390450Y201217D01*
X390283Y200717D01*
Y200217D01*
X390450Y199717D01*
X390867Y199217D01*
X391367Y198883D01*
X391950Y198800D01*
X392533Y198967D01*
X393117Y199467D01*
G01X397300Y198800D02*
Y203800D01*
G01X404400Y198800D02*
Y202133D01*
G01Y201550D02*
X404067Y201883D01*
X403567Y202050D01*
X402983Y202133D01*
X402400Y201967D01*
X401900Y201633D01*
X401567Y201133D01*
X401400Y200467D01*
X401567Y199800D01*
X401900Y199300D01*
X402400Y198967D01*
X402983Y198800D01*
X403567Y198883D01*
X404067Y199133D01*
X404400Y199467D01*
G01X408500Y203800D02*
Y198800D01*
G01X407333Y202133D02*
X409667D01*
G01X414100D02*
Y198800D01*
G01Y203467D02*
X413933Y203550D01*
Y203717D01*
X414100Y203800D01*
X414267Y203717D01*
Y203550D01*
X414100Y203467D01*
G01X418200Y202133D02*
X419700Y198800D01*
X421200Y202133D01*
G01X424050Y201050D02*
X426717D01*
X426467Y201633D01*
X426050Y201967D01*
X425467Y202133D01*
X424883Y202050D01*
X424383Y201800D01*
X424050Y201217D01*
X423883Y200717D01*
Y200217D01*
X424050Y199717D01*
X424467Y199217D01*
X424967Y198883D01*
X425550Y198800D01*
X426133Y198967D01*
X426717Y199467D01*
G01X435000Y197133D02*
Y202133D01*
G01Y201383D02*
X435417Y201800D01*
X435833Y202050D01*
X436500Y202133D01*
X437083Y202050D01*
X437667Y201633D01*
X437917Y201050D01*
X438000Y200467D01*
X437917Y199883D01*
X437667Y199300D01*
X437167Y198967D01*
X436500Y198800D01*
X435917Y198883D01*
X435333Y199133D01*
X435000Y199467D01*
G01X442100Y198800D02*
X441600Y198883D01*
X441100Y199217D01*
X440767Y199800D01*
X440600Y200467D01*
X440767Y201133D01*
X441100Y201717D01*
X441600Y202050D01*
X442100Y202133D01*
X442600Y202050D01*
X443100Y201717D01*
X443433Y201133D01*
X443517Y200467D01*
X443433Y199800D01*
X443100Y199217D01*
X442600Y198883D01*
X442100Y198800D01*
G01X446450Y199383D02*
X446867Y199050D01*
X447450Y198800D01*
X447950D01*
X448450Y198967D01*
X448783Y199217D01*
X448950Y199550D01*
X448867Y200050D01*
X448533Y200300D01*
X447033Y200800D01*
X446700Y201383D01*
X446867Y201800D01*
X447200Y202050D01*
X447700Y202133D01*
X448200Y202050D01*
X448700Y201800D01*
G01X453300Y202133D02*
Y198800D01*
G01Y203467D02*
X453133Y203550D01*
Y203717D01*
X453300Y203800D01*
X453467Y203717D01*
Y203550D01*
X453300Y203467D01*
G01X458900Y203800D02*
Y198800D01*
G01X457733Y202133D02*
X460067D01*
G01X464500D02*
Y198800D01*
G01Y203467D02*
X464333Y203550D01*
Y203717D01*
X464500Y203800D01*
X464667Y203717D01*
Y203550D01*
X464500Y203467D01*
G01X470100Y198800D02*
X469600Y198883D01*
X469100Y199217D01*
X468767Y199800D01*
X468600Y200467D01*
X468767Y201133D01*
X469100Y201717D01*
X469600Y202050D01*
X470100Y202133D01*
X470600Y202050D01*
X471100Y201717D01*
X471433Y201133D01*
X471517Y200467D01*
X471433Y199800D01*
X471100Y199217D01*
X470600Y198883D01*
X470100Y198800D01*
G01X474283D02*
Y202133D01*
G01Y201300D02*
X474617Y201717D01*
X475117Y202050D01*
X475783Y202133D01*
X476367Y202050D01*
X476867Y201717D01*
X477117Y201133D01*
Y198800D01*
G01X485400D02*
Y203800D01*
G01Y201300D02*
X485817Y201800D01*
X486317Y202050D01*
X486817Y202133D01*
X487567Y201967D01*
X488067Y201633D01*
X488400Y201050D01*
Y200383D01*
X488233Y199717D01*
X487900Y199217D01*
X487317Y198883D01*
X486817Y198800D01*
X486317Y198883D01*
X485817Y199133D01*
X485400Y199550D01*
G01X491250Y201050D02*
X493917D01*
X493667Y201633D01*
X493250Y201967D01*
X492667Y202133D01*
X492083Y202050D01*
X491583Y201800D01*
X491250Y201217D01*
X491083Y200717D01*
Y200217D01*
X491250Y199717D01*
X491667Y199217D01*
X492167Y198883D01*
X492750Y198800D01*
X493333Y198967D01*
X493917Y199467D01*
G01X498100Y203800D02*
Y198800D01*
G01X496933Y202133D02*
X499267D01*
G01X501617D02*
X502617Y198800D01*
X503700Y202133D01*
X504783Y198800D01*
X505783Y202133D01*
G01X508050Y201050D02*
X510717D01*
X510467Y201633D01*
X510050Y201967D01*
X509467Y202133D01*
X508883Y202050D01*
X508383Y201800D01*
X508050Y201217D01*
X507883Y200717D01*
Y200217D01*
X508050Y199717D01*
X508467Y199217D01*
X508967Y198883D01*
X509550Y198800D01*
X510133Y198967D01*
X510717Y199467D01*
G01X513650Y201050D02*
X516317D01*
X516067Y201633D01*
X515650Y201967D01*
X515067Y202133D01*
X514483Y202050D01*
X513983Y201800D01*
X513650Y201217D01*
X513483Y200717D01*
Y200217D01*
X513650Y199717D01*
X514067Y199217D01*
X514567Y198883D01*
X515150Y198800D01*
X515733Y198967D01*
X516317Y199467D01*
G01X519083Y198800D02*
Y202133D01*
G01Y201300D02*
X519417Y201717D01*
X519917Y202050D01*
X520583Y202133D01*
X521167Y202050D01*
X521667Y201717D01*
X521917Y201133D01*
Y198800D01*
G01X533200D02*
Y202133D01*
G01Y201550D02*
X532867Y201883D01*
X532367Y202050D01*
X531783Y202133D01*
X531200Y201967D01*
X530700Y201633D01*
X530367Y201133D01*
X530200Y200467D01*
X530367Y199800D01*
X530700Y199300D01*
X531200Y198967D01*
X531783Y198800D01*
X532367Y198883D01*
X532867Y199133D01*
X533200Y199467D01*
G01X535883Y198800D02*
Y202133D01*
G01Y201300D02*
X536217Y201717D01*
X536717Y202050D01*
X537383Y202133D01*
X537967Y202050D01*
X538467Y201717D01*
X538717Y201133D01*
Y198800D01*
G01X541150Y197300D02*
X541650Y197133D01*
X542317Y197300D01*
X542733Y197633D01*
X543067Y198050D01*
X543567Y199383D01*
X544650Y202133D01*
G01X541983D02*
X543567Y199383D01*
G01X552600Y197133D02*
Y202133D01*
G01Y201383D02*
X553017Y201800D01*
X553433Y202050D01*
X554100Y202133D01*
X554683Y202050D01*
X555267Y201633D01*
X555517Y201050D01*
X555600Y200467D01*
X555517Y199883D01*
X555267Y199300D01*
X554767Y198967D01*
X554100Y198800D01*
X553517Y198883D01*
X552933Y199133D01*
X552600Y199467D01*
G01X561200Y198800D02*
Y202133D01*
G01Y201550D02*
X560867Y201883D01*
X560367Y202050D01*
X559783Y202133D01*
X559200Y201967D01*
X558700Y201633D01*
X558367Y201133D01*
X558200Y200467D01*
X558367Y199800D01*
X558700Y199300D01*
X559200Y198967D01*
X559783Y198800D01*
X560367Y198883D01*
X560867Y199133D01*
X561200Y199467D01*
G01X566800Y203800D02*
Y198800D01*
G01Y199550D02*
X566467Y199133D01*
X565967Y198883D01*
X565383Y198800D01*
X564717Y198967D01*
X564217Y199383D01*
X563883Y199883D01*
X563800Y200467D01*
X563883Y201050D01*
X564217Y201550D01*
X564717Y201967D01*
X565383Y202133D01*
X565967Y202050D01*
X566383Y201883D01*
X566800Y201550D01*
G01X576500Y203800D02*
Y198800D01*
G01X575333Y202133D02*
X577667D01*
G01X582100Y198800D02*
X581600Y198883D01*
X581100Y199217D01*
X580767Y199800D01*
X580600Y200467D01*
X580767Y201133D01*
X581100Y201717D01*
X581600Y202050D01*
X582100Y202133D01*
X582600Y202050D01*
X583100Y201717D01*
X583433Y201133D01*
X583517Y200467D01*
X583433Y199800D01*
X583100Y199217D01*
X582600Y198883D01*
X582100Y198800D01*
G01X591800Y197133D02*
Y202133D01*
G01Y201383D02*
X592217Y201800D01*
X592633Y202050D01*
X593300Y202133D01*
X593883Y202050D01*
X594467Y201633D01*
X594717Y201050D01*
X594800Y200467D01*
X594717Y199883D01*
X594467Y199300D01*
X593967Y198967D01*
X593300Y198800D01*
X592717Y198883D01*
X592133Y199133D01*
X591800Y199467D01*
G01X600400Y198800D02*
Y202133D01*
G01Y201550D02*
X600067Y201883D01*
X599567Y202050D01*
X598983Y202133D01*
X598400Y201967D01*
X597900Y201633D01*
X597567Y201133D01*
X597400Y200467D01*
X597567Y199800D01*
X597900Y199300D01*
X598400Y198967D01*
X598983Y198800D01*
X599567Y198883D01*
X600067Y199133D01*
X600400Y199467D01*
G01X606000Y203800D02*
Y198800D01*
G01Y199550D02*
X605667Y199133D01*
X605167Y198883D01*
X604583Y198800D01*
X603917Y198967D01*
X603417Y199383D01*
X603083Y199883D01*
X603000Y200467D01*
X603083Y201050D01*
X603417Y201550D01*
X603917Y201967D01*
X604583Y202133D01*
X605167Y202050D01*
X605583Y201883D01*
X606000Y201550D01*
G01X384350Y213800D02*
Y218800D01*
G01X387850D02*
Y213800D01*
G01Y216300D02*
X384350D01*
G01X389867Y213800D02*
Y218800D01*
X391533D01*
X392200Y218550D01*
X392700Y218217D01*
X393117Y217717D01*
X393450Y217133D01*
X393533Y216300D01*
X393450Y215467D01*
X393117Y214883D01*
X392700Y214383D01*
X392200Y214050D01*
X391533Y213800D01*
X389867D01*
G01X396300Y218800D02*
X398300D01*
G01X397300D02*
Y213800D01*
G01X396300D02*
X398300D01*
G01X406833D02*
Y218800D01*
X408833D01*
X409500Y218550D01*
X410000Y217967D01*
X410167Y217300D01*
X410000Y216633D01*
X409583Y216133D01*
X408833Y215883D01*
X406833D01*
G01X415933Y218383D02*
X415433Y218633D01*
X414850Y218800D01*
X414183D01*
X413433Y218550D01*
X412850Y218133D01*
X412433Y217633D01*
X412100Y216800D01*
X412017Y216050D01*
X412183Y215300D01*
X412433Y214800D01*
X412933Y214300D01*
X413517Y213967D01*
X414100Y213800D01*
X414683D01*
X415267Y213967D01*
X415767Y214217D01*
X416183Y214550D01*
G01X420367Y216467D02*
X420700Y216717D01*
X420950Y217133D01*
X421117Y217717D01*
X420950Y218217D01*
X420617Y218550D01*
X420033Y218800D01*
X417783D01*
Y213800D01*
X420533D01*
X421117Y214133D01*
X421450Y214633D01*
X421617Y215217D01*
X421450Y215800D01*
X420950Y216300D01*
X420367Y216467D01*
X417783D01*
G01X425300Y213633D02*
X425133Y213717D01*
Y213883D01*
X425300Y213967D01*
X425467Y213883D01*
Y213717D01*
X425300Y213633D01*
G01X377600Y164300D02*
X808100D01*
G01X377600Y179300D02*
X808100D01*
G01X384850Y230383D02*
X385267Y230050D01*
X385850Y229800D01*
X386350D01*
X386850Y229967D01*
X387183Y230217D01*
X387350Y230550D01*
X387267Y231050D01*
X386933Y231300D01*
X385433Y231800D01*
X385100Y232383D01*
X385267Y232800D01*
X385600Y233050D01*
X386100Y233133D01*
X386600Y233050D01*
X387100Y232800D01*
G01X390200Y228133D02*
Y233133D01*
G01Y232383D02*
X390617Y232800D01*
X391033Y233050D01*
X391700Y233133D01*
X392283Y233050D01*
X392867Y232633D01*
X393117Y232050D01*
X393200Y231467D01*
X393117Y230883D01*
X392867Y230300D01*
X392367Y229967D01*
X391700Y229800D01*
X391117Y229883D01*
X390533Y230133D01*
X390200Y230467D01*
G01X396050Y232050D02*
X398717D01*
X398467Y232633D01*
X398050Y232967D01*
X397467Y233133D01*
X396883Y233050D01*
X396383Y232800D01*
X396050Y232217D01*
X395883Y231717D01*
Y231217D01*
X396050Y230717D01*
X396467Y230217D01*
X396967Y229883D01*
X397550Y229800D01*
X398133Y229967D01*
X398717Y230467D01*
G01X404233Y232717D02*
X403650Y233050D01*
X403150Y233133D01*
X402483Y232967D01*
X401983Y232633D01*
X401650Y232050D01*
X401567Y231467D01*
X401650Y230883D01*
X401983Y230383D01*
X402483Y229967D01*
X403150Y229800D01*
X403733Y229967D01*
X404233Y230300D01*
G01X408500Y233133D02*
Y229800D01*
G01Y234467D02*
X408333Y234550D01*
Y234717D01*
X408500Y234800D01*
X408667Y234717D01*
Y234550D01*
X408500Y234467D01*
G01X413600Y229800D02*
Y234050D01*
X413767Y234467D01*
X414100Y234717D01*
X414600Y234800D01*
X415100Y234633D01*
X415350Y234217D01*
G01X414350Y232800D02*
X412683D01*
G01X419700Y233133D02*
Y229800D01*
G01Y234467D02*
X419533Y234550D01*
Y234717D01*
X419700Y234800D01*
X419867Y234717D01*
Y234550D01*
X419700Y234467D01*
G01X426633Y232717D02*
X426050Y233050D01*
X425550Y233133D01*
X424883Y232967D01*
X424383Y232633D01*
X424050Y232050D01*
X423967Y231467D01*
X424050Y230883D01*
X424383Y230383D01*
X424883Y229967D01*
X425550Y229800D01*
X426133Y229967D01*
X426633Y230300D01*
G01X432400Y229800D02*
Y233133D01*
G01Y232550D02*
X432067Y232883D01*
X431567Y233050D01*
X430983Y233133D01*
X430400Y232967D01*
X429900Y232633D01*
X429567Y232133D01*
X429400Y231467D01*
X429567Y230800D01*
X429900Y230300D01*
X430400Y229967D01*
X430983Y229800D01*
X431567Y229883D01*
X432067Y230133D01*
X432400Y230467D01*
G01X436500Y234800D02*
Y229800D01*
G01X435333Y233133D02*
X437667D01*
G01X442100D02*
Y229800D01*
G01Y234467D02*
X441933Y234550D01*
Y234717D01*
X442100Y234800D01*
X442267Y234717D01*
Y234550D01*
X442100Y234467D01*
G01X447700Y229800D02*
X447200Y229883D01*
X446700Y230217D01*
X446367Y230800D01*
X446200Y231467D01*
X446367Y232133D01*
X446700Y232717D01*
X447200Y233050D01*
X447700Y233133D01*
X448200Y233050D01*
X448700Y232717D01*
X449033Y232133D01*
X449117Y231467D01*
X449033Y230800D01*
X448700Y230217D01*
X448200Y229883D01*
X447700Y229800D01*
G01X451883D02*
Y233133D01*
G01Y232300D02*
X452217Y232717D01*
X452717Y233050D01*
X453383Y233133D01*
X453967Y233050D01*
X454467Y232717D01*
X454717Y232133D01*
Y229800D01*
G01X458900Y229633D02*
X458733Y229717D01*
Y229883D01*
X458900Y229967D01*
X459067Y229883D01*
Y229717D01*
X458900Y229633D01*
G01X384350Y239467D02*
X385017Y239050D01*
X385767Y238800D01*
X386433D01*
X387100Y239050D01*
X387600Y239467D01*
X387850Y240050D01*
X387683Y240633D01*
X387267Y241133D01*
X386517Y241467D01*
X385517Y241633D01*
X384933Y241967D01*
X384683Y242550D01*
X384850Y243133D01*
X385267Y243550D01*
X385850Y243800D01*
X386433D01*
X387017Y243633D01*
X387517Y243217D01*
G01X390450Y241050D02*
X393117D01*
X392867Y241633D01*
X392450Y241967D01*
X391867Y242133D01*
X391283Y242050D01*
X390783Y241800D01*
X390450Y241217D01*
X390283Y240717D01*
Y240217D01*
X390450Y239717D01*
X390867Y239217D01*
X391367Y238883D01*
X391950Y238800D01*
X392533Y238967D01*
X393117Y239467D01*
G01X396133Y238800D02*
Y242133D01*
G01Y241467D02*
X396550Y241800D01*
X396967Y242050D01*
X397550Y242133D01*
X397967Y242050D01*
X398467Y241800D01*
G01X401400Y242133D02*
X402900Y238800D01*
X404400Y242133D01*
G01X407250Y241050D02*
X409917D01*
X409667Y241633D01*
X409250Y241967D01*
X408667Y242133D01*
X408083Y242050D01*
X407583Y241800D01*
X407250Y241217D01*
X407083Y240717D01*
Y240217D01*
X407250Y239717D01*
X407667Y239217D01*
X408167Y238883D01*
X408750Y238800D01*
X409333Y238967D01*
X409917Y239467D01*
G01X412933Y238800D02*
Y242133D01*
G01Y241467D02*
X413350Y241800D01*
X413767Y242050D01*
X414350Y242133D01*
X414767Y242050D01*
X415267Y241800D01*
G01X423633Y238800D02*
Y243800D01*
X425633D01*
X426300Y243550D01*
X426800Y242967D01*
X426967Y242300D01*
X426800Y241633D01*
X426383Y241133D01*
X425633Y240883D01*
X423633D01*
G01X432733Y243383D02*
X432233Y243633D01*
X431650Y243800D01*
X430983D01*
X430233Y243550D01*
X429650Y243133D01*
X429233Y242633D01*
X428900Y241800D01*
X428817Y241050D01*
X428983Y240300D01*
X429233Y239800D01*
X429733Y239300D01*
X430317Y238967D01*
X430900Y238800D01*
X431483D01*
X432067Y238967D01*
X432567Y239217D01*
X432983Y239550D01*
G01X437167Y241467D02*
X437500Y241717D01*
X437750Y242133D01*
X437917Y242717D01*
X437750Y243217D01*
X437417Y243550D01*
X436833Y243800D01*
X434583D01*
Y238800D01*
X437333D01*
X437917Y239133D01*
X438250Y239633D01*
X438417Y240217D01*
X438250Y240800D01*
X437750Y241300D01*
X437167Y241467D01*
X434583D01*
G01X442100Y238633D02*
X441933Y238717D01*
Y238883D01*
X442100Y238967D01*
X442267Y238883D01*
Y238717D01*
X442100Y238633D01*
G01Y240883D02*
X441933Y240967D01*
Y241133D01*
X442100Y241217D01*
X442267Y241133D01*
Y240967D01*
X442100Y240883D01*
G01X446117Y238800D02*
Y243800D01*
X449283D01*
G01X448117Y241383D02*
X446117D01*
G01X453300Y238800D02*
X452800Y238883D01*
X452300Y239217D01*
X451967Y239800D01*
X451800Y240467D01*
X451967Y241133D01*
X452300Y241717D01*
X452800Y242050D01*
X453300Y242133D01*
X453800Y242050D01*
X454300Y241717D01*
X454633Y241133D01*
X454717Y240467D01*
X454633Y239800D01*
X454300Y239217D01*
X453800Y238883D01*
X453300Y238800D01*
G01X458900D02*
Y243800D01*
G01X464500Y238800D02*
Y243800D01*
G01X470100Y238800D02*
X469600Y238883D01*
X469100Y239217D01*
X468767Y239800D01*
X468600Y240467D01*
X468767Y241133D01*
X469100Y241717D01*
X469600Y242050D01*
X470100Y242133D01*
X470600Y242050D01*
X471100Y241717D01*
X471433Y241133D01*
X471517Y240467D01*
X471433Y239800D01*
X471100Y239217D01*
X470600Y238883D01*
X470100Y238800D01*
G01X473617Y242133D02*
X474617Y238800D01*
X475700Y242133D01*
X476783Y238800D01*
X477783Y242133D01*
G01X485733Y238800D02*
Y242133D01*
G01Y241467D02*
X486150Y241800D01*
X486567Y242050D01*
X487150Y242133D01*
X487567Y242050D01*
X488067Y241800D01*
G01X492500Y242133D02*
Y238800D01*
G01Y243467D02*
X492333Y243550D01*
Y243717D01*
X492500Y243800D01*
X492667Y243717D01*
Y243550D01*
X492500Y243467D01*
G01X496933Y237550D02*
X497517Y237217D01*
X498183Y237133D01*
X498767Y237217D01*
X499267Y237633D01*
X499600Y238217D01*
Y242133D01*
G01Y241467D02*
X499267Y241800D01*
X498767Y242050D01*
X498183Y242133D01*
X497517Y241967D01*
X497100Y241633D01*
X496767Y241050D01*
X496600Y240467D01*
X496683Y239967D01*
X497017Y239383D01*
X497517Y238967D01*
X498183Y238800D01*
X498683Y238883D01*
X499267Y239217D01*
X499600Y239550D01*
G01X502283Y238800D02*
Y243800D01*
G01Y241383D02*
X502700Y241800D01*
X503117Y242050D01*
X503783Y242133D01*
X504283Y242050D01*
X504867Y241717D01*
X505117Y241217D01*
Y238800D01*
G01X509300Y243800D02*
Y238800D01*
G01X508133Y242133D02*
X510467D01*
G01X519250Y239383D02*
X519667Y239050D01*
X520250Y238800D01*
X520750D01*
X521250Y238967D01*
X521583Y239217D01*
X521750Y239550D01*
X521667Y240050D01*
X521333Y240300D01*
X519833Y240800D01*
X519500Y241383D01*
X519667Y241800D01*
X520000Y242050D01*
X520500Y242133D01*
X521000Y242050D01*
X521500Y241800D01*
G01X526100Y242133D02*
Y238800D01*
G01Y243467D02*
X525933Y243550D01*
Y243717D01*
X526100Y243800D01*
X526267Y243717D01*
Y243550D01*
X526100Y243467D01*
G01X533200Y243800D02*
Y238800D01*
G01Y239550D02*
X532867Y239133D01*
X532367Y238883D01*
X531783Y238800D01*
X531117Y238967D01*
X530617Y239383D01*
X530283Y239883D01*
X530200Y240467D01*
X530283Y241050D01*
X530617Y241550D01*
X531117Y241967D01*
X531783Y242133D01*
X532367Y242050D01*
X532783Y241883D01*
X533200Y241550D01*
G01X536050Y241050D02*
X538717D01*
X538467Y241633D01*
X538050Y241967D01*
X537467Y242133D01*
X536883Y242050D01*
X536383Y241800D01*
X536050Y241217D01*
X535883Y240717D01*
Y240217D01*
X536050Y239717D01*
X536467Y239217D01*
X536967Y238883D01*
X537550Y238800D01*
X538133Y238967D01*
X538717Y239467D01*
G01X547250Y239383D02*
X547667Y239050D01*
X548250Y238800D01*
X548750D01*
X549250Y238967D01*
X549583Y239217D01*
X549750Y239550D01*
X549667Y240050D01*
X549333Y240300D01*
X547833Y240800D01*
X547500Y241383D01*
X547667Y241800D01*
X548000Y242050D01*
X548500Y242133D01*
X549000Y242050D01*
X549500Y241800D01*
G01X552600Y237133D02*
Y242133D01*
G01Y241383D02*
X553017Y241800D01*
X553433Y242050D01*
X554100Y242133D01*
X554683Y242050D01*
X555267Y241633D01*
X555517Y241050D01*
X555600Y240467D01*
X555517Y239883D01*
X555267Y239300D01*
X554767Y238967D01*
X554100Y238800D01*
X553517Y238883D01*
X552933Y239133D01*
X552600Y239467D01*
G01X558450Y241050D02*
X561117D01*
X560867Y241633D01*
X560450Y241967D01*
X559867Y242133D01*
X559283Y242050D01*
X558783Y241800D01*
X558450Y241217D01*
X558283Y240717D01*
Y240217D01*
X558450Y239717D01*
X558867Y239217D01*
X559367Y238883D01*
X559950Y238800D01*
X560533Y238967D01*
X561117Y239467D01*
G01X566633Y241717D02*
X566050Y242050D01*
X565550Y242133D01*
X564883Y241967D01*
X564383Y241633D01*
X564050Y241050D01*
X563967Y240467D01*
X564050Y239883D01*
X564383Y239383D01*
X564883Y238967D01*
X565550Y238800D01*
X566133Y238967D01*
X566633Y239300D01*
G01X576333Y237883D02*
X576667Y238967D01*
G01X582100Y242133D02*
Y238800D01*
G01Y243467D02*
X581933Y243550D01*
Y243717D01*
X582100Y243800D01*
X582267Y243717D01*
Y243550D01*
X582100Y243467D01*
G01X587200Y238800D02*
Y243050D01*
X587367Y243467D01*
X587700Y243717D01*
X588200Y243800D01*
X588700Y243633D01*
X588950Y243217D01*
G01X587950Y241800D02*
X586283D01*
G01X597650Y239383D02*
X598067Y239050D01*
X598650Y238800D01*
X599150D01*
X599650Y238967D01*
X599983Y239217D01*
X600150Y239550D01*
X600067Y240050D01*
X599733Y240300D01*
X598233Y240800D01*
X597900Y241383D01*
X598067Y241800D01*
X598400Y242050D01*
X598900Y242133D01*
X599400Y242050D01*
X599900Y241800D01*
G01X604500Y243800D02*
Y238800D01*
G01X603333Y242133D02*
X605667D01*
G01X611600Y238800D02*
Y242133D01*
G01Y241550D02*
X611267Y241883D01*
X610767Y242050D01*
X610183Y242133D01*
X609600Y241967D01*
X609100Y241633D01*
X608767Y241133D01*
X608600Y240467D01*
X608767Y239800D01*
X609100Y239300D01*
X609600Y238967D01*
X610183Y238800D01*
X610767Y238883D01*
X611267Y239133D01*
X611600Y239467D01*
G01X617033Y241717D02*
X616450Y242050D01*
X615950Y242133D01*
X615283Y241967D01*
X614783Y241633D01*
X614450Y241050D01*
X614367Y240467D01*
X614450Y239883D01*
X614783Y239383D01*
X615283Y238967D01*
X615950Y238800D01*
X616533Y238967D01*
X617033Y239300D01*
G01X619883Y238800D02*
Y243800D01*
G01X622550Y242133D02*
X619883Y240217D01*
G01X620967Y240967D02*
X622717Y238800D01*
G01X631083Y242133D02*
Y239800D01*
X631417Y239217D01*
X631917Y238883D01*
X632500Y238800D01*
X633083Y238883D01*
X633583Y239217D01*
X633917Y239800D01*
G01Y238800D02*
Y242133D01*
G01X636600Y237133D02*
Y242133D01*
G01Y241383D02*
X637017Y241800D01*
X637433Y242050D01*
X638100Y242133D01*
X638683Y242050D01*
X639267Y241633D01*
X639517Y241050D01*
X639600Y240467D01*
X639517Y239883D01*
X639267Y239300D01*
X638767Y238967D01*
X638100Y238800D01*
X637517Y238883D01*
X636933Y239133D01*
X636600Y239467D01*
G01X647217Y242133D02*
X648217Y238800D01*
X649300Y242133D01*
X650383Y238800D01*
X651383Y242133D01*
G01X654900D02*
Y238800D01*
G01Y243467D02*
X654733Y243550D01*
Y243717D01*
X654900Y243800D01*
X655067Y243717D01*
Y243550D01*
X654900Y243467D01*
G01X660500Y243800D02*
Y238800D01*
G01X659333Y242133D02*
X661667D01*
G01X664683Y238800D02*
Y243800D01*
G01Y241383D02*
X665100Y241800D01*
X665517Y242050D01*
X666183Y242133D01*
X666683Y242050D01*
X667267Y241717D01*
X667517Y241217D01*
Y238800D01*
G01X671700D02*
X671200Y238883D01*
X670700Y239217D01*
X670367Y239800D01*
X670200Y240467D01*
X670367Y241133D01*
X670700Y241717D01*
X671200Y242050D01*
X671700Y242133D01*
X672200Y242050D01*
X672700Y241717D01*
X673033Y241133D01*
X673117Y240467D01*
X673033Y239800D01*
X672700Y239217D01*
X672200Y238883D01*
X671700Y238800D01*
G01X675883Y242133D02*
Y239800D01*
X676217Y239217D01*
X676717Y238883D01*
X677300Y238800D01*
X677883Y238883D01*
X678383Y239217D01*
X678717Y239800D01*
G01Y238800D02*
Y242133D01*
G01X682900Y243800D02*
Y238800D01*
G01X681733Y242133D02*
X684067D01*
G01X386100Y258800D02*
Y253800D01*
G01X384183Y258800D02*
X388017D01*
G01X390533Y253800D02*
Y257133D01*
G01Y256467D02*
X390950Y256800D01*
X391367Y257050D01*
X391950Y257133D01*
X392367Y257050D01*
X392867Y256800D01*
G01X398800Y253800D02*
Y257133D01*
G01Y256550D02*
X398467Y256883D01*
X397967Y257050D01*
X397383Y257133D01*
X396800Y256967D01*
X396300Y256633D01*
X395967Y256133D01*
X395800Y255467D01*
X395967Y254800D01*
X396300Y254300D01*
X396800Y253967D01*
X397383Y253800D01*
X397967Y253883D01*
X398467Y254133D01*
X398800Y254467D01*
G01X404400Y258800D02*
Y253800D01*
G01Y254550D02*
X404067Y254133D01*
X403567Y253883D01*
X402983Y253800D01*
X402317Y253967D01*
X401817Y254383D01*
X401483Y254883D01*
X401400Y255467D01*
X401483Y256050D01*
X401817Y256550D01*
X402317Y256967D01*
X402983Y257133D01*
X403567Y257050D01*
X403983Y256883D01*
X404400Y256550D01*
G01X408500Y257133D02*
Y253800D01*
G01Y258467D02*
X408333Y258550D01*
Y258717D01*
X408500Y258800D01*
X408667Y258717D01*
Y258550D01*
X408500Y258467D01*
G01X414100Y258800D02*
Y253800D01*
G01X412933Y257133D02*
X415267D01*
G01X419700D02*
Y253800D01*
G01Y258467D02*
X419533Y258550D01*
Y258717D01*
X419700Y258800D01*
X419867Y258717D01*
Y258550D01*
X419700Y258467D01*
G01X425300Y253800D02*
X424800Y253883D01*
X424300Y254217D01*
X423967Y254800D01*
X423800Y255467D01*
X423967Y256133D01*
X424300Y256717D01*
X424800Y257050D01*
X425300Y257133D01*
X425800Y257050D01*
X426300Y256717D01*
X426633Y256133D01*
X426717Y255467D01*
X426633Y254800D01*
X426300Y254217D01*
X425800Y253883D01*
X425300Y253800D01*
G01X429483D02*
Y257133D01*
G01Y256300D02*
X429817Y256717D01*
X430317Y257050D01*
X430983Y257133D01*
X431567Y257050D01*
X432067Y256717D01*
X432317Y256133D01*
Y253800D01*
G01X438000D02*
Y257133D01*
G01Y256550D02*
X437667Y256883D01*
X437167Y257050D01*
X436583Y257133D01*
X436000Y256967D01*
X435500Y256633D01*
X435167Y256133D01*
X435000Y255467D01*
X435167Y254800D01*
X435500Y254300D01*
X436000Y253967D01*
X436583Y253800D01*
X437167Y253883D01*
X437667Y254133D01*
X438000Y254467D01*
G01X442100Y253800D02*
Y258800D01*
G01X451633Y253800D02*
Y258800D01*
X453633D01*
X454300Y258550D01*
X454800Y257967D01*
X454967Y257300D01*
X454800Y256633D01*
X454383Y256133D01*
X453633Y255883D01*
X451633D01*
G01X460733Y258383D02*
X460233Y258633D01*
X459650Y258800D01*
X458983D01*
X458233Y258550D01*
X457650Y258133D01*
X457233Y257633D01*
X456900Y256800D01*
X456817Y256050D01*
X456983Y255300D01*
X457233Y254800D01*
X457733Y254300D01*
X458317Y253967D01*
X458900Y253800D01*
X459483D01*
X460067Y253967D01*
X460567Y254217D01*
X460983Y254550D01*
G01X465167Y256467D02*
X465500Y256717D01*
X465750Y257133D01*
X465917Y257717D01*
X465750Y258217D01*
X465417Y258550D01*
X464833Y258800D01*
X462583D01*
Y253800D01*
X465333D01*
X465917Y254133D01*
X466250Y254633D01*
X466417Y255217D01*
X466250Y255800D01*
X465750Y256300D01*
X465167Y256467D01*
X462583D01*
G01X470100Y253633D02*
X469933Y253717D01*
Y253883D01*
X470100Y253967D01*
X470267Y253883D01*
Y253717D01*
X470100Y253633D01*
G01X377600Y224300D02*
X808100D01*
G01X377600Y249300D02*
X808100D01*
G01X376100Y326300D02*
X808100D01*
G01X376100Y379300D02*
X808100D01*
G01X383600Y462800D02*
Y457800D01*
G01X382433Y461133D02*
X384767D01*
G01X389200Y457800D02*
X388700Y457883D01*
X388200Y458217D01*
X387867Y458800D01*
X387700Y459467D01*
X387867Y460133D01*
X388200Y460717D01*
X388700Y461050D01*
X389200Y461133D01*
X389700Y461050D01*
X390200Y460717D01*
X390533Y460133D01*
X390617Y459467D01*
X390533Y458800D01*
X390200Y458217D01*
X389700Y457883D01*
X389200Y457800D01*
G01X394800D02*
Y462800D01*
G01X399150Y460050D02*
X401817D01*
X401567Y460633D01*
X401150Y460967D01*
X400567Y461133D01*
X399983Y461050D01*
X399483Y460800D01*
X399150Y460217D01*
X398983Y459717D01*
Y459217D01*
X399150Y458717D01*
X399567Y458217D01*
X400067Y457883D01*
X400650Y457800D01*
X401233Y457967D01*
X401817Y458467D01*
G01X404833Y457800D02*
Y461133D01*
G01Y460467D02*
X405250Y460800D01*
X405667Y461050D01*
X406250Y461133D01*
X406667Y461050D01*
X407167Y460800D01*
G01X413100Y457800D02*
Y461133D01*
G01Y460550D02*
X412767Y460883D01*
X412267Y461050D01*
X411683Y461133D01*
X411100Y460967D01*
X410600Y460633D01*
X410267Y460133D01*
X410100Y459467D01*
X410267Y458800D01*
X410600Y458300D01*
X411100Y457967D01*
X411683Y457800D01*
X412267Y457883D01*
X412767Y458133D01*
X413100Y458467D01*
G01X415783Y457800D02*
Y461133D01*
G01Y460300D02*
X416117Y460717D01*
X416617Y461050D01*
X417283Y461133D01*
X417867Y461050D01*
X418367Y460717D01*
X418617Y460133D01*
Y457800D01*
G01X424133Y460717D02*
X423550Y461050D01*
X423050Y461133D01*
X422383Y460967D01*
X421883Y460633D01*
X421550Y460050D01*
X421467Y459467D01*
X421550Y458883D01*
X421883Y458383D01*
X422383Y457967D01*
X423050Y457800D01*
X423633Y457967D01*
X424133Y458300D01*
G01X427150Y460050D02*
X429817D01*
X429567Y460633D01*
X429150Y460967D01*
X428567Y461133D01*
X427983Y461050D01*
X427483Y460800D01*
X427150Y460217D01*
X426983Y459717D01*
Y459217D01*
X427150Y458717D01*
X427567Y458217D01*
X428067Y457883D01*
X428650Y457800D01*
X429233Y457967D01*
X429817Y458467D01*
G01X439600Y462800D02*
Y457800D01*
G01X438433Y461133D02*
X440767D01*
G01X446700Y457800D02*
Y461133D01*
G01Y460550D02*
X446367Y460883D01*
X445867Y461050D01*
X445283Y461133D01*
X444700Y460967D01*
X444200Y460633D01*
X443867Y460133D01*
X443700Y459467D01*
X443867Y458800D01*
X444200Y458300D01*
X444700Y457967D01*
X445283Y457800D01*
X445867Y457883D01*
X446367Y458133D01*
X446700Y458467D01*
G01X449300Y457800D02*
Y462800D01*
G01Y460300D02*
X449717Y460800D01*
X450217Y461050D01*
X450717Y461133D01*
X451467Y460967D01*
X451967Y460633D01*
X452300Y460050D01*
Y459383D01*
X452133Y458717D01*
X451800Y458217D01*
X451217Y457883D01*
X450717Y457800D01*
X450217Y457883D01*
X449717Y458133D01*
X449300Y458550D01*
G01X456400Y457800D02*
Y462800D01*
G01X460750Y460050D02*
X463417D01*
X463167Y460633D01*
X462750Y460967D01*
X462167Y461133D01*
X461583Y461050D01*
X461083Y460800D01*
X460750Y460217D01*
X460583Y459717D01*
Y459217D01*
X460750Y458717D01*
X461167Y458217D01*
X461667Y457883D01*
X462250Y457800D01*
X462833Y457967D01*
X463417Y458467D01*
G01X467600Y457633D02*
X467433Y457717D01*
Y457883D01*
X467600Y457967D01*
X467767Y457883D01*
Y457717D01*
X467600Y457633D01*
G01X382267Y468550D02*
X382850Y468217D01*
X383350Y468133D01*
X384017Y468300D01*
X384517Y468717D01*
X384767Y469467D01*
Y473133D01*
G01Y474467D02*
X384600Y474550D01*
Y474717D01*
X384767Y474800D01*
X384933Y474717D01*
Y474550D01*
X384767Y474467D01*
G01X387783Y473133D02*
Y470800D01*
X388117Y470217D01*
X388617Y469883D01*
X389200Y469800D01*
X389783Y469883D01*
X390283Y470217D01*
X390617Y470800D01*
G01Y469800D02*
Y473133D01*
G01X393383Y469800D02*
Y473133D01*
G01Y472300D02*
X393717Y472717D01*
X394217Y473050D01*
X394883Y473133D01*
X395467Y473050D01*
X395967Y472717D01*
X396217Y472133D01*
Y469800D01*
G01X401733Y472717D02*
X401150Y473050D01*
X400650Y473133D01*
X399983Y472967D01*
X399483Y472633D01*
X399150Y472050D01*
X399067Y471467D01*
X399150Y470883D01*
X399483Y470383D01*
X399983Y469967D01*
X400650Y469800D01*
X401233Y469967D01*
X401733Y470300D01*
G01X406000Y474800D02*
Y469800D01*
G01X404833Y473133D02*
X407167D01*
G01X411600D02*
Y469800D01*
G01Y474467D02*
X411433Y474550D01*
Y474717D01*
X411600Y474800D01*
X411767Y474717D01*
Y474550D01*
X411600Y474467D01*
G01X417200Y469800D02*
X416700Y469883D01*
X416200Y470217D01*
X415867Y470800D01*
X415700Y471467D01*
X415867Y472133D01*
X416200Y472717D01*
X416700Y473050D01*
X417200Y473133D01*
X417700Y473050D01*
X418200Y472717D01*
X418533Y472133D01*
X418617Y471467D01*
X418533Y470800D01*
X418200Y470217D01*
X417700Y469883D01*
X417200Y469800D01*
G01X421383D02*
Y473133D01*
G01Y472300D02*
X421717Y472717D01*
X422217Y473050D01*
X422883Y473133D01*
X423467Y473050D01*
X423967Y472717D01*
X424217Y472133D01*
Y469800D01*
G01X432500D02*
Y474800D01*
G01Y472300D02*
X432917Y472800D01*
X433417Y473050D01*
X433917Y473133D01*
X434667Y472967D01*
X435167Y472633D01*
X435500Y472050D01*
Y471383D01*
X435333Y470717D01*
X435000Y470217D01*
X434417Y469883D01*
X433917Y469800D01*
X433417Y469883D01*
X432917Y470133D01*
X432500Y470550D01*
G01X438350Y472050D02*
X441017D01*
X440767Y472633D01*
X440350Y472967D01*
X439767Y473133D01*
X439183Y473050D01*
X438683Y472800D01*
X438350Y472217D01*
X438183Y471717D01*
Y471217D01*
X438350Y470717D01*
X438767Y470217D01*
X439267Y469883D01*
X439850Y469800D01*
X440433Y469967D01*
X441017Y470467D01*
G01X445200Y469800D02*
Y474800D01*
G01X450800Y469800D02*
X450300Y469883D01*
X449800Y470217D01*
X449467Y470800D01*
X449300Y471467D01*
X449467Y472133D01*
X449800Y472717D01*
X450300Y473050D01*
X450800Y473133D01*
X451300Y473050D01*
X451800Y472717D01*
X452133Y472133D01*
X452217Y471467D01*
X452133Y470800D01*
X451800Y470217D01*
X451300Y469883D01*
X450800Y469800D01*
G01X454317Y473133D02*
X455317Y469800D01*
X456400Y473133D01*
X457483Y469800D01*
X458483Y473133D01*
G01X467600Y474800D02*
Y469800D01*
G01X466433Y473133D02*
X468767D01*
G01X471783Y469800D02*
Y474800D01*
G01Y472383D02*
X472200Y472800D01*
X472617Y473050D01*
X473283Y473133D01*
X473783Y473050D01*
X474367Y472717D01*
X474617Y472217D01*
Y469800D01*
G01X477550Y472050D02*
X480217D01*
X479967Y472633D01*
X479550Y472967D01*
X478967Y473133D01*
X478383Y473050D01*
X477883Y472800D01*
X477550Y472217D01*
X477383Y471717D01*
Y471217D01*
X477550Y470717D01*
X477967Y470217D01*
X478467Y469883D01*
X479050Y469800D01*
X479633Y469967D01*
X480217Y470467D01*
G01X487500Y469800D02*
Y473133D01*
G01Y472217D02*
X487750Y472633D01*
X488167Y472967D01*
X488750Y473133D01*
X489333Y472967D01*
X489750Y472633D01*
X490000Y472217D01*
Y469800D01*
G01Y472217D02*
X490250Y472633D01*
X490667Y472967D01*
X491250Y473133D01*
X491833Y472967D01*
X492250Y472633D01*
X492500Y472133D01*
Y469800D01*
G01X495600Y473133D02*
Y469800D01*
G01Y474467D02*
X495433Y474550D01*
Y474717D01*
X495600Y474800D01*
X495767Y474717D01*
Y474550D01*
X495600Y474467D01*
G01X499783Y469800D02*
Y473133D01*
G01Y472300D02*
X500117Y472717D01*
X500617Y473050D01*
X501283Y473133D01*
X501867Y473050D01*
X502367Y472717D01*
X502617Y472133D01*
Y469800D01*
G01X513733Y472717D02*
X513150Y473050D01*
X512650Y473133D01*
X511983Y472967D01*
X511483Y472633D01*
X511150Y472050D01*
X511067Y471467D01*
X511150Y470883D01*
X511483Y470383D01*
X511983Y469967D01*
X512650Y469800D01*
X513233Y469967D01*
X513733Y470300D01*
G01X518000Y469800D02*
X517500Y469883D01*
X517000Y470217D01*
X516667Y470800D01*
X516500Y471467D01*
X516667Y472133D01*
X517000Y472717D01*
X517500Y473050D01*
X518000Y473133D01*
X518500Y473050D01*
X519000Y472717D01*
X519333Y472133D01*
X519417Y471467D01*
X519333Y470800D01*
X519000Y470217D01*
X518500Y469883D01*
X518000Y469800D01*
G01X522183D02*
Y473133D01*
G01Y472300D02*
X522517Y472717D01*
X523017Y473050D01*
X523683Y473133D01*
X524267Y473050D01*
X524767Y472717D01*
X525017Y472133D01*
Y469800D01*
G01X530700Y474800D02*
Y469800D01*
G01Y470550D02*
X530367Y470133D01*
X529867Y469883D01*
X529283Y469800D01*
X528617Y469967D01*
X528117Y470383D01*
X527783Y470883D01*
X527700Y471467D01*
X527783Y472050D01*
X528117Y472550D01*
X528617Y472967D01*
X529283Y473133D01*
X529867Y473050D01*
X530283Y472883D01*
X530700Y472550D01*
G01X533383Y473133D02*
Y470800D01*
X533717Y470217D01*
X534217Y469883D01*
X534800Y469800D01*
X535383Y469883D01*
X535883Y470217D01*
X536217Y470800D01*
G01Y469800D02*
Y473133D01*
G01X541733Y472717D02*
X541150Y473050D01*
X540650Y473133D01*
X539983Y472967D01*
X539483Y472633D01*
X539150Y472050D01*
X539067Y471467D01*
X539150Y470883D01*
X539483Y470383D01*
X539983Y469967D01*
X540650Y469800D01*
X541233Y469967D01*
X541733Y470300D01*
G01X546000Y474800D02*
Y469800D01*
G01X544833Y473133D02*
X547167D01*
G01X551600Y469800D02*
X551100Y469883D01*
X550600Y470217D01*
X550267Y470800D01*
X550100Y471467D01*
X550267Y472133D01*
X550600Y472717D01*
X551100Y473050D01*
X551600Y473133D01*
X552100Y473050D01*
X552600Y472717D01*
X552933Y472133D01*
X553017Y471467D01*
X552933Y470800D01*
X552600Y470217D01*
X552100Y469883D01*
X551600Y469800D01*
G01X556033D02*
Y473133D01*
G01Y472467D02*
X556450Y472800D01*
X556867Y473050D01*
X557450Y473133D01*
X557867Y473050D01*
X558367Y472800D01*
G01X566317Y473133D02*
X567317Y469800D01*
X568400Y473133D01*
X569483Y469800D01*
X570483Y473133D01*
G01X574000D02*
Y469800D01*
G01Y474467D02*
X573833Y474550D01*
Y474717D01*
X574000Y474800D01*
X574167Y474717D01*
Y474550D01*
X574000Y474467D01*
G01X581100Y474800D02*
Y469800D01*
G01Y470550D02*
X580767Y470133D01*
X580267Y469883D01*
X579683Y469800D01*
X579017Y469967D01*
X578517Y470383D01*
X578183Y470883D01*
X578100Y471467D01*
X578183Y472050D01*
X578517Y472550D01*
X579017Y472967D01*
X579683Y473133D01*
X580267Y473050D01*
X580683Y472883D01*
X581100Y472550D01*
G01X585200Y474800D02*
Y469800D01*
G01X584033Y473133D02*
X586367D01*
G01X589383Y469800D02*
Y474800D01*
G01Y472383D02*
X589800Y472800D01*
X590217Y473050D01*
X590883Y473133D01*
X591383Y473050D01*
X591967Y472717D01*
X592217Y472217D01*
Y469800D01*
G01X600750Y470383D02*
X601167Y470050D01*
X601750Y469800D01*
X602250D01*
X602750Y469967D01*
X603083Y470217D01*
X603250Y470550D01*
X603167Y471050D01*
X602833Y471300D01*
X601333Y471800D01*
X601000Y472383D01*
X601167Y472800D01*
X601500Y473050D01*
X602000Y473133D01*
X602500Y473050D01*
X603000Y472800D01*
G01X606100Y468133D02*
Y473133D01*
G01Y472383D02*
X606517Y472800D01*
X606933Y473050D01*
X607600Y473133D01*
X608183Y473050D01*
X608767Y472633D01*
X609017Y472050D01*
X609100Y471467D01*
X609017Y470883D01*
X608767Y470300D01*
X608267Y469967D01*
X607600Y469800D01*
X607017Y469883D01*
X606433Y470133D01*
X606100Y470467D01*
G01X611950Y472050D02*
X614617D01*
X614367Y472633D01*
X613950Y472967D01*
X613367Y473133D01*
X612783Y473050D01*
X612283Y472800D01*
X611950Y472217D01*
X611783Y471717D01*
Y471217D01*
X611950Y470717D01*
X612367Y470217D01*
X612867Y469883D01*
X613450Y469800D01*
X614033Y469967D01*
X614617Y470467D01*
G01X620133Y472717D02*
X619550Y473050D01*
X619050Y473133D01*
X618383Y472967D01*
X617883Y472633D01*
X617550Y472050D01*
X617467Y471467D01*
X617550Y470883D01*
X617883Y470383D01*
X618383Y469967D01*
X619050Y469800D01*
X619633Y469967D01*
X620133Y470300D01*
G01X624400Y473133D02*
Y469800D01*
G01Y474467D02*
X624233Y474550D01*
Y474717D01*
X624400Y474800D01*
X624567Y474717D01*
Y474550D01*
X624400Y474467D01*
G01X629500Y469800D02*
Y474050D01*
X629667Y474467D01*
X630000Y474717D01*
X630500Y474800D01*
X631000Y474633D01*
X631250Y474217D01*
G01X630250Y472800D02*
X628583D01*
G01X635600Y473133D02*
Y469800D01*
G01Y474467D02*
X635433Y474550D01*
Y474717D01*
X635600Y474800D01*
X635767Y474717D01*
Y474550D01*
X635600Y474467D01*
G01X639950Y472050D02*
X642617D01*
X642367Y472633D01*
X641950Y472967D01*
X641367Y473133D01*
X640783Y473050D01*
X640283Y472800D01*
X639950Y472217D01*
X639783Y471717D01*
Y471217D01*
X639950Y470717D01*
X640367Y470217D01*
X640867Y469883D01*
X641450Y469800D01*
X642033Y469967D01*
X642617Y470467D01*
G01X648300Y474800D02*
Y469800D01*
G01Y470550D02*
X647967Y470133D01*
X647467Y469883D01*
X646883Y469800D01*
X646217Y469967D01*
X645717Y470383D01*
X645383Y470883D01*
X645300Y471467D01*
X645383Y472050D01*
X645717Y472550D01*
X646217Y472967D01*
X646883Y473133D01*
X647467Y473050D01*
X647883Y472883D01*
X648300Y472550D01*
G01X658000Y469800D02*
X657500Y469883D01*
X657000Y470217D01*
X656667Y470800D01*
X656500Y471467D01*
X656667Y472133D01*
X657000Y472717D01*
X657500Y473050D01*
X658000Y473133D01*
X658500Y473050D01*
X659000Y472717D01*
X659333Y472133D01*
X659417Y471467D01*
X659333Y470800D01*
X659000Y470217D01*
X658500Y469883D01*
X658000Y469800D01*
G01X662183D02*
Y473133D01*
G01Y472300D02*
X662517Y472717D01*
X663017Y473050D01*
X663683Y473133D01*
X664267Y473050D01*
X664767Y472717D01*
X665017Y472133D01*
Y469800D01*
G01X674800Y474800D02*
Y469800D01*
G01X673633Y473133D02*
X675967D01*
G01X678983Y469800D02*
Y474800D01*
G01Y472383D02*
X679400Y472800D01*
X679817Y473050D01*
X680483Y473133D01*
X680983Y473050D01*
X681567Y472717D01*
X681817Y472217D01*
Y469800D01*
G01X684750Y472050D02*
X687417D01*
X687167Y472633D01*
X686750Y472967D01*
X686167Y473133D01*
X685583Y473050D01*
X685083Y472800D01*
X684750Y472217D01*
X684583Y471717D01*
Y471217D01*
X684750Y470717D01*
X685167Y470217D01*
X685667Y469883D01*
X686250Y469800D01*
X686833Y469967D01*
X687417Y470467D01*
G01X381850Y480300D02*
Y485300D01*
G01X385350D02*
Y480300D01*
G01Y482800D02*
X381850D01*
G01X389200Y480300D02*
X388700Y480383D01*
X388200Y480717D01*
X387867Y481300D01*
X387700Y481967D01*
X387867Y482633D01*
X388200Y483217D01*
X388700Y483550D01*
X389200Y483633D01*
X389700Y483550D01*
X390200Y483217D01*
X390533Y482633D01*
X390617Y481967D01*
X390533Y481300D01*
X390200Y480717D01*
X389700Y480383D01*
X389200Y480300D01*
G01X392717Y483633D02*
X393717Y480300D01*
X394800Y483633D01*
X395883Y480300D01*
X396883Y483633D01*
G01X399150Y482550D02*
X401817D01*
X401567Y483133D01*
X401150Y483467D01*
X400567Y483633D01*
X399983Y483550D01*
X399483Y483300D01*
X399150Y482717D01*
X398983Y482217D01*
Y481717D01*
X399150Y481217D01*
X399567Y480717D01*
X400067Y480383D01*
X400650Y480300D01*
X401233Y480467D01*
X401817Y480967D01*
G01X404500Y483633D02*
X406000Y480300D01*
X407500Y483633D01*
G01X410350Y482550D02*
X413017D01*
X412767Y483133D01*
X412350Y483467D01*
X411767Y483633D01*
X411183Y483550D01*
X410683Y483300D01*
X410350Y482717D01*
X410183Y482217D01*
Y481717D01*
X410350Y481217D01*
X410767Y480717D01*
X411267Y480383D01*
X411850Y480300D01*
X412433Y480467D01*
X413017Y480967D01*
G01X416033Y480300D02*
Y483633D01*
G01Y482967D02*
X416450Y483300D01*
X416867Y483550D01*
X417450Y483633D01*
X417867Y483550D01*
X418367Y483300D01*
G01X422633Y479383D02*
X422967Y480467D01*
G01X428400Y485300D02*
Y480300D01*
G01X427233Y483633D02*
X429567D01*
G01X432583Y480300D02*
Y485300D01*
G01Y482883D02*
X433000Y483300D01*
X433417Y483550D01*
X434083Y483633D01*
X434583Y483550D01*
X435167Y483217D01*
X435417Y482717D01*
Y480300D01*
G01X438350Y482550D02*
X441017D01*
X440767Y483133D01*
X440350Y483467D01*
X439767Y483633D01*
X439183Y483550D01*
X438683Y483300D01*
X438350Y482717D01*
X438183Y482217D01*
Y481717D01*
X438350Y481217D01*
X438767Y480717D01*
X439267Y480383D01*
X439850Y480300D01*
X440433Y480467D01*
X441017Y480967D01*
G01X450800Y485300D02*
Y480300D01*
G01X449633Y483633D02*
X451967D01*
G01X457900Y480300D02*
Y483633D01*
G01Y483050D02*
X457567Y483383D01*
X457067Y483550D01*
X456483Y483633D01*
X455900Y483467D01*
X455400Y483133D01*
X455067Y482633D01*
X454900Y481967D01*
X455067Y481300D01*
X455400Y480800D01*
X455900Y480467D01*
X456483Y480300D01*
X457067Y480383D01*
X457567Y480633D01*
X457900Y480967D01*
G01X460583Y480300D02*
Y483633D01*
G01Y482800D02*
X460917Y483217D01*
X461417Y483550D01*
X462083Y483633D01*
X462667Y483550D01*
X463167Y483217D01*
X463417Y482633D01*
Y480300D01*
G01X466433Y479050D02*
X467017Y478717D01*
X467683Y478633D01*
X468267Y478717D01*
X468767Y479133D01*
X469100Y479717D01*
Y483633D01*
G01Y482967D02*
X468767Y483300D01*
X468267Y483550D01*
X467683Y483633D01*
X467017Y483467D01*
X466600Y483133D01*
X466267Y482550D01*
X466100Y481967D01*
X466183Y481467D01*
X466517Y480883D01*
X467017Y480467D01*
X467683Y480300D01*
X468183Y480383D01*
X468767Y480717D01*
X469100Y481050D01*
G01X471950Y482550D02*
X474617D01*
X474367Y483133D01*
X473950Y483467D01*
X473367Y483633D01*
X472783Y483550D01*
X472283Y483300D01*
X471950Y482717D01*
X471783Y482217D01*
Y481717D01*
X471950Y481217D01*
X472367Y480717D01*
X472867Y480383D01*
X473450Y480300D01*
X474033Y480467D01*
X474617Y480967D01*
G01X477383Y480300D02*
Y483633D01*
G01Y482800D02*
X477717Y483217D01*
X478217Y483550D01*
X478883Y483633D01*
X479467Y483550D01*
X479967Y483217D01*
X480217Y482633D01*
Y480300D01*
G01X485733Y483217D02*
X485150Y483550D01*
X484650Y483633D01*
X483983Y483467D01*
X483483Y483133D01*
X483150Y482550D01*
X483067Y481967D01*
X483150Y481383D01*
X483483Y480883D01*
X483983Y480467D01*
X484650Y480300D01*
X485233Y480467D01*
X485733Y480800D01*
G01X488250Y478800D02*
X488750Y478633D01*
X489417Y478800D01*
X489833Y479133D01*
X490167Y479550D01*
X490667Y480883D01*
X491750Y483633D01*
G01X489083D02*
X490667Y480883D01*
G01X499950D02*
X500367Y480550D01*
X500950Y480300D01*
X501450D01*
X501950Y480467D01*
X502283Y480717D01*
X502450Y481050D01*
X502367Y481550D01*
X502033Y481800D01*
X500533Y482300D01*
X500200Y482883D01*
X500367Y483300D01*
X500700Y483550D01*
X501200Y483633D01*
X501700Y483550D01*
X502200Y483300D01*
G01X505383Y480300D02*
Y485300D01*
G01Y482883D02*
X505800Y483300D01*
X506217Y483550D01*
X506883Y483633D01*
X507383Y483550D01*
X507967Y483217D01*
X508217Y482717D01*
Y480300D01*
G01X512400D02*
X511900Y480383D01*
X511400Y480717D01*
X511067Y481300D01*
X510900Y481967D01*
X511067Y482633D01*
X511400Y483217D01*
X511900Y483550D01*
X512400Y483633D01*
X512900Y483550D01*
X513400Y483217D01*
X513733Y482633D01*
X513817Y481967D01*
X513733Y481300D01*
X513400Y480717D01*
X512900Y480383D01*
X512400Y480300D01*
G01X516583Y483633D02*
Y481300D01*
X516917Y480717D01*
X517417Y480383D01*
X518000Y480300D01*
X518583Y480383D01*
X519083Y480717D01*
X519417Y481300D01*
G01Y480300D02*
Y483633D01*
G01X523600Y480300D02*
Y485300D01*
G01X530700D02*
Y480300D01*
G01Y481050D02*
X530367Y480633D01*
X529867Y480383D01*
X529283Y480300D01*
X528617Y480467D01*
X528117Y480883D01*
X527783Y481383D01*
X527700Y481967D01*
X527783Y482550D01*
X528117Y483050D01*
X528617Y483467D01*
X529283Y483633D01*
X529867Y483550D01*
X530283Y483383D01*
X530700Y483050D01*
G01X538983Y480300D02*
Y483633D01*
G01Y482800D02*
X539317Y483217D01*
X539817Y483550D01*
X540483Y483633D01*
X541067Y483550D01*
X541567Y483217D01*
X541817Y482633D01*
Y480300D01*
G01X546000D02*
X545500Y480383D01*
X545000Y480717D01*
X544667Y481300D01*
X544500Y481967D01*
X544667Y482633D01*
X545000Y483217D01*
X545500Y483550D01*
X546000Y483633D01*
X546500Y483550D01*
X547000Y483217D01*
X547333Y482633D01*
X547417Y481967D01*
X547333Y481300D01*
X547000Y480717D01*
X546500Y480383D01*
X546000Y480300D01*
G01X551600Y485300D02*
Y480300D01*
G01X550433Y483633D02*
X552767D01*
G01X561633Y480300D02*
Y483633D01*
G01Y482967D02*
X562050Y483300D01*
X562467Y483550D01*
X563050Y483633D01*
X563467Y483550D01*
X563967Y483300D01*
G01X567150Y482550D02*
X569817D01*
X569567Y483133D01*
X569150Y483467D01*
X568567Y483633D01*
X567983Y483550D01*
X567483Y483300D01*
X567150Y482717D01*
X566983Y482217D01*
Y481717D01*
X567150Y481217D01*
X567567Y480717D01*
X568067Y480383D01*
X568650Y480300D01*
X569233Y480467D01*
X569817Y480967D01*
G01X575500Y485300D02*
Y480300D01*
G01Y481050D02*
X575167Y480633D01*
X574667Y480383D01*
X574083Y480300D01*
X573417Y480467D01*
X572917Y480883D01*
X572583Y481383D01*
X572500Y481967D01*
X572583Y482550D01*
X572917Y483050D01*
X573417Y483467D01*
X574083Y483633D01*
X574667Y483550D01*
X575083Y483383D01*
X575500Y483050D01*
G01X578183Y483633D02*
Y481300D01*
X578517Y480717D01*
X579017Y480383D01*
X579600Y480300D01*
X580183Y480383D01*
X580683Y480717D01*
X581017Y481300D01*
G01Y480300D02*
Y483633D01*
G01X586533Y483217D02*
X585950Y483550D01*
X585450Y483633D01*
X584783Y483467D01*
X584283Y483133D01*
X583950Y482550D01*
X583867Y481967D01*
X583950Y481383D01*
X584283Y480883D01*
X584783Y480467D01*
X585450Y480300D01*
X586033Y480467D01*
X586533Y480800D01*
G01X589550Y482550D02*
X592217D01*
X591967Y483133D01*
X591550Y483467D01*
X590967Y483633D01*
X590383Y483550D01*
X589883Y483300D01*
X589550Y482717D01*
X589383Y482217D01*
Y481717D01*
X589550Y481217D01*
X589967Y480717D01*
X590467Y480383D01*
X591050Y480300D01*
X591633Y480467D01*
X592217Y480967D01*
G01X602000Y485300D02*
Y480300D01*
G01X600833Y483633D02*
X603167D01*
G01X606183Y480300D02*
Y485300D01*
G01Y482883D02*
X606600Y483300D01*
X607017Y483550D01*
X607683Y483633D01*
X608183Y483550D01*
X608767Y483217D01*
X609017Y482717D01*
Y480300D01*
G01X611950Y482550D02*
X614617D01*
X614367Y483133D01*
X613950Y483467D01*
X613367Y483633D01*
X612783Y483550D01*
X612283Y483300D01*
X611950Y482717D01*
X611783Y482217D01*
Y481717D01*
X611950Y481217D01*
X612367Y480717D01*
X612867Y480383D01*
X613450Y480300D01*
X614033Y480467D01*
X614617Y480967D01*
G01X624400Y480300D02*
Y485300D01*
G01X631500Y480300D02*
Y483633D01*
G01Y483050D02*
X631167Y483383D01*
X630667Y483550D01*
X630083Y483633D01*
X629500Y483467D01*
X629000Y483133D01*
X628667Y482633D01*
X628500Y481967D01*
X628667Y481300D01*
X629000Y480800D01*
X629500Y480467D01*
X630083Y480300D01*
X630667Y480383D01*
X631167Y480633D01*
X631500Y480967D01*
G01X634183Y480300D02*
Y483633D01*
G01Y482800D02*
X634517Y483217D01*
X635017Y483550D01*
X635683Y483633D01*
X636267Y483550D01*
X636767Y483217D01*
X637017Y482633D01*
Y480300D01*
G01X642700Y485300D02*
Y480300D01*
G01Y481050D02*
X642367Y480633D01*
X641867Y480383D01*
X641283Y480300D01*
X640617Y480467D01*
X640117Y480883D01*
X639783Y481383D01*
X639700Y481967D01*
X639783Y482550D01*
X640117Y483050D01*
X640617Y483467D01*
X641283Y483633D01*
X641867Y483550D01*
X642283Y483383D01*
X642700Y483050D01*
G01X645300Y480133D02*
X648300Y485300D01*
G01X653733Y483217D02*
X653150Y483550D01*
X652650Y483633D01*
X651983Y483467D01*
X651483Y483133D01*
X651150Y482550D01*
X651067Y481967D01*
X651150Y481383D01*
X651483Y480883D01*
X651983Y480467D01*
X652650Y480300D01*
X653233Y480467D01*
X653733Y480800D01*
G01X658000Y480300D02*
X657500Y480383D01*
X657000Y480717D01*
X656667Y481300D01*
X656500Y481967D01*
X656667Y482633D01*
X657000Y483217D01*
X657500Y483550D01*
X658000Y483633D01*
X658500Y483550D01*
X659000Y483217D01*
X659333Y482633D01*
X659417Y481967D01*
X659333Y481300D01*
X659000Y480717D01*
X658500Y480383D01*
X658000Y480300D01*
G01X662183D02*
Y483633D01*
G01Y482800D02*
X662517Y483217D01*
X663017Y483550D01*
X663683Y483633D01*
X664267Y483550D01*
X664767Y483217D01*
X665017Y482633D01*
Y480300D01*
G01X670700Y485300D02*
Y480300D01*
G01Y481050D02*
X670367Y480633D01*
X669867Y480383D01*
X669283Y480300D01*
X668617Y480467D01*
X668117Y480883D01*
X667783Y481383D01*
X667700Y481967D01*
X667783Y482550D01*
X668117Y483050D01*
X668617Y483467D01*
X669283Y483633D01*
X669867Y483550D01*
X670283Y483383D01*
X670700Y483050D01*
G01X673383Y483633D02*
Y481300D01*
X673717Y480717D01*
X674217Y480383D01*
X674800Y480300D01*
X675383Y480383D01*
X675883Y480717D01*
X676217Y481300D01*
G01Y480300D02*
Y483633D01*
G01X681733Y483217D02*
X681150Y483550D01*
X680650Y483633D01*
X679983Y483467D01*
X679483Y483133D01*
X679150Y482550D01*
X679067Y481967D01*
X679150Y481383D01*
X679483Y480883D01*
X679983Y480467D01*
X680650Y480300D01*
X681233Y480467D01*
X681733Y480800D01*
G01X686000Y485300D02*
Y480300D01*
G01X684833Y483633D02*
X687167D01*
G01X691600Y480300D02*
X691100Y480383D01*
X690600Y480717D01*
X690267Y481300D01*
X690100Y481967D01*
X690267Y482633D01*
X690600Y483217D01*
X691100Y483550D01*
X691600Y483633D01*
X692100Y483550D01*
X692600Y483217D01*
X692933Y482633D01*
X693017Y481967D01*
X692933Y481300D01*
X692600Y480717D01*
X692100Y480383D01*
X691600Y480300D01*
G01X696033D02*
Y483633D01*
G01Y482967D02*
X696450Y483300D01*
X696867Y483550D01*
X697450Y483633D01*
X697867Y483550D01*
X698367Y483300D01*
G01X385100Y490800D02*
Y494133D01*
G01Y493550D02*
X384767Y493883D01*
X384267Y494050D01*
X383683Y494133D01*
X383100Y493967D01*
X382600Y493633D01*
X382267Y493133D01*
X382100Y492467D01*
X382267Y491800D01*
X382600Y491300D01*
X383100Y490967D01*
X383683Y490800D01*
X384267Y490883D01*
X384767Y491133D01*
X385100Y491467D01*
G01X390533Y493717D02*
X389950Y494050D01*
X389450Y494133D01*
X388783Y493967D01*
X388283Y493633D01*
X387950Y493050D01*
X387867Y492467D01*
X387950Y491883D01*
X388283Y491383D01*
X388783Y490967D01*
X389450Y490800D01*
X390033Y490967D01*
X390533Y491300D01*
G01X396133Y493717D02*
X395550Y494050D01*
X395050Y494133D01*
X394383Y493967D01*
X393883Y493633D01*
X393550Y493050D01*
X393467Y492467D01*
X393550Y491883D01*
X393883Y491383D01*
X394383Y490967D01*
X395050Y490800D01*
X395633Y490967D01*
X396133Y491300D01*
G01X399150Y493050D02*
X401817D01*
X401567Y493633D01*
X401150Y493967D01*
X400567Y494133D01*
X399983Y494050D01*
X399483Y493800D01*
X399150Y493217D01*
X398983Y492717D01*
Y492217D01*
X399150Y491717D01*
X399567Y491217D01*
X400067Y490883D01*
X400650Y490800D01*
X401233Y490967D01*
X401817Y491467D01*
G01X404500Y489133D02*
Y494133D01*
G01Y493383D02*
X404917Y493800D01*
X405333Y494050D01*
X406000Y494133D01*
X406583Y494050D01*
X407167Y493633D01*
X407417Y493050D01*
X407500Y492467D01*
X407417Y491883D01*
X407167Y491300D01*
X406667Y490967D01*
X406000Y490800D01*
X405417Y490883D01*
X404833Y491133D01*
X404500Y491467D01*
G01X411600Y495800D02*
Y490800D01*
G01X410433Y494133D02*
X412767D01*
G01X418700Y490800D02*
Y494133D01*
G01Y493550D02*
X418367Y493883D01*
X417867Y494050D01*
X417283Y494133D01*
X416700Y493967D01*
X416200Y493633D01*
X415867Y493133D01*
X415700Y492467D01*
X415867Y491800D01*
X416200Y491300D01*
X416700Y490967D01*
X417283Y490800D01*
X417867Y490883D01*
X418367Y491133D01*
X418700Y491467D01*
G01X421300Y490800D02*
Y495800D01*
G01Y493300D02*
X421717Y493800D01*
X422217Y494050D01*
X422717Y494133D01*
X423467Y493967D01*
X423967Y493633D01*
X424300Y493050D01*
Y492383D01*
X424133Y491717D01*
X423800Y491217D01*
X423217Y490883D01*
X422717Y490800D01*
X422217Y490883D01*
X421717Y491133D01*
X421300Y491550D01*
G01X428400Y490800D02*
Y495800D01*
G01X432750Y493050D02*
X435417D01*
X435167Y493633D01*
X434750Y493967D01*
X434167Y494133D01*
X433583Y494050D01*
X433083Y493800D01*
X432750Y493217D01*
X432583Y492717D01*
Y492217D01*
X432750Y491717D01*
X433167Y491217D01*
X433667Y490883D01*
X434250Y490800D01*
X434833Y490967D01*
X435417Y491467D01*
G01X439600Y490633D02*
X439433Y490717D01*
Y490883D01*
X439600Y490967D01*
X439767Y490883D01*
Y490717D01*
X439600Y490633D01*
G01X383600Y506300D02*
Y501300D01*
G01X381683Y506300D02*
X385517D01*
G01X387783Y501300D02*
Y506300D01*
G01Y503883D02*
X388200Y504300D01*
X388617Y504550D01*
X389283Y504633D01*
X389783Y504550D01*
X390367Y504217D01*
X390617Y503717D01*
Y501300D01*
G01X393550Y503550D02*
X396217D01*
X395967Y504133D01*
X395550Y504467D01*
X394967Y504633D01*
X394383Y504550D01*
X393883Y504300D01*
X393550Y503717D01*
X393383Y503217D01*
Y502717D01*
X393550Y502217D01*
X393967Y501717D01*
X394467Y501383D01*
X395050Y501300D01*
X395633Y501467D01*
X396217Y501967D01*
G01X404500Y501300D02*
Y506300D01*
G01Y503800D02*
X404917Y504300D01*
X405417Y504550D01*
X405917Y504633D01*
X406667Y504467D01*
X407167Y504133D01*
X407500Y503550D01*
Y502883D01*
X407333Y502217D01*
X407000Y501717D01*
X406417Y501383D01*
X405917Y501300D01*
X405417Y501383D01*
X404917Y501633D01*
X404500Y502050D01*
G01X410433Y501300D02*
Y504633D01*
G01Y503967D02*
X410850Y504300D01*
X411267Y504550D01*
X411850Y504633D01*
X412267Y504550D01*
X412767Y504300D01*
G01X415950Y503550D02*
X418617D01*
X418367Y504133D01*
X417950Y504467D01*
X417367Y504633D01*
X416783Y504550D01*
X416283Y504300D01*
X415950Y503717D01*
X415783Y503217D01*
Y502717D01*
X415950Y502217D01*
X416367Y501717D01*
X416867Y501383D01*
X417450Y501300D01*
X418033Y501467D01*
X418617Y501967D01*
G01X424300Y501300D02*
Y504633D01*
G01Y504050D02*
X423967Y504383D01*
X423467Y504550D01*
X422883Y504633D01*
X422300Y504467D01*
X421800Y504133D01*
X421467Y503633D01*
X421300Y502967D01*
X421467Y502300D01*
X421800Y501800D01*
X422300Y501467D01*
X422883Y501300D01*
X423467Y501383D01*
X423967Y501633D01*
X424300Y501967D01*
G01X426983Y501300D02*
Y506300D01*
G01X429650Y504633D02*
X426983Y502717D01*
G01X428067Y503467D02*
X429817Y501300D01*
G01X434000D02*
X433500Y501383D01*
X433000Y501717D01*
X432667Y502300D01*
X432500Y502967D01*
X432667Y503633D01*
X433000Y504217D01*
X433500Y504550D01*
X434000Y504633D01*
X434500Y504550D01*
X435000Y504217D01*
X435333Y503633D01*
X435417Y502967D01*
X435333Y502300D01*
X435000Y501717D01*
X434500Y501383D01*
X434000Y501300D01*
G01X438183Y504633D02*
Y502300D01*
X438517Y501717D01*
X439017Y501383D01*
X439600Y501300D01*
X440183Y501383D01*
X440683Y501717D01*
X441017Y502300D01*
G01Y501300D02*
Y504633D01*
G01X445200Y506300D02*
Y501300D01*
G01X444033Y504633D02*
X446367D01*
G01X456400D02*
Y501300D01*
G01Y505967D02*
X456233Y506050D01*
Y506217D01*
X456400Y506300D01*
X456567Y506217D01*
Y506050D01*
X456400Y505967D01*
G01X460750Y501883D02*
X461167Y501550D01*
X461750Y501300D01*
X462250D01*
X462750Y501467D01*
X463083Y501717D01*
X463250Y502050D01*
X463167Y502550D01*
X462833Y502800D01*
X461333Y503300D01*
X461000Y503883D01*
X461167Y504300D01*
X461500Y504550D01*
X462000Y504633D01*
X462500Y504550D01*
X463000Y504300D01*
G01X471783Y501300D02*
Y504633D01*
G01Y503800D02*
X472117Y504217D01*
X472617Y504550D01*
X473283Y504633D01*
X473867Y504550D01*
X474367Y504217D01*
X474617Y503633D01*
Y501300D01*
G01X478800D02*
X478300Y501383D01*
X477800Y501717D01*
X477467Y502300D01*
X477300Y502967D01*
X477467Y503633D01*
X477800Y504217D01*
X478300Y504550D01*
X478800Y504633D01*
X479300Y504550D01*
X479800Y504217D01*
X480133Y503633D01*
X480217Y502967D01*
X480133Y502300D01*
X479800Y501717D01*
X479300Y501383D01*
X478800Y501300D01*
G01X484400Y506300D02*
Y501300D01*
G01X483233Y504633D02*
X485567D01*
G01X497100Y501300D02*
Y504633D01*
G01Y504050D02*
X496767Y504383D01*
X496267Y504550D01*
X495683Y504633D01*
X495100Y504467D01*
X494600Y504133D01*
X494267Y503633D01*
X494100Y502967D01*
X494267Y502300D01*
X494600Y501800D01*
X495100Y501467D01*
X495683Y501300D01*
X496267Y501383D01*
X496767Y501633D01*
X497100Y501967D01*
G01X501200Y501300D02*
Y506300D01*
G01X506800Y501300D02*
Y506300D01*
G01X512400Y501300D02*
X511900Y501383D01*
X511400Y501717D01*
X511067Y502300D01*
X510900Y502967D01*
X511067Y503633D01*
X511400Y504217D01*
X511900Y504550D01*
X512400Y504633D01*
X512900Y504550D01*
X513400Y504217D01*
X513733Y503633D01*
X513817Y502967D01*
X513733Y502300D01*
X513400Y501717D01*
X512900Y501383D01*
X512400Y501300D01*
G01X515917Y504633D02*
X516917Y501300D01*
X518000Y504633D01*
X519083Y501300D01*
X520083Y504633D01*
G01X522350Y503550D02*
X525017D01*
X524767Y504133D01*
X524350Y504467D01*
X523767Y504633D01*
X523183Y504550D01*
X522683Y504300D01*
X522350Y503717D01*
X522183Y503217D01*
Y502717D01*
X522350Y502217D01*
X522767Y501717D01*
X523267Y501383D01*
X523850Y501300D01*
X524433Y501467D01*
X525017Y501967D01*
G01X530700Y506300D02*
Y501300D01*
G01Y502050D02*
X530367Y501633D01*
X529867Y501383D01*
X529283Y501300D01*
X528617Y501467D01*
X528117Y501883D01*
X527783Y502383D01*
X527700Y502967D01*
X527783Y503550D01*
X528117Y504050D01*
X528617Y504467D01*
X529283Y504633D01*
X529867Y504550D01*
X530283Y504383D01*
X530700Y504050D01*
G01X534633Y500383D02*
X534967Y501467D01*
G01X550100Y501300D02*
Y506300D01*
G01Y503800D02*
X550517Y504300D01*
X551017Y504550D01*
X551517Y504633D01*
X552267Y504467D01*
X552767Y504133D01*
X553100Y503550D01*
Y502883D01*
X552933Y502217D01*
X552600Y501717D01*
X552017Y501383D01*
X551517Y501300D01*
X551017Y501383D01*
X550517Y501633D01*
X550100Y502050D01*
G01X555783Y504633D02*
Y502300D01*
X556117Y501717D01*
X556617Y501383D01*
X557200Y501300D01*
X557783Y501383D01*
X558283Y501717D01*
X558617Y502300D01*
G01Y501300D02*
Y504633D01*
G01X562800Y506300D02*
Y501300D01*
G01X561633Y504633D02*
X563967D01*
G01X575500Y501300D02*
Y504633D01*
G01Y504050D02*
X575167Y504383D01*
X574667Y504550D01*
X574083Y504633D01*
X573500Y504467D01*
X573000Y504133D01*
X572667Y503633D01*
X572500Y502967D01*
X572667Y502300D01*
X573000Y501800D01*
X573500Y501467D01*
X574083Y501300D01*
X574667Y501383D01*
X575167Y501633D01*
X575500Y501967D01*
G01X578183Y501300D02*
Y504633D01*
G01Y503800D02*
X578517Y504217D01*
X579017Y504550D01*
X579683Y504633D01*
X580267Y504550D01*
X580767Y504217D01*
X581017Y503633D01*
Y501300D01*
G01X583783D02*
Y504633D01*
G01Y503800D02*
X584117Y504217D01*
X584617Y504550D01*
X585283Y504633D01*
X585867Y504550D01*
X586367Y504217D01*
X586617Y503633D01*
Y501300D01*
G01X589383Y504633D02*
Y502300D01*
X589717Y501717D01*
X590217Y501383D01*
X590800Y501300D01*
X591383Y501383D01*
X591883Y501717D01*
X592217Y502300D01*
G01Y501300D02*
Y504633D01*
G01X597900Y501300D02*
Y504633D01*
G01Y504050D02*
X597567Y504383D01*
X597067Y504550D01*
X596483Y504633D01*
X595900Y504467D01*
X595400Y504133D01*
X595067Y503633D01*
X594900Y502967D01*
X595067Y502300D01*
X595400Y501800D01*
X595900Y501467D01*
X596483Y501300D01*
X597067Y501383D01*
X597567Y501633D01*
X597900Y501967D01*
G01X602000Y501300D02*
Y506300D01*
G01X612033Y501300D02*
Y504633D01*
G01Y503967D02*
X612450Y504300D01*
X612867Y504550D01*
X613450Y504633D01*
X613867Y504550D01*
X614367Y504300D01*
G01X618800Y504633D02*
Y501300D01*
G01Y505967D02*
X618633Y506050D01*
Y506217D01*
X618800Y506300D01*
X618967Y506217D01*
Y506050D01*
X618800Y505967D01*
G01X622983Y501300D02*
Y504633D01*
G01Y503800D02*
X623317Y504217D01*
X623817Y504550D01*
X624483Y504633D01*
X625067Y504550D01*
X625567Y504217D01*
X625817Y503633D01*
Y501300D01*
G01X628833Y500050D02*
X629417Y499717D01*
X630083Y499633D01*
X630667Y499717D01*
X631167Y500133D01*
X631500Y500717D01*
Y504633D01*
G01Y503967D02*
X631167Y504300D01*
X630667Y504550D01*
X630083Y504633D01*
X629417Y504467D01*
X629000Y504133D01*
X628667Y503550D01*
X628500Y502967D01*
X628583Y502467D01*
X628917Y501883D01*
X629417Y501467D01*
X630083Y501300D01*
X630583Y501383D01*
X631167Y501717D01*
X631500Y502050D01*
G01X641200Y506300D02*
Y501300D01*
G01X640033Y504633D02*
X642367D01*
G01X648300Y501300D02*
Y504633D01*
G01Y504050D02*
X647967Y504383D01*
X647467Y504550D01*
X646883Y504633D01*
X646300Y504467D01*
X645800Y504133D01*
X645467Y503633D01*
X645300Y502967D01*
X645467Y502300D01*
X645800Y501800D01*
X646300Y501467D01*
X646883Y501300D01*
X647467Y501383D01*
X647967Y501633D01*
X648300Y501967D01*
G01X650983Y501300D02*
Y504633D01*
G01Y503800D02*
X651317Y504217D01*
X651817Y504550D01*
X652483Y504633D01*
X653067Y504550D01*
X653567Y504217D01*
X653817Y503633D01*
Y501300D01*
G01X656833Y500050D02*
X657417Y499717D01*
X658083Y499633D01*
X658667Y499717D01*
X659167Y500133D01*
X659500Y500717D01*
Y504633D01*
G01Y503967D02*
X659167Y504300D01*
X658667Y504550D01*
X658083Y504633D01*
X657417Y504467D01*
X657000Y504133D01*
X656667Y503550D01*
X656500Y502967D01*
X656583Y502467D01*
X656917Y501883D01*
X657417Y501467D01*
X658083Y501300D01*
X658583Y501383D01*
X659167Y501717D01*
X659500Y502050D01*
G01X662350Y503550D02*
X665017D01*
X664767Y504133D01*
X664350Y504467D01*
X663767Y504633D01*
X663183Y504550D01*
X662683Y504300D01*
X662350Y503717D01*
X662183Y503217D01*
Y502717D01*
X662350Y502217D01*
X662767Y501717D01*
X663267Y501383D01*
X663850Y501300D01*
X664433Y501467D01*
X665017Y501967D01*
G01X667783Y501300D02*
Y504633D01*
G01Y503800D02*
X668117Y504217D01*
X668617Y504550D01*
X669283Y504633D01*
X669867Y504550D01*
X670367Y504217D01*
X670617Y503633D01*
Y501300D01*
G01X676133Y504217D02*
X675550Y504550D01*
X675050Y504633D01*
X674383Y504467D01*
X673883Y504133D01*
X673550Y503550D01*
X673467Y502967D01*
X673550Y502383D01*
X673883Y501883D01*
X674383Y501467D01*
X675050Y501300D01*
X675633Y501467D01*
X676133Y501800D01*
G01X678650Y499800D02*
X679150Y499633D01*
X679817Y499800D01*
X680233Y500133D01*
X680567Y500550D01*
X681067Y501883D01*
X682150Y504633D01*
G01X679483D02*
X681067Y501883D01*
G01X691600Y504633D02*
Y501300D01*
G01Y505967D02*
X691433Y506050D01*
Y506217D01*
X691600Y506300D01*
X691767Y506217D01*
Y506050D01*
X691600Y505967D01*
G01X695950Y501883D02*
X696367Y501550D01*
X696950Y501300D01*
X697450D01*
X697950Y501467D01*
X698283Y501717D01*
X698450Y502050D01*
X698367Y502550D01*
X698033Y502800D01*
X696533Y503300D01*
X696200Y503883D01*
X696367Y504300D01*
X696700Y504550D01*
X697200Y504633D01*
X697700Y504550D01*
X698200Y504300D01*
G01X376100Y485800D02*
Y767800D01*
G01X386600Y526300D02*
Y521300D01*
G01Y522050D02*
X386267Y521633D01*
X385767Y521383D01*
X385183Y521300D01*
X384517Y521467D01*
X384017Y521883D01*
X383683Y522383D01*
X383600Y522967D01*
X383683Y523550D01*
X384017Y524050D01*
X384517Y524467D01*
X385183Y524633D01*
X385767Y524550D01*
X386183Y524383D01*
X386600Y524050D01*
G01X389450Y523550D02*
X392117D01*
X391867Y524133D01*
X391450Y524467D01*
X390867Y524633D01*
X390283Y524550D01*
X389783Y524300D01*
X389450Y523717D01*
X389283Y523217D01*
Y522717D01*
X389450Y522217D01*
X389867Y521717D01*
X390367Y521383D01*
X390950Y521300D01*
X391533Y521467D01*
X392117Y521967D01*
G01X394800Y519633D02*
Y524633D01*
G01Y523883D02*
X395217Y524300D01*
X395633Y524550D01*
X396300Y524633D01*
X396883Y524550D01*
X397467Y524133D01*
X397717Y523550D01*
X397800Y522967D01*
X397717Y522383D01*
X397467Y521800D01*
X396967Y521467D01*
X396300Y521300D01*
X395717Y521383D01*
X395133Y521633D01*
X394800Y521967D01*
G01X401900Y526300D02*
Y521300D01*
G01X400733Y524633D02*
X403067D01*
G01X406083Y521300D02*
Y526300D01*
G01Y523883D02*
X406500Y524300D01*
X406917Y524550D01*
X407583Y524633D01*
X408083Y524550D01*
X408667Y524217D01*
X408917Y523717D01*
Y521300D01*
G01X418700Y526300D02*
Y521300D01*
G01X417533Y524633D02*
X419867D01*
G01X424300Y521300D02*
X423800Y521383D01*
X423300Y521717D01*
X422967Y522300D01*
X422800Y522967D01*
X422967Y523633D01*
X423300Y524217D01*
X423800Y524550D01*
X424300Y524633D01*
X424800Y524550D01*
X425300Y524217D01*
X425633Y523633D01*
X425717Y522967D01*
X425633Y522300D01*
X425300Y521717D01*
X424800Y521383D01*
X424300Y521300D01*
G01X429900D02*
Y526300D01*
G01X434250Y523550D02*
X436917D01*
X436667Y524133D01*
X436250Y524467D01*
X435667Y524633D01*
X435083Y524550D01*
X434583Y524300D01*
X434250Y523717D01*
X434083Y523217D01*
Y522717D01*
X434250Y522217D01*
X434667Y521717D01*
X435167Y521383D01*
X435750Y521300D01*
X436333Y521467D01*
X436917Y521967D01*
G01X439933Y521300D02*
Y524633D01*
G01Y523967D02*
X440350Y524300D01*
X440767Y524550D01*
X441350Y524633D01*
X441767Y524550D01*
X442267Y524300D01*
G01X448200Y521300D02*
Y524633D01*
G01Y524050D02*
X447867Y524383D01*
X447367Y524550D01*
X446783Y524633D01*
X446200Y524467D01*
X445700Y524133D01*
X445367Y523633D01*
X445200Y522967D01*
X445367Y522300D01*
X445700Y521800D01*
X446200Y521467D01*
X446783Y521300D01*
X447367Y521383D01*
X447867Y521633D01*
X448200Y521967D01*
G01X450883Y521300D02*
Y524633D01*
G01Y523800D02*
X451217Y524217D01*
X451717Y524550D01*
X452383Y524633D01*
X452967Y524550D01*
X453467Y524217D01*
X453717Y523633D01*
Y521300D01*
G01X459233Y524217D02*
X458650Y524550D01*
X458150Y524633D01*
X457483Y524467D01*
X456983Y524133D01*
X456650Y523550D01*
X456567Y522967D01*
X456650Y522383D01*
X456983Y521883D01*
X457483Y521467D01*
X458150Y521300D01*
X458733Y521467D01*
X459233Y521800D01*
G01X462250Y523550D02*
X464917D01*
X464667Y524133D01*
X464250Y524467D01*
X463667Y524633D01*
X463083Y524550D01*
X462583Y524300D01*
X462250Y523717D01*
X462083Y523217D01*
Y522717D01*
X462250Y522217D01*
X462667Y521717D01*
X463167Y521383D01*
X463750Y521300D01*
X464333Y521467D01*
X464917Y521967D01*
G01X384350Y542300D02*
Y547300D01*
G01X387850D02*
Y542300D01*
G01Y544800D02*
X384350D01*
G01X391700Y542300D02*
X391200Y542383D01*
X390700Y542717D01*
X390367Y543300D01*
X390200Y543967D01*
X390367Y544633D01*
X390700Y545217D01*
X391200Y545550D01*
X391700Y545633D01*
X392200Y545550D01*
X392700Y545217D01*
X393033Y544633D01*
X393117Y543967D01*
X393033Y543300D01*
X392700Y542717D01*
X392200Y542383D01*
X391700Y542300D01*
G01X397300D02*
Y547300D01*
G01X401650Y544550D02*
X404317D01*
X404067Y545133D01*
X403650Y545467D01*
X403067Y545633D01*
X402483Y545550D01*
X401983Y545300D01*
X401650Y544717D01*
X401483Y544217D01*
Y543717D01*
X401650Y543217D01*
X402067Y542717D01*
X402567Y542383D01*
X403150Y542300D01*
X403733Y542467D01*
X404317Y542967D01*
G01X411600Y547300D02*
X412767Y542300D01*
X414100Y547300D01*
X415433Y542300D01*
X416600Y547300D01*
G01X421200Y542300D02*
Y545633D01*
G01Y545050D02*
X420867Y545383D01*
X420367Y545550D01*
X419783Y545633D01*
X419200Y545467D01*
X418700Y545133D01*
X418367Y544633D01*
X418200Y543967D01*
X418367Y543300D01*
X418700Y542800D01*
X419200Y542467D01*
X419783Y542300D01*
X420367Y542383D01*
X420867Y542633D01*
X421200Y542967D01*
G01X425300Y542300D02*
Y547300D01*
G01X430900Y542300D02*
Y547300D01*
G01X440433Y542300D02*
Y547300D01*
X442517D01*
X443183Y547050D01*
X443600Y546717D01*
X443767Y546050D01*
X443600Y545383D01*
X443100Y544967D01*
X442517Y544717D01*
X440433D01*
G01X442517D02*
X443767Y542300D01*
G01X447700D02*
X447200Y542383D01*
X446700Y542717D01*
X446367Y543300D01*
X446200Y543967D01*
X446367Y544633D01*
X446700Y545217D01*
X447200Y545550D01*
X447700Y545633D01*
X448200Y545550D01*
X448700Y545217D01*
X449033Y544633D01*
X449117Y543967D01*
X449033Y543300D01*
X448700Y542717D01*
X448200Y542383D01*
X447700Y542300D01*
G01X451883Y545633D02*
Y543300D01*
X452217Y542717D01*
X452717Y542383D01*
X453300Y542300D01*
X453883Y542383D01*
X454383Y542717D01*
X454717Y543300D01*
G01Y542300D02*
Y545633D01*
G01X457733Y541050D02*
X458317Y540717D01*
X458983Y540633D01*
X459567Y540717D01*
X460067Y541133D01*
X460400Y541717D01*
Y545633D01*
G01Y544967D02*
X460067Y545300D01*
X459567Y545550D01*
X458983Y545633D01*
X458317Y545467D01*
X457900Y545133D01*
X457567Y544550D01*
X457400Y543967D01*
X457483Y543467D01*
X457817Y542883D01*
X458317Y542467D01*
X458983Y542300D01*
X459483Y542383D01*
X460067Y542717D01*
X460400Y543050D01*
G01X463083Y542300D02*
Y547300D01*
G01Y544883D02*
X463500Y545300D01*
X463917Y545550D01*
X464583Y545633D01*
X465083Y545550D01*
X465667Y545217D01*
X465917Y544717D01*
Y542300D01*
G01X468683D02*
Y545633D01*
G01Y544800D02*
X469017Y545217D01*
X469517Y545550D01*
X470183Y545633D01*
X470767Y545550D01*
X471267Y545217D01*
X471517Y544633D01*
Y542300D01*
G01X474450Y544550D02*
X477117D01*
X476867Y545133D01*
X476450Y545467D01*
X475867Y545633D01*
X475283Y545550D01*
X474783Y545300D01*
X474450Y544717D01*
X474283Y544217D01*
Y543717D01*
X474450Y543217D01*
X474867Y542717D01*
X475367Y542383D01*
X475950Y542300D01*
X476533Y542467D01*
X477117Y542967D01*
G01X480050Y542883D02*
X480467Y542550D01*
X481050Y542300D01*
X481550D01*
X482050Y542467D01*
X482383Y542717D01*
X482550Y543050D01*
X482467Y543550D01*
X482133Y543800D01*
X480633Y544300D01*
X480300Y544883D01*
X480467Y545300D01*
X480800Y545550D01*
X481300Y545633D01*
X481800Y545550D01*
X482300Y545300D01*
G01X485650Y542883D02*
X486067Y542550D01*
X486650Y542300D01*
X487150D01*
X487650Y542467D01*
X487983Y542717D01*
X488150Y543050D01*
X488067Y543550D01*
X487733Y543800D01*
X486233Y544300D01*
X485900Y544883D01*
X486067Y545300D01*
X486400Y545550D01*
X486900Y545633D01*
X487400Y545550D01*
X487900Y545300D01*
G01X386100Y558800D02*
X385433Y558883D01*
X384850Y559217D01*
X384350Y559717D01*
X384017Y560300D01*
X383850Y560967D01*
Y561633D01*
X384017Y562300D01*
X384350Y562883D01*
X384850Y563383D01*
X385433Y563717D01*
X386100Y563800D01*
X386767Y563717D01*
X387350Y563383D01*
X387850Y562883D01*
X388183Y562300D01*
X388350Y561633D01*
Y560967D01*
X388183Y560300D01*
X387850Y559717D01*
X387350Y559217D01*
X386767Y558883D01*
X386100Y558800D01*
G01X391700Y563800D02*
Y558800D01*
G01X390533Y562133D02*
X392867D01*
G01X395883Y558800D02*
Y563800D01*
G01Y561383D02*
X396300Y561800D01*
X396717Y562050D01*
X397383Y562133D01*
X397883Y562050D01*
X398467Y561717D01*
X398717Y561217D01*
Y558800D01*
G01X401650Y561050D02*
X404317D01*
X404067Y561633D01*
X403650Y561967D01*
X403067Y562133D01*
X402483Y562050D01*
X401983Y561800D01*
X401650Y561217D01*
X401483Y560717D01*
Y560217D01*
X401650Y559717D01*
X402067Y559217D01*
X402567Y558883D01*
X403150Y558800D01*
X403733Y558967D01*
X404317Y559467D01*
G01X407333Y558800D02*
Y562133D01*
G01Y561467D02*
X407750Y561800D01*
X408167Y562050D01*
X408750Y562133D01*
X409167Y562050D01*
X409667Y561800D01*
G01X412850Y559383D02*
X413267Y559050D01*
X413850Y558800D01*
X414350D01*
X414850Y558967D01*
X415183Y559217D01*
X415350Y559550D01*
X415267Y560050D01*
X414933Y560300D01*
X413433Y560800D01*
X413100Y561383D01*
X413267Y561800D01*
X413600Y562050D01*
X414100Y562133D01*
X414600Y562050D01*
X415100Y561800D01*
G01X424883Y557133D02*
X424050Y557967D01*
X423633Y558800D01*
Y562133D01*
X424050Y562967D01*
X424883Y563800D01*
G01X430900Y558800D02*
Y563800D01*
G01X436500Y562133D02*
Y558800D01*
G01Y563467D02*
X436333Y563550D01*
Y563717D01*
X436500Y563800D01*
X436667Y563717D01*
Y563550D01*
X436500Y563467D01*
G01X440683Y558800D02*
Y563800D01*
G01X443350Y562133D02*
X440683Y560217D01*
G01X441767Y560967D02*
X443517Y558800D01*
G01X446450Y561050D02*
X449117D01*
X448867Y561633D01*
X448450Y561967D01*
X447867Y562133D01*
X447283Y562050D01*
X446783Y561800D01*
X446450Y561217D01*
X446283Y560717D01*
Y560217D01*
X446450Y559717D01*
X446867Y559217D01*
X447367Y558883D01*
X447950Y558800D01*
X448533Y558967D01*
X449117Y559467D01*
G01X457650Y561050D02*
X460317D01*
X460067Y561633D01*
X459650Y561967D01*
X459067Y562133D01*
X458483Y562050D01*
X457983Y561800D01*
X457650Y561217D01*
X457483Y560717D01*
Y560217D01*
X457650Y559717D01*
X458067Y559217D01*
X458567Y558883D01*
X459150Y558800D01*
X459733Y558967D01*
X460317Y559467D01*
G01X464500Y558800D02*
Y563800D01*
G01X470100Y558800D02*
Y563800D01*
G01X475700Y562133D02*
Y558800D01*
G01Y563467D02*
X475533Y563550D01*
Y563717D01*
X475700Y563800D01*
X475867Y563717D01*
Y563550D01*
X475700Y563467D01*
G01X479800Y557133D02*
Y562133D01*
G01Y561383D02*
X480217Y561800D01*
X480633Y562050D01*
X481300Y562133D01*
X481883Y562050D01*
X482467Y561633D01*
X482717Y561050D01*
X482800Y560467D01*
X482717Y559883D01*
X482467Y559300D01*
X481967Y558967D01*
X481300Y558800D01*
X480717Y558883D01*
X480133Y559133D01*
X479800Y559467D01*
G01X485650Y559383D02*
X486067Y559050D01*
X486650Y558800D01*
X487150D01*
X487650Y558967D01*
X487983Y559217D01*
X488150Y559550D01*
X488067Y560050D01*
X487733Y560300D01*
X486233Y560800D01*
X485900Y561383D01*
X486067Y561800D01*
X486400Y562050D01*
X486900Y562133D01*
X487400Y562050D01*
X487900Y561800D01*
G01X491250Y561050D02*
X493917D01*
X493667Y561633D01*
X493250Y561967D01*
X492667Y562133D01*
X492083Y562050D01*
X491583Y561800D01*
X491250Y561217D01*
X491083Y560717D01*
Y560217D01*
X491250Y559717D01*
X491667Y559217D01*
X492167Y558883D01*
X492750Y558800D01*
X493333Y558967D01*
X493917Y559467D01*
G01X505200Y558800D02*
Y562133D01*
G01Y561550D02*
X504867Y561883D01*
X504367Y562050D01*
X503783Y562133D01*
X503200Y561967D01*
X502700Y561633D01*
X502367Y561133D01*
X502200Y560467D01*
X502367Y559800D01*
X502700Y559300D01*
X503200Y558967D01*
X503783Y558800D01*
X504367Y558883D01*
X504867Y559133D01*
X505200Y559467D01*
G01X507883Y558800D02*
Y562133D01*
G01Y561300D02*
X508217Y561717D01*
X508717Y562050D01*
X509383Y562133D01*
X509967Y562050D01*
X510467Y561717D01*
X510717Y561133D01*
Y558800D01*
G01X516400Y563800D02*
Y558800D01*
G01Y559550D02*
X516067Y559133D01*
X515567Y558883D01*
X514983Y558800D01*
X514317Y558967D01*
X513817Y559383D01*
X513483Y559883D01*
X513400Y560467D01*
X513483Y561050D01*
X513817Y561550D01*
X514317Y561967D01*
X514983Y562133D01*
X515567Y562050D01*
X515983Y561883D01*
X516400Y561550D01*
G01X526100Y558800D02*
X525600Y558883D01*
X525100Y559217D01*
X524767Y559800D01*
X524600Y560467D01*
X524767Y561133D01*
X525100Y561717D01*
X525600Y562050D01*
X526100Y562133D01*
X526600Y562050D01*
X527100Y561717D01*
X527433Y561133D01*
X527517Y560467D01*
X527433Y559800D01*
X527100Y559217D01*
X526600Y558883D01*
X526100Y558800D01*
G01X531700Y563800D02*
Y558800D01*
G01X530533Y562133D02*
X532867D01*
G01X535883Y558800D02*
Y563800D01*
G01Y561383D02*
X536300Y561800D01*
X536717Y562050D01*
X537383Y562133D01*
X537883Y562050D01*
X538467Y561717D01*
X538717Y561217D01*
Y558800D01*
G01X541650Y561050D02*
X544317D01*
X544067Y561633D01*
X543650Y561967D01*
X543067Y562133D01*
X542483Y562050D01*
X541983Y561800D01*
X541650Y561217D01*
X541483Y560717D01*
Y560217D01*
X541650Y559717D01*
X542067Y559217D01*
X542567Y558883D01*
X543150Y558800D01*
X543733Y558967D01*
X544317Y559467D01*
G01X547333Y558800D02*
Y562133D01*
G01Y561467D02*
X547750Y561800D01*
X548167Y562050D01*
X548750Y562133D01*
X549167Y562050D01*
X549667Y561800D01*
G01X552850Y559383D02*
X553267Y559050D01*
X553850Y558800D01*
X554350D01*
X554850Y558967D01*
X555183Y559217D01*
X555350Y559550D01*
X555267Y560050D01*
X554933Y560300D01*
X553433Y560800D01*
X553100Y561383D01*
X553267Y561800D01*
X553600Y562050D01*
X554100Y562133D01*
X554600Y562050D01*
X555100Y561800D01*
G01X560117Y557133D02*
X560950Y557967D01*
X561367Y558800D01*
Y562133D01*
X560950Y562967D01*
X560117Y563800D01*
G01X384433Y573800D02*
Y578800D01*
X386433D01*
X387100Y578550D01*
X387600Y577967D01*
X387767Y577300D01*
X387600Y576633D01*
X387183Y576133D01*
X386433Y575883D01*
X384433D01*
G01X391700Y578800D02*
Y573800D01*
G01X389783Y578800D02*
X393617D01*
G01X395550Y573800D02*
Y578800D01*
G01X399050D02*
Y573800D01*
G01Y576300D02*
X395550D01*
G01X401400Y573633D02*
X404400Y578800D01*
G01X406583Y573800D02*
Y578800D01*
X410417Y573800D01*
Y578800D01*
G01X412433Y573800D02*
Y578800D01*
X414433D01*
X415100Y578550D01*
X415600Y577967D01*
X415767Y577300D01*
X415600Y576633D01*
X415183Y576133D01*
X414433Y575883D01*
X412433D01*
G01X419700Y578800D02*
Y573800D01*
G01X417783Y578800D02*
X421617D01*
G01X423550Y573800D02*
Y578800D01*
G01X427050D02*
Y573800D01*
G01Y576300D02*
X423550D01*
G01X434833Y573800D02*
X438167Y575467D01*
X434833Y577133D01*
G01X441017Y574717D02*
X443183D01*
G01Y576217D02*
X441017D01*
G01X445867Y574550D02*
X446367Y574133D01*
X446950Y573883D01*
X447700Y573800D01*
X448450Y573967D01*
X449033Y574300D01*
X449450Y574883D01*
X449533Y575550D01*
X449367Y576217D01*
X448950Y576633D01*
X448367Y576967D01*
X447783Y577050D01*
X447200Y576967D01*
X446450Y576633D01*
X446700Y578800D01*
X448950D01*
G01X456400Y573800D02*
Y577133D01*
G01Y576217D02*
X456650Y576633D01*
X457067Y576967D01*
X457650Y577133D01*
X458233Y576967D01*
X458650Y576633D01*
X458900Y576217D01*
Y573800D01*
G01Y576217D02*
X459150Y576633D01*
X459567Y576967D01*
X460150Y577133D01*
X460733Y576967D01*
X461150Y576633D01*
X461400Y576133D01*
Y573800D01*
G01X462000D02*
Y577133D01*
G01Y576217D02*
X462250Y576633D01*
X462667Y576967D01*
X463250Y577133D01*
X463833Y576967D01*
X464250Y576633D01*
X464500Y576217D01*
Y573800D01*
G01Y576217D02*
X464750Y576633D01*
X465167Y576967D01*
X465750Y577133D01*
X466333Y576967D01*
X466750Y576633D01*
X467000Y576133D01*
Y573800D01*
G01X384183Y587300D02*
Y592300D01*
X388017Y587300D01*
Y592300D01*
G01X390033Y587300D02*
Y592300D01*
X392033D01*
X392700Y592050D01*
X393200Y591467D01*
X393367Y590800D01*
X393200Y590133D01*
X392783Y589633D01*
X392033Y589383D01*
X390033D01*
G01X397300Y592300D02*
Y587300D01*
G01X395383Y592300D02*
X399217D01*
G01X401150Y587300D02*
Y592300D01*
G01X404650D02*
Y587300D01*
G01Y589800D02*
X401150D01*
G01X412350Y587967D02*
X413017Y587550D01*
X413767Y587300D01*
X414433D01*
X415100Y587550D01*
X415600Y587967D01*
X415850Y588550D01*
X415683Y589133D01*
X415267Y589633D01*
X414517Y589967D01*
X413517Y590133D01*
X412933Y590467D01*
X412683Y591050D01*
X412850Y591633D01*
X413267Y592050D01*
X413850Y592300D01*
X414433D01*
X415017Y592133D01*
X415517Y591717D01*
G01X419700Y590633D02*
Y587300D01*
G01Y591967D02*
X419533Y592050D01*
Y592217D01*
X419700Y592300D01*
X419867Y592217D01*
Y592050D01*
X419700Y591967D01*
G01X424050Y590633D02*
X426550D01*
X424050Y587300D01*
X426550D01*
G01X429650Y589550D02*
X432317D01*
X432067Y590133D01*
X431650Y590467D01*
X431067Y590633D01*
X430483Y590550D01*
X429983Y590300D01*
X429650Y589717D01*
X429483Y589217D01*
Y588717D01*
X429650Y588217D01*
X430067Y587717D01*
X430567Y587383D01*
X431150Y587300D01*
X431733Y587467D01*
X432317Y587967D01*
G01X440267Y588300D02*
X440767Y587717D01*
X441433Y587383D01*
X442183Y587300D01*
X442850Y587383D01*
X443517Y587800D01*
X443933Y588300D01*
X444017Y588800D01*
X443850Y589383D01*
X443267Y589800D01*
X442683Y589967D01*
X441933D01*
G01X442683D02*
X443183Y590217D01*
X443600Y590633D01*
X443767Y591133D01*
X443600Y591633D01*
X443183Y592050D01*
X442433Y592300D01*
X441683Y592217D01*
X440933Y591883D01*
G01X447700Y587133D02*
X447533Y587217D01*
Y587383D01*
X447700Y587467D01*
X447867Y587383D01*
Y587217D01*
X447700Y587133D01*
G01X451467Y588050D02*
X451967Y587633D01*
X452550Y587383D01*
X453300Y587300D01*
X454050Y587467D01*
X454633Y587800D01*
X455050Y588383D01*
X455133Y589050D01*
X454967Y589717D01*
X454550Y590133D01*
X453967Y590467D01*
X453383Y590550D01*
X452800Y590467D01*
X452050Y590133D01*
X452300Y592300D01*
X454550D01*
G01X457067Y588050D02*
X457567Y587633D01*
X458150Y587383D01*
X458900Y587300D01*
X459650Y587467D01*
X460233Y587800D01*
X460650Y588383D01*
X460733Y589050D01*
X460567Y589717D01*
X460150Y590133D01*
X459567Y590467D01*
X458983Y590550D01*
X458400Y590467D01*
X457650Y590133D01*
X457900Y592300D01*
X460150D01*
G01X462000Y587300D02*
Y590633D01*
G01Y589717D02*
X462250Y590133D01*
X462667Y590467D01*
X463250Y590633D01*
X463833Y590467D01*
X464250Y590133D01*
X464500Y589717D01*
Y587300D01*
G01Y589717D02*
X464750Y590133D01*
X465167Y590467D01*
X465750Y590633D01*
X466333Y590467D01*
X466750Y590133D01*
X467000Y589633D01*
Y587300D01*
G01X467600D02*
Y590633D01*
G01Y589717D02*
X467850Y590133D01*
X468267Y590467D01*
X468850Y590633D01*
X469433Y590467D01*
X469850Y590133D01*
X470100Y589717D01*
Y587300D01*
G01Y589717D02*
X470350Y590133D01*
X470767Y590467D01*
X471350Y590633D01*
X471933Y590467D01*
X472350Y590133D01*
X472600Y589633D01*
Y587300D01*
G01X376100Y567800D02*
X808100D01*
G01X376100Y582800D02*
X808100D01*
G01X376100Y597800D02*
X808100D01*
G01X384183Y602300D02*
Y607300D01*
X388017Y602300D01*
Y607300D01*
G01X390033Y602300D02*
Y607300D01*
X392033D01*
X392700Y607050D01*
X393200Y606467D01*
X393367Y605800D01*
X393200Y605133D01*
X392783Y604633D01*
X392033Y604383D01*
X390033D01*
G01X397300Y607300D02*
Y602300D01*
G01X395383Y607300D02*
X399217D01*
G01X401150Y602300D02*
Y607300D01*
G01X404650D02*
Y602300D01*
G01Y604800D02*
X401150D01*
G01X412350Y602967D02*
X413017Y602550D01*
X413767Y602300D01*
X414433D01*
X415100Y602550D01*
X415600Y602967D01*
X415850Y603550D01*
X415683Y604133D01*
X415267Y604633D01*
X414517Y604967D01*
X413517Y605133D01*
X412933Y605467D01*
X412683Y606050D01*
X412850Y606633D01*
X413267Y607050D01*
X413850Y607300D01*
X414433D01*
X415017Y607133D01*
X415517Y606717D01*
G01X419700Y605633D02*
Y602300D01*
G01Y606967D02*
X419533Y607050D01*
Y607217D01*
X419700Y607300D01*
X419867Y607217D01*
Y607050D01*
X419700Y606967D01*
G01X424050Y605633D02*
X426550D01*
X424050Y602300D01*
X426550D01*
G01X429650Y604550D02*
X432317D01*
X432067Y605133D01*
X431650Y605467D01*
X431067Y605633D01*
X430483Y605550D01*
X429983Y605300D01*
X429650Y604717D01*
X429483Y604217D01*
Y603717D01*
X429650Y603217D01*
X430067Y602717D01*
X430567Y602383D01*
X431150Y602300D01*
X431733Y602467D01*
X432317Y602967D01*
G01X438167Y602300D02*
X434833Y603967D01*
X438167Y605633D01*
G01X445867Y603050D02*
X446367Y602633D01*
X446950Y602383D01*
X447700Y602300D01*
X448450Y602467D01*
X449033Y602800D01*
X449450Y603383D01*
X449533Y604050D01*
X449367Y604717D01*
X448950Y605133D01*
X448367Y605467D01*
X447783Y605550D01*
X447200Y605467D01*
X446450Y605133D01*
X446700Y607300D01*
X448950D01*
G01X450800Y602300D02*
Y605633D01*
G01Y604717D02*
X451050Y605133D01*
X451467Y605467D01*
X452050Y605633D01*
X452633Y605467D01*
X453050Y605133D01*
X453300Y604717D01*
Y602300D01*
G01Y604717D02*
X453550Y605133D01*
X453967Y605467D01*
X454550Y605633D01*
X455133Y605467D01*
X455550Y605133D01*
X455800Y604633D01*
Y602300D01*
G01X456400D02*
Y605633D01*
G01Y604717D02*
X456650Y605133D01*
X457067Y605467D01*
X457650Y605633D01*
X458233Y605467D01*
X458650Y605133D01*
X458900Y604717D01*
Y602300D01*
G01Y604717D02*
X459150Y605133D01*
X459567Y605467D01*
X460150Y605633D01*
X460733Y605467D01*
X461150Y605133D01*
X461400Y604633D01*
Y602300D01*
G01X384267Y623800D02*
Y620217D01*
X384600Y619467D01*
X385267Y618967D01*
X386100Y618800D01*
X386933Y618967D01*
X387600Y619467D01*
X387933Y620217D01*
Y623800D01*
G01X390283Y618800D02*
Y622133D01*
G01Y621300D02*
X390617Y621717D01*
X391117Y622050D01*
X391783Y622133D01*
X392367Y622050D01*
X392867Y621717D01*
X393117Y621133D01*
Y618800D01*
G01X396217Y620467D02*
X398383D01*
G01X401400Y617133D02*
Y622133D01*
G01Y621383D02*
X401817Y621800D01*
X402233Y622050D01*
X402900Y622133D01*
X403483Y622050D01*
X404067Y621633D01*
X404317Y621050D01*
X404400Y620467D01*
X404317Y619883D01*
X404067Y619300D01*
X403567Y618967D01*
X402900Y618800D01*
X402317Y618883D01*
X401733Y619133D01*
X401400Y619467D01*
G01X408500Y618800D02*
Y623800D01*
G01X412683Y622133D02*
Y619800D01*
X413017Y619217D01*
X413517Y618883D01*
X414100Y618800D01*
X414683Y618883D01*
X415183Y619217D01*
X415517Y619800D01*
G01Y618800D02*
Y622133D01*
G01X418533Y617550D02*
X419117Y617217D01*
X419783Y617133D01*
X420367Y617217D01*
X420867Y617633D01*
X421200Y618217D01*
Y622133D01*
G01Y621467D02*
X420867Y621800D01*
X420367Y622050D01*
X419783Y622133D01*
X419117Y621967D01*
X418700Y621633D01*
X418367Y621050D01*
X418200Y620467D01*
X418283Y619967D01*
X418617Y619383D01*
X419117Y618967D01*
X419783Y618800D01*
X420283Y618883D01*
X420867Y619217D01*
X421200Y619550D01*
G01X424133Y617550D02*
X424717Y617217D01*
X425383Y617133D01*
X425967Y617217D01*
X426467Y617633D01*
X426800Y618217D01*
Y622133D01*
G01Y621467D02*
X426467Y621800D01*
X425967Y622050D01*
X425383Y622133D01*
X424717Y621967D01*
X424300Y621633D01*
X423967Y621050D01*
X423800Y620467D01*
X423883Y619967D01*
X424217Y619383D01*
X424717Y618967D01*
X425383Y618800D01*
X425883Y618883D01*
X426467Y619217D01*
X426800Y619550D01*
G01X429650Y621050D02*
X432317D01*
X432067Y621633D01*
X431650Y621967D01*
X431067Y622133D01*
X430483Y622050D01*
X429983Y621800D01*
X429650Y621217D01*
X429483Y620717D01*
Y620217D01*
X429650Y619717D01*
X430067Y619217D01*
X430567Y618883D01*
X431150Y618800D01*
X431733Y618967D01*
X432317Y619467D01*
G01X438000Y623800D02*
Y618800D01*
G01Y619550D02*
X437667Y619133D01*
X437167Y618883D01*
X436583Y618800D01*
X435917Y618967D01*
X435417Y619383D01*
X435083Y619883D01*
X435000Y620467D01*
X435083Y621050D01*
X435417Y621550D01*
X435917Y621967D01*
X436583Y622133D01*
X437167Y622050D01*
X437583Y621883D01*
X438000Y621550D01*
G01X446033Y618800D02*
Y623800D01*
X448033D01*
X448700Y623550D01*
X449200Y622967D01*
X449367Y622300D01*
X449200Y621633D01*
X448783Y621133D01*
X448033Y620883D01*
X446033D01*
G01X453300Y623800D02*
Y618800D01*
G01X451383Y623800D02*
X455217D01*
G01X457150Y618800D02*
Y623800D01*
G01X460650D02*
Y618800D01*
G01Y621300D02*
X457150D01*
G01X469683Y617133D02*
X468850Y617967D01*
X468433Y618800D01*
Y622133D01*
X468850Y622967D01*
X469683Y623800D01*
G01X473950Y618800D02*
Y623800D01*
G01X477450D02*
Y618800D01*
G01Y621300D02*
X473950D01*
G01X481300Y618800D02*
X480800Y618883D01*
X480300Y619217D01*
X479967Y619800D01*
X479800Y620467D01*
X479967Y621133D01*
X480300Y621717D01*
X480800Y622050D01*
X481300Y622133D01*
X481800Y622050D01*
X482300Y621717D01*
X482633Y621133D01*
X482717Y620467D01*
X482633Y619800D01*
X482300Y619217D01*
X481800Y618883D01*
X481300Y618800D01*
G01X486900D02*
Y623800D01*
G01X491250Y621050D02*
X493917D01*
X493667Y621633D01*
X493250Y621967D01*
X492667Y622133D01*
X492083Y622050D01*
X491583Y621800D01*
X491250Y621217D01*
X491083Y620717D01*
Y620217D01*
X491250Y619717D01*
X491667Y619217D01*
X492167Y618883D01*
X492750Y618800D01*
X493333Y618967D01*
X493917Y619467D01*
G01X501950D02*
X502617Y619050D01*
X503367Y618800D01*
X504033D01*
X504700Y619050D01*
X505200Y619467D01*
X505450Y620050D01*
X505283Y620633D01*
X504867Y621133D01*
X504117Y621467D01*
X503117Y621633D01*
X502533Y621967D01*
X502283Y622550D01*
X502450Y623133D01*
X502867Y623550D01*
X503450Y623800D01*
X504033D01*
X504617Y623633D01*
X505117Y623217D01*
G01X509300Y622133D02*
Y618800D01*
G01Y623467D02*
X509133Y623550D01*
Y623717D01*
X509300Y623800D01*
X509467Y623717D01*
Y623550D01*
X509300Y623467D01*
G01X513650Y622133D02*
X516150D01*
X513650Y618800D01*
X516150D01*
G01X519250Y621050D02*
X521917D01*
X521667Y621633D01*
X521250Y621967D01*
X520667Y622133D01*
X520083Y622050D01*
X519583Y621800D01*
X519250Y621217D01*
X519083Y620717D01*
Y620217D01*
X519250Y619717D01*
X519667Y619217D01*
X520167Y618883D01*
X520750Y618800D01*
X521333Y618967D01*
X521917Y619467D01*
G01X527767Y618800D02*
X524433Y620467D01*
X527767Y622133D01*
G01X531700Y618800D02*
Y623800D01*
X530700Y622800D01*
G01Y618800D02*
X532700D01*
G01X535883Y619383D02*
X536467Y618967D01*
X537133Y618800D01*
X537800Y618967D01*
X538383Y619467D01*
X538800Y620217D01*
X538967Y620967D01*
Y621883D01*
X538800Y622633D01*
X538383Y623300D01*
X537883Y623633D01*
X537300Y623800D01*
X536633Y623633D01*
X536133Y623300D01*
X535800Y622800D01*
X535633Y622133D01*
X535800Y621550D01*
X536217Y620967D01*
X536717Y620633D01*
X537300Y620550D01*
X537967Y620717D01*
X538467Y621133D01*
X538967Y621883D01*
G01X542733Y618800D02*
X542900Y619883D01*
X543150Y620800D01*
X543483Y621633D01*
X543900Y622550D01*
X544567Y623800D01*
X541233D01*
G01X546000Y618800D02*
Y622133D01*
G01Y621217D02*
X546250Y621633D01*
X546667Y621967D01*
X547250Y622133D01*
X547833Y621967D01*
X548250Y621633D01*
X548500Y621217D01*
Y618800D01*
G01Y621217D02*
X548750Y621633D01*
X549167Y621967D01*
X549750Y622133D01*
X550333Y621967D01*
X550750Y621633D01*
X551000Y621133D01*
Y618800D01*
G01X554100Y622133D02*
Y618800D01*
G01Y623467D02*
X553933Y623550D01*
Y623717D01*
X554100Y623800D01*
X554267Y623717D01*
Y623550D01*
X554100Y623467D01*
G01X559700Y618800D02*
Y623800D01*
G01X568817Y622133D02*
X569817Y618800D01*
X570900Y622133D01*
X571983Y618800D01*
X572983Y622133D01*
G01X576500D02*
Y618800D01*
G01Y623467D02*
X576333Y623550D01*
Y623717D01*
X576500Y623800D01*
X576667Y623717D01*
Y623550D01*
X576500Y623467D01*
G01X582100Y623800D02*
Y618800D01*
G01X580933Y622133D02*
X583267D01*
G01X586283Y618800D02*
Y623800D01*
G01Y621383D02*
X586700Y621800D01*
X587117Y622050D01*
X587783Y622133D01*
X588283Y622050D01*
X588867Y621717D01*
X589117Y621217D01*
Y618800D01*
G01X597150D02*
Y623800D01*
G01X600650D02*
Y618800D01*
G01Y621300D02*
X597150D01*
G01X602417Y618800D02*
X604500Y623800D01*
X606583Y618800D01*
G01X605833Y620550D02*
X603167D01*
G01X608350Y619467D02*
X609017Y619050D01*
X609767Y618800D01*
X610433D01*
X611100Y619050D01*
X611600Y619467D01*
X611850Y620050D01*
X611683Y620633D01*
X611267Y621133D01*
X610517Y621467D01*
X609517Y621633D01*
X608933Y621967D01*
X608683Y622550D01*
X608850Y623133D01*
X609267Y623550D01*
X609850Y623800D01*
X610433D01*
X611017Y623633D01*
X611517Y623217D01*
G01X614033Y623800D02*
Y618800D01*
X617367D01*
G01X625400Y617133D02*
Y622133D01*
G01Y621383D02*
X625817Y621800D01*
X626233Y622050D01*
X626900Y622133D01*
X627483Y622050D01*
X628067Y621633D01*
X628317Y621050D01*
X628400Y620467D01*
X628317Y619883D01*
X628067Y619300D01*
X627567Y618967D01*
X626900Y618800D01*
X626317Y618883D01*
X625733Y619133D01*
X625400Y619467D01*
G01X631333Y618800D02*
Y622133D01*
G01Y621467D02*
X631750Y621800D01*
X632167Y622050D01*
X632750Y622133D01*
X633167Y622050D01*
X633667Y621800D01*
G01X638100Y618800D02*
X637600Y618883D01*
X637100Y619217D01*
X636767Y619800D01*
X636600Y620467D01*
X636767Y621133D01*
X637100Y621717D01*
X637600Y622050D01*
X638100Y622133D01*
X638600Y622050D01*
X639100Y621717D01*
X639433Y621133D01*
X639517Y620467D01*
X639433Y619800D01*
X639100Y619217D01*
X638600Y618883D01*
X638100Y618800D01*
G01X645200Y623800D02*
Y618800D01*
G01Y619550D02*
X644867Y619133D01*
X644367Y618883D01*
X643783Y618800D01*
X643117Y618967D01*
X642617Y619383D01*
X642283Y619883D01*
X642200Y620467D01*
X642283Y621050D01*
X642617Y621550D01*
X643117Y621967D01*
X643783Y622133D01*
X644367Y622050D01*
X644783Y621883D01*
X645200Y621550D01*
G01X647883Y622133D02*
Y619800D01*
X648217Y619217D01*
X648717Y618883D01*
X649300Y618800D01*
X649883Y618883D01*
X650383Y619217D01*
X650717Y619800D01*
G01Y618800D02*
Y622133D01*
G01X656233Y621717D02*
X655650Y622050D01*
X655150Y622133D01*
X654483Y621967D01*
X653983Y621633D01*
X653650Y621050D01*
X653567Y620467D01*
X653650Y619883D01*
X653983Y619383D01*
X654483Y618967D01*
X655150Y618800D01*
X655733Y618967D01*
X656233Y619300D01*
G01X660500Y623800D02*
Y618800D01*
G01X659333Y622133D02*
X661667D01*
G01X664850Y619383D02*
X665267Y619050D01*
X665850Y618800D01*
X666350D01*
X666850Y618967D01*
X667183Y619217D01*
X667350Y619550D01*
X667267Y620050D01*
X666933Y620300D01*
X665433Y620800D01*
X665100Y621383D01*
X665267Y621800D01*
X665600Y622050D01*
X666100Y622133D01*
X666600Y622050D01*
X667100Y621800D01*
G01X672117Y617133D02*
X672950Y617967D01*
X673367Y618800D01*
Y622133D01*
X672950Y622967D01*
X672117Y623800D01*
G01X384267Y638800D02*
Y635217D01*
X384600Y634467D01*
X385267Y633967D01*
X386100Y633800D01*
X386933Y633967D01*
X387600Y634467D01*
X387933Y635217D01*
Y638800D01*
G01X390283Y633800D02*
Y637133D01*
G01Y636300D02*
X390617Y636717D01*
X391117Y637050D01*
X391783Y637133D01*
X392367Y637050D01*
X392867Y636717D01*
X393117Y636133D01*
Y633800D01*
G01X396217Y635467D02*
X398383D01*
G01X401400Y632133D02*
Y637133D01*
G01Y636383D02*
X401817Y636800D01*
X402233Y637050D01*
X402900Y637133D01*
X403483Y637050D01*
X404067Y636633D01*
X404317Y636050D01*
X404400Y635467D01*
X404317Y634883D01*
X404067Y634300D01*
X403567Y633967D01*
X402900Y633800D01*
X402317Y633883D01*
X401733Y634133D01*
X401400Y634467D01*
G01X408500Y633800D02*
Y638800D01*
G01X412683Y637133D02*
Y634800D01*
X413017Y634217D01*
X413517Y633883D01*
X414100Y633800D01*
X414683Y633883D01*
X415183Y634217D01*
X415517Y634800D01*
G01Y633800D02*
Y637133D01*
G01X418533Y632550D02*
X419117Y632217D01*
X419783Y632133D01*
X420367Y632217D01*
X420867Y632633D01*
X421200Y633217D01*
Y637133D01*
G01Y636467D02*
X420867Y636800D01*
X420367Y637050D01*
X419783Y637133D01*
X419117Y636967D01*
X418700Y636633D01*
X418367Y636050D01*
X418200Y635467D01*
X418283Y634967D01*
X418617Y634383D01*
X419117Y633967D01*
X419783Y633800D01*
X420283Y633883D01*
X420867Y634217D01*
X421200Y634550D01*
G01X424133Y632550D02*
X424717Y632217D01*
X425383Y632133D01*
X425967Y632217D01*
X426467Y632633D01*
X426800Y633217D01*
Y637133D01*
G01Y636467D02*
X426467Y636800D01*
X425967Y637050D01*
X425383Y637133D01*
X424717Y636967D01*
X424300Y636633D01*
X423967Y636050D01*
X423800Y635467D01*
X423883Y634967D01*
X424217Y634383D01*
X424717Y633967D01*
X425383Y633800D01*
X425883Y633883D01*
X426467Y634217D01*
X426800Y634550D01*
G01X429650Y636050D02*
X432317D01*
X432067Y636633D01*
X431650Y636967D01*
X431067Y637133D01*
X430483Y637050D01*
X429983Y636800D01*
X429650Y636217D01*
X429483Y635717D01*
Y635217D01*
X429650Y634717D01*
X430067Y634217D01*
X430567Y633883D01*
X431150Y633800D01*
X431733Y633967D01*
X432317Y634467D01*
G01X438000Y638800D02*
Y633800D01*
G01Y634550D02*
X437667Y634133D01*
X437167Y633883D01*
X436583Y633800D01*
X435917Y633967D01*
X435417Y634383D01*
X435083Y634883D01*
X435000Y635467D01*
X435083Y636050D01*
X435417Y636550D01*
X435917Y636967D01*
X436583Y637133D01*
X437167Y637050D01*
X437583Y636883D01*
X438000Y636550D01*
G01X446033Y633800D02*
Y638800D01*
X448033D01*
X448700Y638550D01*
X449200Y637967D01*
X449367Y637300D01*
X449200Y636633D01*
X448783Y636133D01*
X448033Y635883D01*
X446033D01*
G01X453300Y638800D02*
Y633800D01*
G01X451383Y638800D02*
X455217D01*
G01X457150Y633800D02*
Y638800D01*
G01X460650D02*
Y633800D01*
G01Y636300D02*
X457150D01*
G01X469683Y632133D02*
X468850Y632967D01*
X468433Y633800D01*
Y637133D01*
X468850Y637967D01*
X469683Y638800D01*
G01X473950Y633800D02*
Y638800D01*
G01X477450D02*
Y633800D01*
G01Y636300D02*
X473950D01*
G01X481300Y633800D02*
X480800Y633883D01*
X480300Y634217D01*
X479967Y634800D01*
X479800Y635467D01*
X479967Y636133D01*
X480300Y636717D01*
X480800Y637050D01*
X481300Y637133D01*
X481800Y637050D01*
X482300Y636717D01*
X482633Y636133D01*
X482717Y635467D01*
X482633Y634800D01*
X482300Y634217D01*
X481800Y633883D01*
X481300Y633800D01*
G01X486900D02*
Y638800D01*
G01X491250Y636050D02*
X493917D01*
X493667Y636633D01*
X493250Y636967D01*
X492667Y637133D01*
X492083Y637050D01*
X491583Y636800D01*
X491250Y636217D01*
X491083Y635717D01*
Y635217D01*
X491250Y634717D01*
X491667Y634217D01*
X492167Y633883D01*
X492750Y633800D01*
X493333Y633967D01*
X493917Y634467D01*
G01X501950D02*
X502617Y634050D01*
X503367Y633800D01*
X504033D01*
X504700Y634050D01*
X505200Y634467D01*
X505450Y635050D01*
X505283Y635633D01*
X504867Y636133D01*
X504117Y636467D01*
X503117Y636633D01*
X502533Y636967D01*
X502283Y637550D01*
X502450Y638133D01*
X502867Y638550D01*
X503450Y638800D01*
X504033D01*
X504617Y638633D01*
X505117Y638217D01*
G01X509300Y637133D02*
Y633800D01*
G01Y638467D02*
X509133Y638550D01*
Y638717D01*
X509300Y638800D01*
X509467Y638717D01*
Y638550D01*
X509300Y638467D01*
G01X513650Y637133D02*
X516150D01*
X513650Y633800D01*
X516150D01*
G01X519250Y636050D02*
X521917D01*
X521667Y636633D01*
X521250Y636967D01*
X520667Y637133D01*
X520083Y637050D01*
X519583Y636800D01*
X519250Y636217D01*
X519083Y635717D01*
Y635217D01*
X519250Y634717D01*
X519667Y634217D01*
X520167Y633883D01*
X520750Y633800D01*
X521333Y633967D01*
X521917Y634467D01*
G01X527767Y633800D02*
X524433Y635467D01*
X527767Y637133D01*
G01X531700Y633800D02*
Y638800D01*
X530700Y637800D01*
G01Y633800D02*
X532700D01*
G01X535883Y634383D02*
X536467Y633967D01*
X537133Y633800D01*
X537800Y633967D01*
X538383Y634467D01*
X538800Y635217D01*
X538967Y635967D01*
Y636883D01*
X538800Y637633D01*
X538383Y638300D01*
X537883Y638633D01*
X537300Y638800D01*
X536633Y638633D01*
X536133Y638300D01*
X535800Y637800D01*
X535633Y637133D01*
X535800Y636550D01*
X536217Y635967D01*
X536717Y635633D01*
X537300Y635550D01*
X537967Y635717D01*
X538467Y636133D01*
X538967Y636883D01*
G01X542733Y633800D02*
X542900Y634883D01*
X543150Y635800D01*
X543483Y636633D01*
X543900Y637550D01*
X544567Y638800D01*
X541233D01*
G01X546000Y633800D02*
Y637133D01*
G01Y636217D02*
X546250Y636633D01*
X546667Y636967D01*
X547250Y637133D01*
X547833Y636967D01*
X548250Y636633D01*
X548500Y636217D01*
Y633800D01*
G01Y636217D02*
X548750Y636633D01*
X549167Y636967D01*
X549750Y637133D01*
X550333Y636967D01*
X550750Y636633D01*
X551000Y636133D01*
Y633800D01*
G01X554100Y637133D02*
Y633800D01*
G01Y638467D02*
X553933Y638550D01*
Y638717D01*
X554100Y638800D01*
X554267Y638717D01*
Y638550D01*
X554100Y638467D01*
G01X559700Y633800D02*
Y638800D01*
G01X568817Y637133D02*
X569817Y633800D01*
X570900Y637133D01*
X571983Y633800D01*
X572983Y637133D01*
G01X576500D02*
Y633800D01*
G01Y638467D02*
X576333Y638550D01*
Y638717D01*
X576500Y638800D01*
X576667Y638717D01*
Y638550D01*
X576500Y638467D01*
G01X582100Y638800D02*
Y633800D01*
G01X580933Y637133D02*
X583267D01*
G01X586283Y633800D02*
Y638800D01*
G01Y636383D02*
X586700Y636800D01*
X587117Y637050D01*
X587783Y637133D01*
X588283Y637050D01*
X588867Y636717D01*
X589117Y636217D01*
Y633800D01*
G01X597483D02*
Y637133D01*
G01Y636300D02*
X597817Y636717D01*
X598317Y637050D01*
X598983Y637133D01*
X599567Y637050D01*
X600067Y636717D01*
X600317Y636133D01*
Y633800D01*
G01X604500D02*
X604000Y633883D01*
X603500Y634217D01*
X603167Y634800D01*
X603000Y635467D01*
X603167Y636133D01*
X603500Y636717D01*
X604000Y637050D01*
X604500Y637133D01*
X605000Y637050D01*
X605500Y636717D01*
X605833Y636133D01*
X605917Y635467D01*
X605833Y634800D01*
X605500Y634217D01*
X605000Y633883D01*
X604500Y633800D01*
G01X608683D02*
Y637133D01*
G01Y636300D02*
X609017Y636717D01*
X609517Y637050D01*
X610183Y637133D01*
X610767Y637050D01*
X611267Y636717D01*
X611517Y636133D01*
Y633800D01*
G01X614617Y635467D02*
X616783D01*
G01X619550Y633800D02*
Y638800D01*
G01X623050D02*
Y633800D01*
G01Y636300D02*
X619550D01*
G01X624817Y633800D02*
X626900Y638800D01*
X628983Y633800D01*
G01X628233Y635550D02*
X625567D01*
G01X630750Y634467D02*
X631417Y634050D01*
X632167Y633800D01*
X632833D01*
X633500Y634050D01*
X634000Y634467D01*
X634250Y635050D01*
X634083Y635633D01*
X633667Y636133D01*
X632917Y636467D01*
X631917Y636633D01*
X631333Y636967D01*
X631083Y637550D01*
X631250Y638133D01*
X631667Y638550D01*
X632250Y638800D01*
X632833D01*
X633417Y638633D01*
X633917Y638217D01*
G01X636433Y638800D02*
Y633800D01*
X639767D01*
G01X647800Y632133D02*
Y637133D01*
G01Y636383D02*
X648217Y636800D01*
X648633Y637050D01*
X649300Y637133D01*
X649883Y637050D01*
X650467Y636633D01*
X650717Y636050D01*
X650800Y635467D01*
X650717Y634883D01*
X650467Y634300D01*
X649967Y633967D01*
X649300Y633800D01*
X648717Y633883D01*
X648133Y634133D01*
X647800Y634467D01*
G01X653733Y633800D02*
Y637133D01*
G01Y636467D02*
X654150Y636800D01*
X654567Y637050D01*
X655150Y637133D01*
X655567Y637050D01*
X656067Y636800D01*
G01X660500Y633800D02*
X660000Y633883D01*
X659500Y634217D01*
X659167Y634800D01*
X659000Y635467D01*
X659167Y636133D01*
X659500Y636717D01*
X660000Y637050D01*
X660500Y637133D01*
X661000Y637050D01*
X661500Y636717D01*
X661833Y636133D01*
X661917Y635467D01*
X661833Y634800D01*
X661500Y634217D01*
X661000Y633883D01*
X660500Y633800D01*
G01X667600Y638800D02*
Y633800D01*
G01Y634550D02*
X667267Y634133D01*
X666767Y633883D01*
X666183Y633800D01*
X665517Y633967D01*
X665017Y634383D01*
X664683Y634883D01*
X664600Y635467D01*
X664683Y636050D01*
X665017Y636550D01*
X665517Y636967D01*
X666183Y637133D01*
X666767Y637050D01*
X667183Y636883D01*
X667600Y636550D01*
G01X670283Y637133D02*
Y634800D01*
X670617Y634217D01*
X671117Y633883D01*
X671700Y633800D01*
X672283Y633883D01*
X672783Y634217D01*
X673117Y634800D01*
G01Y633800D02*
Y637133D01*
G01X678633Y636717D02*
X678050Y637050D01*
X677550Y637133D01*
X676883Y636967D01*
X676383Y636633D01*
X676050Y636050D01*
X675967Y635467D01*
X676050Y634883D01*
X676383Y634383D01*
X676883Y633967D01*
X677550Y633800D01*
X678133Y633967D01*
X678633Y634300D01*
G01X682900Y638800D02*
Y633800D01*
G01X681733Y637133D02*
X684067D01*
G01X687250Y634383D02*
X687667Y634050D01*
X688250Y633800D01*
X688750D01*
X689250Y633967D01*
X689583Y634217D01*
X689750Y634550D01*
X689667Y635050D01*
X689333Y635300D01*
X687833Y635800D01*
X687500Y636383D01*
X687667Y636800D01*
X688000Y637050D01*
X688500Y637133D01*
X689000Y637050D01*
X689500Y636800D01*
G01X694517Y632133D02*
X695350Y632967D01*
X695767Y633800D01*
Y637133D01*
X695350Y637967D01*
X694517Y638800D01*
G01X384433Y648800D02*
Y653800D01*
X386433D01*
X387100Y653550D01*
X387600Y652967D01*
X387767Y652300D01*
X387600Y651633D01*
X387183Y651133D01*
X386433Y650883D01*
X384433D01*
G01X391700Y648800D02*
Y653800D01*
G01X395883Y652133D02*
Y649800D01*
X396217Y649217D01*
X396717Y648883D01*
X397300Y648800D01*
X397883Y648883D01*
X398383Y649217D01*
X398717Y649800D01*
G01Y648800D02*
Y652133D01*
G01X401733Y647550D02*
X402317Y647217D01*
X402983Y647133D01*
X403567Y647217D01*
X404067Y647633D01*
X404400Y648217D01*
Y652133D01*
G01Y651467D02*
X404067Y651800D01*
X403567Y652050D01*
X402983Y652133D01*
X402317Y651967D01*
X401900Y651633D01*
X401567Y651050D01*
X401400Y650467D01*
X401483Y649967D01*
X401817Y649383D01*
X402317Y648967D01*
X402983Y648800D01*
X403483Y648883D01*
X404067Y649217D01*
X404400Y649550D01*
G01X407333Y647550D02*
X407917Y647217D01*
X408583Y647133D01*
X409167Y647217D01*
X409667Y647633D01*
X410000Y648217D01*
Y652133D01*
G01Y651467D02*
X409667Y651800D01*
X409167Y652050D01*
X408583Y652133D01*
X407917Y651967D01*
X407500Y651633D01*
X407167Y651050D01*
X407000Y650467D01*
X407083Y649967D01*
X407417Y649383D01*
X407917Y648967D01*
X408583Y648800D01*
X409083Y648883D01*
X409667Y649217D01*
X410000Y649550D01*
G01X412850Y651050D02*
X415517D01*
X415267Y651633D01*
X414850Y651967D01*
X414267Y652133D01*
X413683Y652050D01*
X413183Y651800D01*
X412850Y651217D01*
X412683Y650717D01*
Y650217D01*
X412850Y649717D01*
X413267Y649217D01*
X413767Y648883D01*
X414350Y648800D01*
X414933Y648967D01*
X415517Y649467D01*
G01X421200Y653800D02*
Y648800D01*
G01Y649550D02*
X420867Y649133D01*
X420367Y648883D01*
X419783Y648800D01*
X419117Y648967D01*
X418617Y649383D01*
X418283Y649883D01*
X418200Y650467D01*
X418283Y651050D01*
X418617Y651550D01*
X419117Y651967D01*
X419783Y652133D01*
X420367Y652050D01*
X420783Y651883D01*
X421200Y651550D01*
G01X429233Y648800D02*
Y653800D01*
X431233D01*
X431900Y653550D01*
X432400Y652967D01*
X432567Y652300D01*
X432400Y651633D01*
X431983Y651133D01*
X431233Y650883D01*
X429233D01*
G01X436500Y653800D02*
Y648800D01*
G01X434583Y653800D02*
X438417D01*
G01X440350Y648800D02*
Y653800D01*
G01X443850D02*
Y648800D01*
G01Y651300D02*
X440350D01*
G01X447283Y647133D02*
X446450Y647967D01*
X446033Y648800D01*
Y652133D01*
X446450Y652967D01*
X447283Y653800D01*
G01X451883Y648800D02*
Y653800D01*
G01Y651383D02*
X452300Y651800D01*
X452717Y652050D01*
X453383Y652133D01*
X453883Y652050D01*
X454467Y651717D01*
X454717Y651217D01*
Y648800D01*
G01X458900D02*
X458400Y648883D01*
X457900Y649217D01*
X457567Y649800D01*
X457400Y650467D01*
X457567Y651133D01*
X457900Y651717D01*
X458400Y652050D01*
X458900Y652133D01*
X459400Y652050D01*
X459900Y651717D01*
X460233Y651133D01*
X460317Y650467D01*
X460233Y649800D01*
X459900Y649217D01*
X459400Y648883D01*
X458900Y648800D01*
G01X464500D02*
Y653800D01*
G01X468850Y651050D02*
X471517D01*
X471267Y651633D01*
X470850Y651967D01*
X470267Y652133D01*
X469683Y652050D01*
X469183Y651800D01*
X468850Y651217D01*
X468683Y650717D01*
Y650217D01*
X468850Y649717D01*
X469267Y649217D01*
X469767Y648883D01*
X470350Y648800D01*
X470933Y648967D01*
X471517Y649467D01*
G01X480050Y649383D02*
X480467Y649050D01*
X481050Y648800D01*
X481550D01*
X482050Y648967D01*
X482383Y649217D01*
X482550Y649550D01*
X482467Y650050D01*
X482133Y650300D01*
X480633Y650800D01*
X480300Y651383D01*
X480467Y651800D01*
X480800Y652050D01*
X481300Y652133D01*
X481800Y652050D01*
X482300Y651800D01*
G01X486900Y652133D02*
Y648800D01*
G01Y653467D02*
X486733Y653550D01*
Y653717D01*
X486900Y653800D01*
X487067Y653717D01*
Y653550D01*
X486900Y653467D01*
G01X491250Y652133D02*
X493750D01*
X491250Y648800D01*
X493750D01*
G01X496850Y651050D02*
X499517D01*
X499267Y651633D01*
X498850Y651967D01*
X498267Y652133D01*
X497683Y652050D01*
X497183Y651800D01*
X496850Y651217D01*
X496683Y650717D01*
Y650217D01*
X496850Y649717D01*
X497267Y649217D01*
X497767Y648883D01*
X498350Y648800D01*
X498933Y648967D01*
X499517Y649467D01*
G01X502033Y648800D02*
X505367Y650467D01*
X502033Y652133D01*
G01X508217Y649717D02*
X510383D01*
G01Y651217D02*
X508217D01*
G01X514900Y648800D02*
Y653800D01*
X513900Y652800D01*
G01Y648800D02*
X515900D01*
G01X518917Y650883D02*
X519500Y651467D01*
X520000Y651800D01*
X520667Y651967D01*
X521250Y651800D01*
X521667Y651467D01*
X522000Y650967D01*
X522083Y650383D01*
X522000Y649883D01*
X521667Y649383D01*
X521167Y648967D01*
X520583Y648800D01*
X519917Y648967D01*
X519333Y649467D01*
X519000Y650217D01*
X518917Y651050D01*
X519083Y652133D01*
X519333Y652717D01*
X519750Y653300D01*
X520333Y653717D01*
X520917Y653800D01*
X521500Y653633D01*
X521917Y653217D01*
G01X529200Y648800D02*
Y652133D01*
G01Y651217D02*
X529450Y651633D01*
X529867Y651967D01*
X530450Y652133D01*
X531033Y651967D01*
X531450Y651633D01*
X531700Y651217D01*
Y648800D01*
G01Y651217D02*
X531950Y651633D01*
X532367Y651967D01*
X532950Y652133D01*
X533533Y651967D01*
X533950Y651633D01*
X534200Y651133D01*
Y648800D01*
G01X537300Y652133D02*
Y648800D01*
G01Y653467D02*
X537133Y653550D01*
Y653717D01*
X537300Y653800D01*
X537467Y653717D01*
Y653550D01*
X537300Y653467D01*
G01X542900Y648800D02*
Y653800D01*
G01X548917Y647133D02*
X549750Y647967D01*
X550167Y648800D01*
Y652133D01*
X549750Y652967D01*
X548917Y653800D01*
G01X376100Y612800D02*
X808100D01*
G01X376100Y627800D02*
X808100D01*
G01X376100Y642800D02*
X808100D01*
G01X386600Y697800D02*
Y692800D01*
G01X384683Y697800D02*
X388517D01*
G01X390783Y692800D02*
Y697800D01*
G01Y695383D02*
X391200Y695800D01*
X391617Y696050D01*
X392283Y696133D01*
X392783Y696050D01*
X393367Y695717D01*
X393617Y695217D01*
Y692800D01*
G01X396550Y695050D02*
X399217D01*
X398967Y695633D01*
X398550Y695967D01*
X397967Y696133D01*
X397383Y696050D01*
X396883Y695800D01*
X396550Y695217D01*
X396383Y694717D01*
Y694217D01*
X396550Y693717D01*
X396967Y693217D01*
X397467Y692883D01*
X398050Y692800D01*
X398633Y692967D01*
X399217Y693467D01*
G01X402233Y692800D02*
Y696133D01*
G01Y695467D02*
X402650Y695800D01*
X403067Y696050D01*
X403650Y696133D01*
X404067Y696050D01*
X404567Y695800D01*
G01X406500Y692800D02*
Y696133D01*
G01Y695217D02*
X406750Y695633D01*
X407167Y695967D01*
X407750Y696133D01*
X408333Y695967D01*
X408750Y695633D01*
X409000Y695217D01*
Y692800D01*
G01Y695217D02*
X409250Y695633D01*
X409667Y695967D01*
X410250Y696133D01*
X410833Y695967D01*
X411250Y695633D01*
X411500Y695133D01*
Y692800D01*
G01X416100D02*
Y696133D01*
G01Y695550D02*
X415767Y695883D01*
X415267Y696050D01*
X414683Y696133D01*
X414100Y695967D01*
X413600Y695633D01*
X413267Y695133D01*
X413100Y694467D01*
X413267Y693800D01*
X413600Y693300D01*
X414100Y692967D01*
X414683Y692800D01*
X415267Y692883D01*
X415767Y693133D01*
X416100Y693467D01*
G01X420200Y692800D02*
Y697800D01*
G01X429900Y691133D02*
Y696133D01*
G01Y695383D02*
X430317Y695800D01*
X430733Y696050D01*
X431400Y696133D01*
X431983Y696050D01*
X432567Y695633D01*
X432817Y695050D01*
X432900Y694467D01*
X432817Y693883D01*
X432567Y693300D01*
X432067Y692967D01*
X431400Y692800D01*
X430817Y692883D01*
X430233Y693133D01*
X429900Y693467D01*
G01X438500Y692800D02*
Y696133D01*
G01Y695550D02*
X438167Y695883D01*
X437667Y696050D01*
X437083Y696133D01*
X436500Y695967D01*
X436000Y695633D01*
X435667Y695133D01*
X435500Y694467D01*
X435667Y693800D01*
X436000Y693300D01*
X436500Y692967D01*
X437083Y692800D01*
X437667Y692883D01*
X438167Y693133D01*
X438500Y693467D01*
G01X444100Y697800D02*
Y692800D01*
G01Y693550D02*
X443767Y693133D01*
X443267Y692883D01*
X442683Y692800D01*
X442017Y692967D01*
X441517Y693383D01*
X441183Y693883D01*
X441100Y694467D01*
X441183Y695050D01*
X441517Y695550D01*
X442017Y695967D01*
X442683Y696133D01*
X443267Y696050D01*
X443683Y695883D01*
X444100Y695550D01*
G01X455133Y695717D02*
X454550Y696050D01*
X454050Y696133D01*
X453383Y695967D01*
X452883Y695633D01*
X452550Y695050D01*
X452467Y694467D01*
X452550Y693883D01*
X452883Y693383D01*
X453383Y692967D01*
X454050Y692800D01*
X454633Y692967D01*
X455133Y693300D01*
G01X460900Y692800D02*
Y696133D01*
G01Y695550D02*
X460567Y695883D01*
X460067Y696050D01*
X459483Y696133D01*
X458900Y695967D01*
X458400Y695633D01*
X458067Y695133D01*
X457900Y694467D01*
X458067Y693800D01*
X458400Y693300D01*
X458900Y692967D01*
X459483Y692800D01*
X460067Y692883D01*
X460567Y693133D01*
X460900Y693467D01*
G01X463583Y692800D02*
Y696133D01*
G01Y695300D02*
X463917Y695717D01*
X464417Y696050D01*
X465083Y696133D01*
X465667Y696050D01*
X466167Y695717D01*
X466417Y695133D01*
Y692800D01*
G01X477533Y695717D02*
X476950Y696050D01*
X476450Y696133D01*
X475783Y695967D01*
X475283Y695633D01*
X474950Y695050D01*
X474867Y694467D01*
X474950Y693883D01*
X475283Y693383D01*
X475783Y692967D01*
X476450Y692800D01*
X477033Y692967D01*
X477533Y693300D01*
G01X480383Y692800D02*
Y697800D01*
G01Y695383D02*
X480800Y695800D01*
X481217Y696050D01*
X481883Y696133D01*
X482383Y696050D01*
X482967Y695717D01*
X483217Y695217D01*
Y692800D01*
G01X488900D02*
Y696133D01*
G01Y695550D02*
X488567Y695883D01*
X488067Y696050D01*
X487483Y696133D01*
X486900Y695967D01*
X486400Y695633D01*
X486067Y695133D01*
X485900Y694467D01*
X486067Y693800D01*
X486400Y693300D01*
X486900Y692967D01*
X487483Y692800D01*
X488067Y692883D01*
X488567Y693133D01*
X488900Y693467D01*
G01X491583Y692800D02*
Y696133D01*
G01Y695300D02*
X491917Y695717D01*
X492417Y696050D01*
X493083Y696133D01*
X493667Y696050D01*
X494167Y695717D01*
X494417Y695133D01*
Y692800D01*
G01X497433Y691550D02*
X498017Y691217D01*
X498683Y691133D01*
X499267Y691217D01*
X499767Y691633D01*
X500100Y692217D01*
Y696133D01*
G01Y695467D02*
X499767Y695800D01*
X499267Y696050D01*
X498683Y696133D01*
X498017Y695967D01*
X497600Y695633D01*
X497267Y695050D01*
X497100Y694467D01*
X497183Y693967D01*
X497517Y693383D01*
X498017Y692967D01*
X498683Y692800D01*
X499183Y692883D01*
X499767Y693217D01*
X500100Y693550D01*
G01X502950Y695050D02*
X505617D01*
X505367Y695633D01*
X504950Y695967D01*
X504367Y696133D01*
X503783Y696050D01*
X503283Y695800D01*
X502950Y695217D01*
X502783Y694717D01*
Y694217D01*
X502950Y693717D01*
X503367Y693217D01*
X503867Y692883D01*
X504450Y692800D01*
X505033Y692967D01*
X505617Y693467D01*
G01X515400Y696133D02*
Y692800D01*
G01Y697467D02*
X515233Y697550D01*
Y697717D01*
X515400Y697800D01*
X515567Y697717D01*
Y697550D01*
X515400Y697467D01*
G01X519583Y692800D02*
Y696133D01*
G01Y695300D02*
X519917Y695717D01*
X520417Y696050D01*
X521083Y696133D01*
X521667Y696050D01*
X522167Y695717D01*
X522417Y695133D01*
Y692800D01*
G01X526600Y697800D02*
Y692800D01*
G01X525433Y696133D02*
X527767D01*
G01X532200Y692800D02*
X531700Y692883D01*
X531200Y693217D01*
X530867Y693800D01*
X530700Y694467D01*
X530867Y695133D01*
X531200Y695717D01*
X531700Y696050D01*
X532200Y696133D01*
X532700Y696050D01*
X533200Y695717D01*
X533533Y695133D01*
X533617Y694467D01*
X533533Y693800D01*
X533200Y693217D01*
X532700Y692883D01*
X532200Y692800D01*
G01X542900D02*
Y697050D01*
X543067Y697467D01*
X543400Y697717D01*
X543900Y697800D01*
X544400Y697633D01*
X544650Y697217D01*
G01X543650Y695800D02*
X541983D01*
G01X547583Y696133D02*
Y693800D01*
X547917Y693217D01*
X548417Y692883D01*
X549000Y692800D01*
X549583Y692883D01*
X550083Y693217D01*
X550417Y693800D01*
G01Y692800D02*
Y696133D01*
G01X554600Y692800D02*
Y697800D01*
G01X560200Y692800D02*
Y697800D01*
G01X572733Y695717D02*
X572150Y696050D01*
X571650Y696133D01*
X570983Y695967D01*
X570483Y695633D01*
X570150Y695050D01*
X570067Y694467D01*
X570150Y693883D01*
X570483Y693383D01*
X570983Y692967D01*
X571650Y692800D01*
X572233Y692967D01*
X572733Y693300D01*
G01X577000Y692800D02*
X576500Y692883D01*
X576000Y693217D01*
X575667Y693800D01*
X575500Y694467D01*
X575667Y695133D01*
X576000Y695717D01*
X576500Y696050D01*
X577000Y696133D01*
X577500Y696050D01*
X578000Y695717D01*
X578333Y695133D01*
X578417Y694467D01*
X578333Y693800D01*
X578000Y693217D01*
X577500Y692883D01*
X577000Y692800D01*
G01X581183D02*
Y696133D01*
G01Y695300D02*
X581517Y695717D01*
X582017Y696050D01*
X582683Y696133D01*
X583267Y696050D01*
X583767Y695717D01*
X584017Y695133D01*
Y692800D01*
G01X588200Y697800D02*
Y692800D01*
G01X587033Y696133D02*
X589367D01*
G01X595300Y692800D02*
Y696133D01*
G01Y695550D02*
X594967Y695883D01*
X594467Y696050D01*
X593883Y696133D01*
X593300Y695967D01*
X592800Y695633D01*
X592467Y695133D01*
X592300Y694467D01*
X592467Y693800D01*
X592800Y693300D01*
X593300Y692967D01*
X593883Y692800D01*
X594467Y692883D01*
X594967Y693133D01*
X595300Y693467D01*
G01X600733Y695717D02*
X600150Y696050D01*
X599650Y696133D01*
X598983Y695967D01*
X598483Y695633D01*
X598150Y695050D01*
X598067Y694467D01*
X598150Y693883D01*
X598483Y693383D01*
X598983Y692967D01*
X599650Y692800D01*
X600233Y692967D01*
X600733Y693300D01*
G01X605000Y697800D02*
Y692800D01*
G01X603833Y696133D02*
X606167D01*
G01X384017Y677300D02*
X386100Y682300D01*
X388183Y677300D01*
G01X387433Y679050D02*
X384767D01*
G01X390283Y677300D02*
Y680633D01*
G01Y679800D02*
X390617Y680217D01*
X391117Y680550D01*
X391783Y680633D01*
X392367Y680550D01*
X392867Y680217D01*
X393117Y679633D01*
Y677300D01*
G01X395550Y675800D02*
X396050Y675633D01*
X396717Y675800D01*
X397133Y676133D01*
X397467Y676550D01*
X397967Y677883D01*
X399050Y680633D01*
G01X396383D02*
X397967Y677883D01*
G01X407083Y677300D02*
Y682300D01*
G01Y679883D02*
X407500Y680300D01*
X407917Y680550D01*
X408583Y680633D01*
X409083Y680550D01*
X409667Y680217D01*
X409917Y679717D01*
Y677300D01*
G01X414100D02*
X413600Y677383D01*
X413100Y677717D01*
X412767Y678300D01*
X412600Y678967D01*
X412767Y679633D01*
X413100Y680217D01*
X413600Y680550D01*
X414100Y680633D01*
X414600Y680550D01*
X415100Y680217D01*
X415433Y679633D01*
X415517Y678967D01*
X415433Y678300D01*
X415100Y677717D01*
X414600Y677383D01*
X414100Y677300D01*
G01X419700D02*
Y682300D01*
G01X424050Y679550D02*
X426717D01*
X426467Y680133D01*
X426050Y680467D01*
X425467Y680633D01*
X424883Y680550D01*
X424383Y680300D01*
X424050Y679717D01*
X423883Y679217D01*
Y678717D01*
X424050Y678217D01*
X424467Y677717D01*
X424967Y677383D01*
X425550Y677300D01*
X426133Y677467D01*
X426717Y677967D01*
G01X436500Y682300D02*
Y677300D01*
G01X435333Y680633D02*
X437667D01*
G01X442100Y677300D02*
X441600Y677383D01*
X441100Y677717D01*
X440767Y678300D01*
X440600Y678967D01*
X440767Y679633D01*
X441100Y680217D01*
X441600Y680550D01*
X442100Y680633D01*
X442600Y680550D01*
X443100Y680217D01*
X443433Y679633D01*
X443517Y678967D01*
X443433Y678300D01*
X443100Y677717D01*
X442600Y677383D01*
X442100Y677300D01*
G01X451883D02*
Y682300D01*
G01Y679883D02*
X452300Y680300D01*
X452717Y680550D01*
X453383Y680633D01*
X453883Y680550D01*
X454467Y680217D01*
X454717Y679717D01*
Y677300D01*
G01X458900D02*
X458400Y677383D01*
X457900Y677717D01*
X457567Y678300D01*
X457400Y678967D01*
X457567Y679633D01*
X457900Y680217D01*
X458400Y680550D01*
X458900Y680633D01*
X459400Y680550D01*
X459900Y680217D01*
X460233Y679633D01*
X460317Y678967D01*
X460233Y678300D01*
X459900Y677717D01*
X459400Y677383D01*
X458900Y677300D01*
G01X464500D02*
Y682300D01*
G01X468850Y679550D02*
X471517D01*
X471267Y680133D01*
X470850Y680467D01*
X470267Y680633D01*
X469683Y680550D01*
X469183Y680300D01*
X468850Y679717D01*
X468683Y679217D01*
Y678717D01*
X468850Y678217D01*
X469267Y677717D01*
X469767Y677383D01*
X470350Y677300D01*
X470933Y677467D01*
X471517Y677967D01*
G01X384433Y663800D02*
Y668800D01*
X386433D01*
X387100Y668550D01*
X387600Y667967D01*
X387767Y667300D01*
X387600Y666633D01*
X387183Y666133D01*
X386433Y665883D01*
X384433D01*
G01X391700Y663800D02*
Y668800D01*
G01X395883Y667133D02*
Y664800D01*
X396217Y664217D01*
X396717Y663883D01*
X397300Y663800D01*
X397883Y663883D01*
X398383Y664217D01*
X398717Y664800D01*
G01Y663800D02*
Y667133D01*
G01X401733Y662550D02*
X402317Y662217D01*
X402983Y662133D01*
X403567Y662217D01*
X404067Y662633D01*
X404400Y663217D01*
Y667133D01*
G01Y666467D02*
X404067Y666800D01*
X403567Y667050D01*
X402983Y667133D01*
X402317Y666967D01*
X401900Y666633D01*
X401567Y666050D01*
X401400Y665467D01*
X401483Y664967D01*
X401817Y664383D01*
X402317Y663967D01*
X402983Y663800D01*
X403483Y663883D01*
X404067Y664217D01*
X404400Y664550D01*
G01X407333Y662550D02*
X407917Y662217D01*
X408583Y662133D01*
X409167Y662217D01*
X409667Y662633D01*
X410000Y663217D01*
Y667133D01*
G01Y666467D02*
X409667Y666800D01*
X409167Y667050D01*
X408583Y667133D01*
X407917Y666967D01*
X407500Y666633D01*
X407167Y666050D01*
X407000Y665467D01*
X407083Y664967D01*
X407417Y664383D01*
X407917Y663967D01*
X408583Y663800D01*
X409083Y663883D01*
X409667Y664217D01*
X410000Y664550D01*
G01X412850Y666050D02*
X415517D01*
X415267Y666633D01*
X414850Y666967D01*
X414267Y667133D01*
X413683Y667050D01*
X413183Y666800D01*
X412850Y666217D01*
X412683Y665717D01*
Y665217D01*
X412850Y664717D01*
X413267Y664217D01*
X413767Y663883D01*
X414350Y663800D01*
X414933Y663967D01*
X415517Y664467D01*
G01X421200Y668800D02*
Y663800D01*
G01Y664550D02*
X420867Y664133D01*
X420367Y663883D01*
X419783Y663800D01*
X419117Y663967D01*
X418617Y664383D01*
X418283Y664883D01*
X418200Y665467D01*
X418283Y666050D01*
X418617Y666550D01*
X419117Y666967D01*
X419783Y667133D01*
X420367Y667050D01*
X420783Y666883D01*
X421200Y666550D01*
G01X428817Y668800D02*
X430900Y663800D01*
X432983Y668800D01*
G01X436500Y667133D02*
Y663800D01*
G01Y668467D02*
X436333Y668550D01*
Y668717D01*
X436500Y668800D01*
X436667Y668717D01*
Y668550D01*
X436500Y668467D01*
G01X443600Y663800D02*
Y667133D01*
G01Y666550D02*
X443267Y666883D01*
X442767Y667050D01*
X442183Y667133D01*
X441600Y666967D01*
X441100Y666633D01*
X440767Y666133D01*
X440600Y665467D01*
X440767Y664800D01*
X441100Y664300D01*
X441600Y663967D01*
X442183Y663800D01*
X442767Y663883D01*
X443267Y664133D01*
X443600Y664467D01*
G01X447283Y662133D02*
X446450Y662967D01*
X446033Y663800D01*
Y667133D01*
X446450Y667967D01*
X447283Y668800D01*
G01X451883Y663800D02*
Y668800D01*
G01Y666383D02*
X452300Y666800D01*
X452717Y667050D01*
X453383Y667133D01*
X453883Y667050D01*
X454467Y666717D01*
X454717Y666217D01*
Y663800D01*
G01X458900D02*
X458400Y663883D01*
X457900Y664217D01*
X457567Y664800D01*
X457400Y665467D01*
X457567Y666133D01*
X457900Y666717D01*
X458400Y667050D01*
X458900Y667133D01*
X459400Y667050D01*
X459900Y666717D01*
X460233Y666133D01*
X460317Y665467D01*
X460233Y664800D01*
X459900Y664217D01*
X459400Y663883D01*
X458900Y663800D01*
G01X464500D02*
Y668800D01*
G01X468850Y666050D02*
X471517D01*
X471267Y666633D01*
X470850Y666967D01*
X470267Y667133D01*
X469683Y667050D01*
X469183Y666800D01*
X468850Y666217D01*
X468683Y665717D01*
Y665217D01*
X468850Y664717D01*
X469267Y664217D01*
X469767Y663883D01*
X470350Y663800D01*
X470933Y663967D01*
X471517Y664467D01*
G01X480050Y664383D02*
X480467Y664050D01*
X481050Y663800D01*
X481550D01*
X482050Y663967D01*
X482383Y664217D01*
X482550Y664550D01*
X482467Y665050D01*
X482133Y665300D01*
X480633Y665800D01*
X480300Y666383D01*
X480467Y666800D01*
X480800Y667050D01*
X481300Y667133D01*
X481800Y667050D01*
X482300Y666800D01*
G01X486900Y667133D02*
Y663800D01*
G01Y668467D02*
X486733Y668550D01*
Y668717D01*
X486900Y668800D01*
X487067Y668717D01*
Y668550D01*
X486900Y668467D01*
G01X491250Y667133D02*
X493750D01*
X491250Y663800D01*
X493750D01*
G01X496850Y666050D02*
X499517D01*
X499267Y666633D01*
X498850Y666967D01*
X498267Y667133D01*
X497683Y667050D01*
X497183Y666800D01*
X496850Y666217D01*
X496683Y665717D01*
Y665217D01*
X496850Y664717D01*
X497267Y664217D01*
X497767Y663883D01*
X498350Y663800D01*
X498933Y663967D01*
X499517Y664467D01*
G01X505367Y663800D02*
X502033Y665467D01*
X505367Y667133D01*
G01X509300Y663800D02*
Y668800D01*
X508300Y667800D01*
G01Y663800D02*
X510300D01*
G01X513317Y665883D02*
X513900Y666467D01*
X514400Y666800D01*
X515067Y666967D01*
X515650Y666800D01*
X516067Y666467D01*
X516400Y665967D01*
X516483Y665383D01*
X516400Y664883D01*
X516067Y664383D01*
X515567Y663967D01*
X514983Y663800D01*
X514317Y663967D01*
X513733Y664467D01*
X513400Y665217D01*
X513317Y666050D01*
X513483Y667133D01*
X513733Y667717D01*
X514150Y668300D01*
X514733Y668717D01*
X515317Y668800D01*
X515900Y668633D01*
X516317Y668217D01*
G01X523600Y663800D02*
Y667133D01*
G01Y666217D02*
X523850Y666633D01*
X524267Y666967D01*
X524850Y667133D01*
X525433Y666967D01*
X525850Y666633D01*
X526100Y666217D01*
Y663800D01*
G01Y666217D02*
X526350Y666633D01*
X526767Y666967D01*
X527350Y667133D01*
X527933Y666967D01*
X528350Y666633D01*
X528600Y666133D01*
Y663800D01*
G01X531700Y667133D02*
Y663800D01*
G01Y668467D02*
X531533Y668550D01*
Y668717D01*
X531700Y668800D01*
X531867Y668717D01*
Y668550D01*
X531700Y668467D01*
G01X537300Y663800D02*
Y668800D01*
G01X543317Y662133D02*
X544150Y662967D01*
X544567Y663800D01*
Y667133D01*
X544150Y667967D01*
X543317Y668800D01*
G01X376100Y657800D02*
X808100D01*
G01X384517Y707800D02*
X386600Y712800D01*
X388683Y707800D01*
G01X387933Y709550D02*
X385267D01*
G01X390783Y707800D02*
Y711133D01*
G01Y710300D02*
X391117Y710717D01*
X391617Y711050D01*
X392283Y711133D01*
X392867Y711050D01*
X393367Y710717D01*
X393617Y710133D01*
Y707800D01*
G01X397800Y712800D02*
Y707800D01*
G01X396633Y711133D02*
X398967D01*
G01X403400D02*
Y707800D01*
G01Y712467D02*
X403233Y712550D01*
Y712717D01*
X403400Y712800D01*
X403567Y712717D01*
Y712550D01*
X403400Y712467D01*
G01X407917Y709467D02*
X410083D01*
G01X413100Y706133D02*
Y711133D01*
G01Y710383D02*
X413517Y710800D01*
X413933Y711050D01*
X414600Y711133D01*
X415183Y711050D01*
X415767Y710633D01*
X416017Y710050D01*
X416100Y709467D01*
X416017Y708883D01*
X415767Y708300D01*
X415267Y707967D01*
X414600Y707800D01*
X414017Y707883D01*
X413433Y708133D01*
X413100Y708467D01*
G01X421700Y707800D02*
Y711133D01*
G01Y710550D02*
X421367Y710883D01*
X420867Y711050D01*
X420283Y711133D01*
X419700Y710967D01*
X419200Y710633D01*
X418867Y710133D01*
X418700Y709467D01*
X418867Y708800D01*
X419200Y708300D01*
X419700Y707967D01*
X420283Y707800D01*
X420867Y707883D01*
X421367Y708133D01*
X421700Y708467D01*
G01X427300Y712800D02*
Y707800D01*
G01Y708550D02*
X426967Y708133D01*
X426467Y707883D01*
X425883Y707800D01*
X425217Y707967D01*
X424717Y708383D01*
X424383Y708883D01*
X424300Y709467D01*
X424383Y710050D01*
X424717Y710550D01*
X425217Y710967D01*
X425883Y711133D01*
X426467Y711050D01*
X426883Y710883D01*
X427300Y710550D01*
G01X435750Y708383D02*
X436167Y708050D01*
X436750Y707800D01*
X437250D01*
X437750Y707967D01*
X438083Y708217D01*
X438250Y708550D01*
X438167Y709050D01*
X437833Y709300D01*
X436333Y709800D01*
X436000Y710383D01*
X436167Y710800D01*
X436500Y711050D01*
X437000Y711133D01*
X437500Y711050D01*
X438000Y710800D01*
G01X442600Y711133D02*
Y707800D01*
G01Y712467D02*
X442433Y712550D01*
Y712717D01*
X442600Y712800D01*
X442767Y712717D01*
Y712550D01*
X442600Y712467D01*
G01X446950Y711133D02*
X449450D01*
X446950Y707800D01*
X449450D01*
G01X452550Y710050D02*
X455217D01*
X454967Y710633D01*
X454550Y710967D01*
X453967Y711133D01*
X453383Y711050D01*
X452883Y710800D01*
X452550Y710217D01*
X452383Y709717D01*
Y709217D01*
X452550Y708717D01*
X452967Y708217D01*
X453467Y707883D01*
X454050Y707800D01*
X454633Y707967D01*
X455217Y708467D01*
G01X383317Y726373D02*
X384317Y723040D01*
X385400Y726373D01*
X386483Y723040D01*
X387483Y726373D01*
G01X391000D02*
Y723040D01*
G01Y727707D02*
X390833Y727790D01*
Y727957D01*
X391000Y728040D01*
X391167Y727957D01*
Y727790D01*
X391000Y727707D01*
G01X396600Y728040D02*
Y723040D01*
G01X395433Y726373D02*
X397767D01*
G01X400783Y723040D02*
Y728040D01*
G01Y725623D02*
X401200Y726040D01*
X401617Y726290D01*
X402283Y726373D01*
X402783Y726290D01*
X403367Y725957D01*
X403617Y725457D01*
Y723040D01*
G01X407800D02*
X407300Y723123D01*
X406800Y723457D01*
X406467Y724040D01*
X406300Y724707D01*
X406467Y725373D01*
X406800Y725957D01*
X407300Y726290D01*
X407800Y726373D01*
X408300Y726290D01*
X408800Y725957D01*
X409133Y725373D01*
X409217Y724707D01*
X409133Y724040D01*
X408800Y723457D01*
X408300Y723123D01*
X407800Y723040D01*
G01X411983Y726373D02*
Y724040D01*
X412317Y723457D01*
X412817Y723123D01*
X413400Y723040D01*
X413983Y723123D01*
X414483Y723457D01*
X414817Y724040D01*
G01Y723040D02*
Y726373D01*
G01X419000Y728040D02*
Y723040D01*
G01X417833Y726373D02*
X420167D01*
G01X431533Y725957D02*
X430950Y726290D01*
X430450Y726373D01*
X429783Y726207D01*
X429283Y725873D01*
X428950Y725290D01*
X428867Y724707D01*
X428950Y724123D01*
X429283Y723623D01*
X429783Y723207D01*
X430450Y723040D01*
X431033Y723207D01*
X431533Y723540D01*
G01X435800Y723040D02*
X435300Y723123D01*
X434800Y723457D01*
X434467Y724040D01*
X434300Y724707D01*
X434467Y725373D01*
X434800Y725957D01*
X435300Y726290D01*
X435800Y726373D01*
X436300Y726290D01*
X436800Y725957D01*
X437133Y725373D01*
X437217Y724707D01*
X437133Y724040D01*
X436800Y723457D01*
X436300Y723123D01*
X435800Y723040D01*
G01X439983D02*
Y726373D01*
G01Y725540D02*
X440317Y725957D01*
X440817Y726290D01*
X441483Y726373D01*
X442067Y726290D01*
X442567Y725957D01*
X442817Y725373D01*
Y723040D01*
G01X445583D02*
Y726373D01*
G01Y725540D02*
X445917Y725957D01*
X446417Y726290D01*
X447083Y726373D01*
X447667Y726290D01*
X448167Y725957D01*
X448417Y725373D01*
Y723040D01*
G01X451350Y725290D02*
X454017D01*
X453767Y725873D01*
X453350Y726207D01*
X452767Y726373D01*
X452183Y726290D01*
X451683Y726040D01*
X451350Y725457D01*
X451183Y724957D01*
Y724457D01*
X451350Y723957D01*
X451767Y723457D01*
X452267Y723123D01*
X452850Y723040D01*
X453433Y723207D01*
X454017Y723707D01*
G01X459533Y725957D02*
X458950Y726290D01*
X458450Y726373D01*
X457783Y726207D01*
X457283Y725873D01*
X456950Y725290D01*
X456867Y724707D01*
X456950Y724123D01*
X457283Y723623D01*
X457783Y723207D01*
X458450Y723040D01*
X459033Y723207D01*
X459533Y723540D01*
G01X463800Y728040D02*
Y723040D01*
G01X462633Y726373D02*
X464967D01*
G01X469400D02*
Y723040D01*
G01Y727707D02*
X469233Y727790D01*
Y727957D01*
X469400Y728040D01*
X469567Y727957D01*
Y727790D01*
X469400Y727707D01*
G01X473583Y723040D02*
Y726373D01*
G01Y725540D02*
X473917Y725957D01*
X474417Y726290D01*
X475083Y726373D01*
X475667Y726290D01*
X476167Y725957D01*
X476417Y725373D01*
Y723040D01*
G01X479433Y721790D02*
X480017Y721457D01*
X480683Y721373D01*
X481267Y721457D01*
X481767Y721873D01*
X482100Y722457D01*
Y726373D01*
G01Y725707D02*
X481767Y726040D01*
X481267Y726290D01*
X480683Y726373D01*
X480017Y726207D01*
X479600Y725873D01*
X479267Y725290D01*
X479100Y724707D01*
X479183Y724207D01*
X479517Y723623D01*
X480017Y723207D01*
X480683Y723040D01*
X481183Y723123D01*
X481767Y723457D01*
X482100Y723790D01*
G01X491800Y728040D02*
Y723040D01*
G01X490633Y726373D02*
X492967D01*
G01X497400Y723040D02*
X496900Y723123D01*
X496400Y723457D01*
X496067Y724040D01*
X495900Y724707D01*
X496067Y725373D01*
X496400Y725957D01*
X496900Y726290D01*
X497400Y726373D01*
X497900Y726290D01*
X498400Y725957D01*
X498733Y725373D01*
X498817Y724707D01*
X498733Y724040D01*
X498400Y723457D01*
X497900Y723123D01*
X497400Y723040D01*
G01X508600D02*
X508100Y723123D01*
X507600Y723457D01*
X507267Y724040D01*
X507100Y724707D01*
X507267Y725373D01*
X507600Y725957D01*
X508100Y726290D01*
X508600Y726373D01*
X509100Y726290D01*
X509600Y725957D01*
X509933Y725373D01*
X510017Y724707D01*
X509933Y724040D01*
X509600Y723457D01*
X509100Y723123D01*
X508600Y723040D01*
G01X514200Y728040D02*
Y723040D01*
G01X513033Y726373D02*
X515367D01*
G01X518383Y723040D02*
Y728040D01*
G01Y725623D02*
X518800Y726040D01*
X519217Y726290D01*
X519883Y726373D01*
X520383Y726290D01*
X520967Y725957D01*
X521217Y725457D01*
Y723040D01*
G01X524150Y725290D02*
X526817D01*
X526567Y725873D01*
X526150Y726207D01*
X525567Y726373D01*
X524983Y726290D01*
X524483Y726040D01*
X524150Y725457D01*
X523983Y724957D01*
Y724457D01*
X524150Y723957D01*
X524567Y723457D01*
X525067Y723123D01*
X525650Y723040D01*
X526233Y723207D01*
X526817Y723707D01*
G01X529833Y723040D02*
Y726373D01*
G01Y725707D02*
X530250Y726040D01*
X530667Y726290D01*
X531250Y726373D01*
X531667Y726290D01*
X532167Y726040D01*
G01X542200Y723040D02*
Y728040D01*
G01X549300Y723040D02*
Y726373D01*
G01Y725790D02*
X548967Y726123D01*
X548467Y726290D01*
X547883Y726373D01*
X547300Y726207D01*
X546800Y725873D01*
X546467Y725373D01*
X546300Y724707D01*
X546467Y724040D01*
X546800Y723540D01*
X547300Y723207D01*
X547883Y723040D01*
X548467Y723123D01*
X548967Y723373D01*
X549300Y723707D01*
G01X551650Y721540D02*
X552150Y721373D01*
X552817Y721540D01*
X553233Y721873D01*
X553567Y722290D01*
X554067Y723623D01*
X555150Y726373D01*
G01X552483D02*
X554067Y723623D01*
G01X557750Y725290D02*
X560417D01*
X560167Y725873D01*
X559750Y726207D01*
X559167Y726373D01*
X558583Y726290D01*
X558083Y726040D01*
X557750Y725457D01*
X557583Y724957D01*
Y724457D01*
X557750Y723957D01*
X558167Y723457D01*
X558667Y723123D01*
X559250Y723040D01*
X559833Y723207D01*
X560417Y723707D01*
G01X563433Y723040D02*
Y726373D01*
G01Y725707D02*
X563850Y726040D01*
X564267Y726290D01*
X564850Y726373D01*
X565267Y726290D01*
X565767Y726040D01*
G01X568950Y723623D02*
X569367Y723290D01*
X569950Y723040D01*
X570450D01*
X570950Y723207D01*
X571283Y723457D01*
X571450Y723790D01*
X571367Y724290D01*
X571033Y724540D01*
X569533Y725040D01*
X569200Y725623D01*
X569367Y726040D01*
X569700Y726290D01*
X570200Y726373D01*
X570700Y726290D01*
X571200Y726040D01*
G01X576217Y721373D02*
X577050Y722207D01*
X577467Y723040D01*
Y726373D01*
X577050Y727207D01*
X576217Y728040D01*
G01X383857Y733750D02*
Y738750D01*
X385523D01*
X386190Y738500D01*
X386690Y738167D01*
X387107Y737667D01*
X387440Y737083D01*
X387523Y736250D01*
X387440Y735417D01*
X387107Y734833D01*
X386690Y734333D01*
X386190Y734000D01*
X385523Y733750D01*
X383857D01*
G01X390040Y736000D02*
X392707D01*
X392457Y736583D01*
X392040Y736917D01*
X391457Y737083D01*
X390873Y737000D01*
X390373Y736750D01*
X390040Y736167D01*
X389873Y735667D01*
Y735167D01*
X390040Y734667D01*
X390457Y734167D01*
X390957Y733833D01*
X391540Y733750D01*
X392123Y733917D01*
X392707Y734417D01*
G01X396890Y733750D02*
Y738750D01*
G01X401240Y736000D02*
X403907D01*
X403657Y736583D01*
X403240Y736917D01*
X402657Y737083D01*
X402073Y737000D01*
X401573Y736750D01*
X401240Y736167D01*
X401073Y735667D01*
Y735167D01*
X401240Y734667D01*
X401657Y734167D01*
X402157Y733833D01*
X402740Y733750D01*
X403323Y733917D01*
X403907Y734417D01*
G01X408090Y738750D02*
Y733750D01*
G01X406923Y737083D02*
X409257D01*
G01X412440Y736000D02*
X415107D01*
X414857Y736583D01*
X414440Y736917D01*
X413857Y737083D01*
X413273Y737000D01*
X412773Y736750D01*
X412440Y736167D01*
X412273Y735667D01*
Y735167D01*
X412440Y734667D01*
X412857Y734167D01*
X413357Y733833D01*
X413940Y733750D01*
X414523Y733917D01*
X415107Y734417D01*
G01X423473Y733750D02*
Y737083D01*
G01Y736250D02*
X423807Y736667D01*
X424307Y737000D01*
X424973Y737083D01*
X425557Y737000D01*
X426057Y736667D01*
X426307Y736083D01*
Y733750D01*
G01X430490D02*
X429990Y733833D01*
X429490Y734167D01*
X429157Y734750D01*
X428990Y735417D01*
X429157Y736083D01*
X429490Y736667D01*
X429990Y737000D01*
X430490Y737083D01*
X430990Y737000D01*
X431490Y736667D01*
X431823Y736083D01*
X431907Y735417D01*
X431823Y734750D01*
X431490Y734167D01*
X430990Y733833D01*
X430490Y733750D01*
G01X434673D02*
Y737083D01*
G01Y736250D02*
X435007Y736667D01*
X435507Y737000D01*
X436173Y737083D01*
X436757Y737000D01*
X437257Y736667D01*
X437507Y736083D01*
Y733750D01*
G01X440607Y735417D02*
X442773D01*
G01X446790Y733750D02*
Y738000D01*
X446957Y738417D01*
X447290Y738667D01*
X447790Y738750D01*
X448290Y738583D01*
X448540Y738167D01*
G01X447540Y736750D02*
X445873D01*
G01X451473Y737083D02*
Y734750D01*
X451807Y734167D01*
X452307Y733833D01*
X452890Y733750D01*
X453473Y733833D01*
X453973Y734167D01*
X454307Y734750D01*
G01Y733750D02*
Y737083D01*
G01X457073Y733750D02*
Y737083D01*
G01Y736250D02*
X457407Y736667D01*
X457907Y737000D01*
X458573Y737083D01*
X459157Y737000D01*
X459657Y736667D01*
X459907Y736083D01*
Y733750D01*
G01X465423Y736667D02*
X464840Y737000D01*
X464340Y737083D01*
X463673Y736917D01*
X463173Y736583D01*
X462840Y736000D01*
X462757Y735417D01*
X462840Y734833D01*
X463173Y734333D01*
X463673Y733917D01*
X464340Y733750D01*
X464923Y733917D01*
X465423Y734250D01*
G01X469690Y738750D02*
Y733750D01*
G01X468523Y737083D02*
X470857D01*
G01X475290D02*
Y733750D01*
G01Y738417D02*
X475123Y738500D01*
Y738667D01*
X475290Y738750D01*
X475457Y738667D01*
Y738500D01*
X475290Y738417D01*
G01X480890Y733750D02*
X480390Y733833D01*
X479890Y734167D01*
X479557Y734750D01*
X479390Y735417D01*
X479557Y736083D01*
X479890Y736667D01*
X480390Y737000D01*
X480890Y737083D01*
X481390Y737000D01*
X481890Y736667D01*
X482223Y736083D01*
X482307Y735417D01*
X482223Y734750D01*
X481890Y734167D01*
X481390Y733833D01*
X480890Y733750D01*
G01X485073D02*
Y737083D01*
G01Y736250D02*
X485407Y736667D01*
X485907Y737000D01*
X486573Y737083D01*
X487157Y737000D01*
X487657Y736667D01*
X487907Y736083D01*
Y733750D01*
G01X493590D02*
Y737083D01*
G01Y736500D02*
X493257Y736833D01*
X492757Y737000D01*
X492173Y737083D01*
X491590Y736917D01*
X491090Y736583D01*
X490757Y736083D01*
X490590Y735417D01*
X490757Y734750D01*
X491090Y734250D01*
X491590Y733917D01*
X492173Y733750D01*
X492757Y733833D01*
X493257Y734083D01*
X493590Y734417D01*
G01X497690Y733750D02*
Y738750D01*
G01X507390Y732083D02*
Y737083D01*
G01Y736333D02*
X507807Y736750D01*
X508223Y737000D01*
X508890Y737083D01*
X509473Y737000D01*
X510057Y736583D01*
X510307Y736000D01*
X510390Y735417D01*
X510307Y734833D01*
X510057Y734250D01*
X509557Y733917D01*
X508890Y733750D01*
X508307Y733833D01*
X507723Y734083D01*
X507390Y734417D01*
G01X515990Y733750D02*
Y737083D01*
G01Y736500D02*
X515657Y736833D01*
X515157Y737000D01*
X514573Y737083D01*
X513990Y736917D01*
X513490Y736583D01*
X513157Y736083D01*
X512990Y735417D01*
X513157Y734750D01*
X513490Y734250D01*
X513990Y733917D01*
X514573Y733750D01*
X515157Y733833D01*
X515657Y734083D01*
X515990Y734417D01*
G01X521590Y738750D02*
Y733750D01*
G01Y734500D02*
X521257Y734083D01*
X520757Y733833D01*
X520173Y733750D01*
X519507Y733917D01*
X519007Y734333D01*
X518673Y734833D01*
X518590Y735417D01*
X518673Y736000D01*
X519007Y736500D01*
X519507Y736917D01*
X520173Y737083D01*
X520757Y737000D01*
X521173Y736833D01*
X521590Y736500D01*
G01X531290Y737083D02*
Y733750D01*
G01Y738417D02*
X531123Y738500D01*
Y738667D01*
X531290Y738750D01*
X531457Y738667D01*
Y738500D01*
X531290Y738417D01*
G01X535473Y733750D02*
Y737083D01*
G01Y736250D02*
X535807Y736667D01*
X536307Y737000D01*
X536973Y737083D01*
X537557Y737000D01*
X538057Y736667D01*
X538307Y736083D01*
Y733750D01*
G01X549590D02*
Y737083D01*
G01Y736500D02*
X549257Y736833D01*
X548757Y737000D01*
X548173Y737083D01*
X547590Y736917D01*
X547090Y736583D01*
X546757Y736083D01*
X546590Y735417D01*
X546757Y734750D01*
X547090Y734250D01*
X547590Y733917D01*
X548173Y733750D01*
X548757Y733833D01*
X549257Y734083D01*
X549590Y734417D01*
G01X553690Y733750D02*
Y738750D01*
G01X559290Y733750D02*
Y738750D01*
G01X568990Y732083D02*
Y737083D01*
G01Y736333D02*
X569407Y736750D01*
X569823Y737000D01*
X570490Y737083D01*
X571073Y737000D01*
X571657Y736583D01*
X571907Y736000D01*
X571990Y735417D01*
X571907Y734833D01*
X571657Y734250D01*
X571157Y733917D01*
X570490Y733750D01*
X569907Y733833D01*
X569323Y734083D01*
X568990Y734417D01*
G01X574923Y733750D02*
Y737083D01*
G01Y736417D02*
X575340Y736750D01*
X575757Y737000D01*
X576340Y737083D01*
X576757Y737000D01*
X577257Y736750D01*
G01X581690Y733750D02*
X581190Y733833D01*
X580690Y734167D01*
X580357Y734750D01*
X580190Y735417D01*
X580357Y736083D01*
X580690Y736667D01*
X581190Y737000D01*
X581690Y737083D01*
X582190Y737000D01*
X582690Y736667D01*
X583023Y736083D01*
X583107Y735417D01*
X583023Y734750D01*
X582690Y734167D01*
X582190Y733833D01*
X581690Y733750D01*
G01X588790Y738750D02*
Y733750D01*
G01Y734500D02*
X588457Y734083D01*
X587957Y733833D01*
X587373Y733750D01*
X586707Y733917D01*
X586207Y734333D01*
X585873Y734833D01*
X585790Y735417D01*
X585873Y736000D01*
X586207Y736500D01*
X586707Y736917D01*
X587373Y737083D01*
X587957Y737000D01*
X588373Y736833D01*
X588790Y736500D01*
G01X591473Y737083D02*
Y734750D01*
X591807Y734167D01*
X592307Y733833D01*
X592890Y733750D01*
X593473Y733833D01*
X593973Y734167D01*
X594307Y734750D01*
G01Y733750D02*
Y737083D01*
G01X599823Y736667D02*
X599240Y737000D01*
X598740Y737083D01*
X598073Y736917D01*
X597573Y736583D01*
X597240Y736000D01*
X597157Y735417D01*
X597240Y734833D01*
X597573Y734333D01*
X598073Y733917D01*
X598740Y733750D01*
X599323Y733917D01*
X599823Y734250D01*
G01X604090Y738750D02*
Y733750D01*
G01X602923Y737083D02*
X605257D01*
G01X608440Y734333D02*
X608857Y734000D01*
X609440Y733750D01*
X609940D01*
X610440Y733917D01*
X610773Y734167D01*
X610940Y734500D01*
X610857Y735000D01*
X610523Y735250D01*
X609023Y735750D01*
X608690Y736333D01*
X608857Y736750D01*
X609190Y737000D01*
X609690Y737083D01*
X610190Y737000D01*
X610690Y736750D01*
G01X615290Y733583D02*
X615123Y733667D01*
Y733833D01*
X615290Y733917D01*
X615457Y733833D01*
Y733667D01*
X615290Y733583D01*
G01X620473Y732083D02*
X619640Y732917D01*
X619223Y733750D01*
Y737083D01*
X619640Y737917D01*
X620473Y738750D01*
G01X625490D02*
X627490D01*
G01X626490D02*
Y733750D01*
G01X625490D02*
X627490D01*
G01X630840Y734333D02*
X631257Y734000D01*
X631840Y733750D01*
X632340D01*
X632840Y733917D01*
X633173Y734167D01*
X633340Y734500D01*
X633257Y735000D01*
X632923Y735250D01*
X631423Y735750D01*
X631090Y736333D01*
X631257Y736750D01*
X631590Y737000D01*
X632090Y737083D01*
X632590Y737000D01*
X633090Y736750D01*
G01X637690Y733750D02*
X637190Y733833D01*
X636690Y734167D01*
X636357Y734750D01*
X636190Y735417D01*
X636357Y736083D01*
X636690Y736667D01*
X637190Y737000D01*
X637690Y737083D01*
X638190Y737000D01*
X638690Y736667D01*
X639023Y736083D01*
X639107Y735417D01*
X639023Y734750D01*
X638690Y734167D01*
X638190Y733833D01*
X637690Y733750D01*
G01X643290D02*
Y738750D01*
G01X650390Y733750D02*
Y737083D01*
G01Y736500D02*
X650057Y736833D01*
X649557Y737000D01*
X648973Y737083D01*
X648390Y736917D01*
X647890Y736583D01*
X647557Y736083D01*
X647390Y735417D01*
X647557Y734750D01*
X647890Y734250D01*
X648390Y733917D01*
X648973Y733750D01*
X649557Y733833D01*
X650057Y734083D01*
X650390Y734417D01*
G01X654490Y738750D02*
Y733750D01*
G01X653323Y737083D02*
X655657D01*
G01X658840Y736000D02*
X661507D01*
X661257Y736583D01*
X660840Y736917D01*
X660257Y737083D01*
X659673Y737000D01*
X659173Y736750D01*
X658840Y736167D01*
X658673Y735667D01*
Y735167D01*
X658840Y734667D01*
X659257Y734167D01*
X659757Y733833D01*
X660340Y733750D01*
X660923Y733917D01*
X661507Y734417D01*
G01X669790Y732083D02*
Y737083D01*
G01Y736333D02*
X670207Y736750D01*
X670623Y737000D01*
X671290Y737083D01*
X671873Y737000D01*
X672457Y736583D01*
X672707Y736000D01*
X672790Y735417D01*
X672707Y734833D01*
X672457Y734250D01*
X671957Y733917D01*
X671290Y733750D01*
X670707Y733833D01*
X670123Y734083D01*
X669790Y734417D01*
G01X678390Y733750D02*
Y737083D01*
G01Y736500D02*
X678057Y736833D01*
X677557Y737000D01*
X676973Y737083D01*
X676390Y736917D01*
X675890Y736583D01*
X675557Y736083D01*
X675390Y735417D01*
X675557Y734750D01*
X675890Y734250D01*
X676390Y733917D01*
X676973Y733750D01*
X677557Y733833D01*
X678057Y734083D01*
X678390Y734417D01*
G01X683990Y738750D02*
Y733750D01*
G01Y734500D02*
X683657Y734083D01*
X683157Y733833D01*
X682573Y733750D01*
X681907Y733917D01*
X681407Y734333D01*
X681073Y734833D01*
X680990Y735417D01*
X681073Y736000D01*
X681407Y736500D01*
X681907Y736917D01*
X682573Y737083D01*
X683157Y737000D01*
X683573Y736833D01*
X683990Y736500D01*
G01X436223Y392763D02*
X436490Y392963D01*
X436690Y393297D01*
X436823Y393763D01*
X436690Y394163D01*
X436423Y394430D01*
X435957Y394630D01*
X434157D01*
Y390630D01*
X436357D01*
X436823Y390897D01*
X437090Y391297D01*
X437223Y391763D01*
X437090Y392230D01*
X436690Y392630D01*
X436223Y392763D01*
X434157D01*
G01X434023Y440130D02*
X435690Y444130D01*
X437357Y440130D01*
G01X436757Y441530D02*
X434623D01*
G01X474717Y417337D02*
X474317Y417537D01*
X473850Y417670D01*
X473317D01*
X472717Y417470D01*
X472250Y417137D01*
X471917Y416737D01*
X471650Y416070D01*
X471583Y415470D01*
X471717Y414870D01*
X471917Y414470D01*
X472317Y414070D01*
X472783Y413803D01*
X473250Y413670D01*
X473717D01*
X474183Y413803D01*
X474583Y414003D01*
X474917Y414270D01*
G01X508600Y453300D02*
Y264300D01*
G01X516577Y318687D02*
X516910Y318937D01*
X517160Y319353D01*
X517327Y319937D01*
X517160Y320437D01*
X516827Y320770D01*
X516243Y321020D01*
X513993D01*
Y316020D01*
X516743D01*
X517327Y316353D01*
X517660Y316853D01*
X517827Y317437D01*
X517660Y318020D01*
X517160Y318520D01*
X516577Y318687D01*
X513993D01*
G01X520093Y319353D02*
Y317020D01*
X520427Y316437D01*
X520927Y316103D01*
X521510Y316020D01*
X522093Y316103D01*
X522593Y316437D01*
X522927Y317020D01*
G01Y316020D02*
Y319353D01*
G01X524610Y316020D02*
Y319353D01*
G01Y318437D02*
X524860Y318853D01*
X525277Y319187D01*
X525860Y319353D01*
X526443Y319187D01*
X526860Y318853D01*
X527110Y318437D01*
Y316020D01*
G01Y318437D02*
X527360Y318853D01*
X527777Y319187D01*
X528360Y319353D01*
X528943Y319187D01*
X529360Y318853D01*
X529610Y318353D01*
Y316020D01*
G01X531210Y314353D02*
Y319353D01*
G01Y318603D02*
X531627Y319020D01*
X532043Y319270D01*
X532710Y319353D01*
X533293Y319270D01*
X533877Y318853D01*
X534127Y318270D01*
X534210Y317687D01*
X534127Y317103D01*
X533877Y316520D01*
X533377Y316187D01*
X532710Y316020D01*
X532127Y316103D01*
X531543Y316353D01*
X531210Y316687D01*
G01X515120Y357013D02*
X516620Y353680D01*
X518120Y357013D01*
G01X522220D02*
Y353680D01*
G01Y358347D02*
X522053Y358430D01*
Y358597D01*
X522220Y358680D01*
X522387Y358597D01*
Y358430D01*
X522220Y358347D01*
G01X529320Y353680D02*
Y357013D01*
G01Y356430D02*
X528987Y356763D01*
X528487Y356930D01*
X527903Y357013D01*
X527320Y356847D01*
X526820Y356513D01*
X526487Y356013D01*
X526320Y355347D01*
X526487Y354680D01*
X526820Y354180D01*
X527320Y353847D01*
X527903Y353680D01*
X528487Y353763D01*
X528987Y354013D01*
X529320Y354347D01*
G01X514667Y366160D02*
Y371160D01*
X516333D01*
X517000Y370910D01*
X517500Y370577D01*
X517917Y370077D01*
X518250Y369493D01*
X518333Y368660D01*
X518250Y367827D01*
X517917Y367243D01*
X517500Y366743D01*
X517000Y366410D01*
X516333Y366160D01*
X514667D01*
G01X522100Y369493D02*
Y366160D01*
G01Y370827D02*
X521933Y370910D01*
Y371077D01*
X522100Y371160D01*
X522267Y371077D01*
Y370910D01*
X522100Y370827D01*
G01X525200Y366160D02*
Y369493D01*
G01Y368577D02*
X525450Y368993D01*
X525867Y369327D01*
X526450Y369493D01*
X527033Y369327D01*
X527450Y368993D01*
X527700Y368577D01*
Y366160D01*
G01Y368577D02*
X527950Y368993D01*
X528367Y369327D01*
X528950Y369493D01*
X529533Y369327D01*
X529950Y368993D01*
X530200Y368493D01*
Y366160D01*
G01X531800Y364493D02*
Y369493D01*
G01Y368743D02*
X532217Y369160D01*
X532633Y369410D01*
X533300Y369493D01*
X533883Y369410D01*
X534467Y368993D01*
X534717Y368410D01*
X534800Y367827D01*
X534717Y367243D01*
X534467Y366660D01*
X533967Y366327D01*
X533300Y366160D01*
X532717Y366243D01*
X532133Y366493D01*
X531800Y366827D01*
G01X538900Y366160D02*
Y371160D01*
G01X543250Y368410D02*
X545917D01*
X545667Y368993D01*
X545250Y369327D01*
X544667Y369493D01*
X544083Y369410D01*
X543583Y369160D01*
X543250Y368577D01*
X543083Y368077D01*
Y367577D01*
X543250Y367077D01*
X543667Y366577D01*
X544167Y366243D01*
X544750Y366160D01*
X545333Y366327D01*
X545917Y366827D01*
G01X555200Y366160D02*
Y370410D01*
X555367Y370827D01*
X555700Y371077D01*
X556200Y371160D01*
X556700Y370993D01*
X556950Y370577D01*
G01X555950Y369160D02*
X554283D01*
G01X561300Y366160D02*
X560800Y366243D01*
X560300Y366577D01*
X559967Y367160D01*
X559800Y367827D01*
X559967Y368493D01*
X560300Y369077D01*
X560800Y369410D01*
X561300Y369493D01*
X561800Y369410D01*
X562300Y369077D01*
X562633Y368493D01*
X562717Y367827D01*
X562633Y367160D01*
X562300Y366577D01*
X561800Y366243D01*
X561300Y366160D01*
G01X565733D02*
Y369493D01*
G01Y368827D02*
X566150Y369160D01*
X566567Y369410D01*
X567150Y369493D01*
X567567Y369410D01*
X568067Y369160D01*
G01X578100Y366160D02*
X577600Y366243D01*
X577100Y366577D01*
X576767Y367160D01*
X576600Y367827D01*
X576767Y368493D01*
X577100Y369077D01*
X577600Y369410D01*
X578100Y369493D01*
X578600Y369410D01*
X579100Y369077D01*
X579433Y368493D01*
X579517Y367827D01*
X579433Y367160D01*
X579100Y366577D01*
X578600Y366243D01*
X578100Y366160D01*
G01X582283Y369493D02*
Y367160D01*
X582617Y366577D01*
X583117Y366243D01*
X583700Y366160D01*
X584283Y366243D01*
X584783Y366577D01*
X585117Y367160D01*
G01Y366160D02*
Y369493D01*
G01X589300Y371160D02*
Y366160D01*
G01X588133Y369493D02*
X590467D01*
G01X593650Y368410D02*
X596317D01*
X596067Y368993D01*
X595650Y369327D01*
X595067Y369493D01*
X594483Y369410D01*
X593983Y369160D01*
X593650Y368577D01*
X593483Y368077D01*
Y367577D01*
X593650Y367077D01*
X594067Y366577D01*
X594567Y366243D01*
X595150Y366160D01*
X595733Y366327D01*
X596317Y366827D01*
G01X599333Y366160D02*
Y369493D01*
G01Y368827D02*
X599750Y369160D01*
X600167Y369410D01*
X600750Y369493D01*
X601167Y369410D01*
X601667Y369160D01*
G01X613200Y366160D02*
Y369493D01*
G01Y368910D02*
X612867Y369243D01*
X612367Y369410D01*
X611783Y369493D01*
X611200Y369327D01*
X610700Y368993D01*
X610367Y368493D01*
X610200Y367827D01*
X610367Y367160D01*
X610700Y366660D01*
X611200Y366327D01*
X611783Y366160D01*
X612367Y366243D01*
X612867Y366493D01*
X613200Y366827D01*
G01X615883Y366160D02*
Y369493D01*
G01Y368660D02*
X616217Y369077D01*
X616717Y369410D01*
X617383Y369493D01*
X617967Y369410D01*
X618467Y369077D01*
X618717Y368493D01*
Y366160D01*
G01X624400Y371160D02*
Y366160D01*
G01Y366910D02*
X624067Y366493D01*
X623567Y366243D01*
X622983Y366160D01*
X622317Y366327D01*
X621817Y366743D01*
X621483Y367243D01*
X621400Y367827D01*
X621483Y368410D01*
X621817Y368910D01*
X622317Y369327D01*
X622983Y369493D01*
X623567Y369410D01*
X623983Y369243D01*
X624400Y368910D01*
G01X634100Y369493D02*
Y366160D01*
G01Y370827D02*
X633933Y370910D01*
Y371077D01*
X634100Y371160D01*
X634267Y371077D01*
Y370910D01*
X634100Y370827D01*
G01X638283Y366160D02*
Y369493D01*
G01Y368660D02*
X638617Y369077D01*
X639117Y369410D01*
X639783Y369493D01*
X640367Y369410D01*
X640867Y369077D01*
X641117Y368493D01*
Y366160D01*
G01X643883D02*
Y369493D01*
G01Y368660D02*
X644217Y369077D01*
X644717Y369410D01*
X645383Y369493D01*
X645967Y369410D01*
X646467Y369077D01*
X646717Y368493D01*
Y366160D01*
G01X649650Y368410D02*
X652317D01*
X652067Y368993D01*
X651650Y369327D01*
X651067Y369493D01*
X650483Y369410D01*
X649983Y369160D01*
X649650Y368577D01*
X649483Y368077D01*
Y367577D01*
X649650Y367077D01*
X650067Y366577D01*
X650567Y366243D01*
X651150Y366160D01*
X651733Y366327D01*
X652317Y366827D01*
G01X655333Y366160D02*
Y369493D01*
G01Y368827D02*
X655750Y369160D01*
X656167Y369410D01*
X656750Y369493D01*
X657167Y369410D01*
X657667Y369160D01*
G01X667700Y366160D02*
Y371160D01*
G01X674800Y366160D02*
Y369493D01*
G01Y368910D02*
X674467Y369243D01*
X673967Y369410D01*
X673383Y369493D01*
X672800Y369327D01*
X672300Y368993D01*
X671967Y368493D01*
X671800Y367827D01*
X671967Y367160D01*
X672300Y366660D01*
X672800Y366327D01*
X673383Y366160D01*
X673967Y366243D01*
X674467Y366493D01*
X674800Y366827D01*
G01X677650Y366743D02*
X678067Y366410D01*
X678650Y366160D01*
X679150D01*
X679650Y366327D01*
X679983Y366577D01*
X680150Y366910D01*
X680067Y367410D01*
X679733Y367660D01*
X678233Y368160D01*
X677900Y368743D01*
X678067Y369160D01*
X678400Y369410D01*
X678900Y369493D01*
X679400Y369410D01*
X679900Y369160D01*
G01X683250Y368410D02*
X685917D01*
X685667Y368993D01*
X685250Y369327D01*
X684667Y369493D01*
X684083Y369410D01*
X683583Y369160D01*
X683250Y368577D01*
X683083Y368077D01*
Y367577D01*
X683250Y367077D01*
X683667Y366577D01*
X684167Y366243D01*
X684750Y366160D01*
X685333Y366327D01*
X685917Y366827D01*
G01X688933Y366160D02*
Y369493D01*
G01Y368827D02*
X689350Y369160D01*
X689767Y369410D01*
X690350Y369493D01*
X690767Y369410D01*
X691267Y369160D01*
G01X557797Y388727D02*
X557397Y388927D01*
X556930Y389060D01*
X556397D01*
X555797Y388860D01*
X555330Y388527D01*
X554997Y388127D01*
X554730Y387460D01*
X554663Y386860D01*
X554797Y386260D01*
X554997Y385860D01*
X555397Y385460D01*
X555863Y385193D01*
X556330Y385060D01*
X556797D01*
X557263Y385193D01*
X557663Y385393D01*
X557997Y385660D01*
G01X515427Y384340D02*
X517510Y389340D01*
X519593Y384340D01*
G01X518843Y386090D02*
X516177D01*
G01X521693Y384340D02*
Y387673D01*
G01Y386840D02*
X522027Y387257D01*
X522527Y387590D01*
X523193Y387673D01*
X523777Y387590D01*
X524277Y387257D01*
X524527Y386673D01*
Y384340D01*
G01X527543Y383090D02*
X528127Y382757D01*
X528793Y382673D01*
X529377Y382757D01*
X529877Y383173D01*
X530210Y383757D01*
Y387673D01*
G01Y387007D02*
X529877Y387340D01*
X529377Y387590D01*
X528793Y387673D01*
X528127Y387507D01*
X527710Y387173D01*
X527377Y386590D01*
X527210Y386007D01*
X527293Y385507D01*
X527627Y384923D01*
X528127Y384507D01*
X528793Y384340D01*
X529293Y384423D01*
X529877Y384757D01*
X530210Y385090D01*
G01X534310Y384340D02*
Y389340D01*
G01X538660Y386590D02*
X541327D01*
X541077Y387173D01*
X540660Y387507D01*
X540077Y387673D01*
X539493Y387590D01*
X538993Y387340D01*
X538660Y386757D01*
X538493Y386257D01*
Y385757D01*
X538660Y385257D01*
X539077Y384757D01*
X539577Y384423D01*
X540160Y384340D01*
X540743Y384507D01*
X541327Y385007D01*
G01X545093Y382673D02*
X544260Y383507D01*
X543843Y384340D01*
Y387673D01*
X544260Y388507D01*
X545093Y389340D01*
G01X562727Y382673D02*
X563560Y383507D01*
X563977Y384340D01*
Y387673D01*
X563560Y388507D01*
X562727Y389340D01*
G01X508600Y394300D02*
X808100D01*
G01X515377Y420727D02*
X515710Y420977D01*
X515960Y421393D01*
X516127Y421977D01*
X515960Y422477D01*
X515627Y422810D01*
X515043Y423060D01*
X512793D01*
Y418060D01*
X515543D01*
X516127Y418393D01*
X516460Y418893D01*
X516627Y419477D01*
X516460Y420060D01*
X515960Y420560D01*
X515377Y420727D01*
X512793D01*
G01X518810Y417893D02*
X521810Y423060D01*
G01X523827Y418060D02*
X525910Y423060D01*
X527993Y418060D01*
G01X527243Y419810D02*
X524577D01*
G01X514233Y447760D02*
Y442760D01*
X517567D01*
G01X523000D02*
Y446093D01*
G01Y445510D02*
X522667Y445843D01*
X522167Y446010D01*
X521583Y446093D01*
X521000Y445927D01*
X520500Y445593D01*
X520167Y445093D01*
X520000Y444427D01*
X520167Y443760D01*
X520500Y443260D01*
X521000Y442927D01*
X521583Y442760D01*
X522167Y442843D01*
X522667Y443093D01*
X523000Y443427D01*
G01X525850Y443343D02*
X526267Y443010D01*
X526850Y442760D01*
X527350D01*
X527850Y442927D01*
X528183Y443177D01*
X528350Y443510D01*
X528267Y444010D01*
X527933Y444260D01*
X526433Y444760D01*
X526100Y445343D01*
X526267Y445760D01*
X526600Y446010D01*
X527100Y446093D01*
X527600Y446010D01*
X528100Y445760D01*
G01X531450Y445010D02*
X534117D01*
X533867Y445593D01*
X533450Y445927D01*
X532867Y446093D01*
X532283Y446010D01*
X531783Y445760D01*
X531450Y445177D01*
X531283Y444677D01*
Y444177D01*
X531450Y443677D01*
X531867Y443177D01*
X532367Y442843D01*
X532950Y442760D01*
X533533Y442927D01*
X534117Y443427D01*
G01X537133Y442760D02*
Y446093D01*
G01Y445427D02*
X537550Y445760D01*
X537967Y446010D01*
X538550Y446093D01*
X538967Y446010D01*
X539467Y445760D01*
G01X548000Y446093D02*
X549500Y442760D01*
X551000Y446093D01*
G01X555100D02*
Y442760D01*
G01Y447427D02*
X554933Y447510D01*
Y447677D01*
X555100Y447760D01*
X555267Y447677D01*
Y447510D01*
X555100Y447427D01*
G01X562200Y442760D02*
Y446093D01*
G01Y445510D02*
X561867Y445843D01*
X561367Y446010D01*
X560783Y446093D01*
X560200Y445927D01*
X559700Y445593D01*
X559367Y445093D01*
X559200Y444427D01*
X559367Y443760D01*
X559700Y443260D01*
X560200Y442927D01*
X560783Y442760D01*
X561367Y442843D01*
X561867Y443093D01*
X562200Y443427D01*
G01X570650Y443343D02*
X571067Y443010D01*
X571650Y442760D01*
X572150D01*
X572650Y442927D01*
X572983Y443177D01*
X573150Y443510D01*
X573067Y444010D01*
X572733Y444260D01*
X571233Y444760D01*
X570900Y445343D01*
X571067Y445760D01*
X571400Y446010D01*
X571900Y446093D01*
X572400Y446010D01*
X572900Y445760D01*
G01X577500Y446093D02*
Y442760D01*
G01Y447427D02*
X577333Y447510D01*
Y447677D01*
X577500Y447760D01*
X577667Y447677D01*
Y447510D01*
X577500Y447427D01*
G01X581850Y446093D02*
X584350D01*
X581850Y442760D01*
X584350D01*
G01X587450Y445010D02*
X590117D01*
X589867Y445593D01*
X589450Y445927D01*
X588867Y446093D01*
X588283Y446010D01*
X587783Y445760D01*
X587450Y445177D01*
X587283Y444677D01*
Y444177D01*
X587450Y443677D01*
X587867Y443177D01*
X588367Y442843D01*
X588950Y442760D01*
X589533Y442927D01*
X590117Y443427D01*
G01X597817Y446093D02*
X598817Y442760D01*
X599900Y446093D01*
X600983Y442760D01*
X601983Y446093D01*
G01X605500D02*
Y442760D01*
G01Y447427D02*
X605333Y447510D01*
Y447677D01*
X605500Y447760D01*
X605667Y447677D01*
Y447510D01*
X605500Y447427D01*
G01X611100Y447760D02*
Y442760D01*
G01X609933Y446093D02*
X612267D01*
G01X615283Y442760D02*
Y447760D01*
G01Y445343D02*
X615700Y445760D01*
X616117Y446010D01*
X616783Y446093D01*
X617283Y446010D01*
X617867Y445677D01*
X618117Y445177D01*
Y442760D01*
G01X622300D02*
X621800Y442843D01*
X621300Y443177D01*
X620967Y443760D01*
X620800Y444427D01*
X620967Y445093D01*
X621300Y445677D01*
X621800Y446010D01*
X622300Y446093D01*
X622800Y446010D01*
X623300Y445677D01*
X623633Y445093D01*
X623717Y444427D01*
X623633Y443760D01*
X623300Y443177D01*
X622800Y442843D01*
X622300Y442760D01*
G01X626483Y446093D02*
Y443760D01*
X626817Y443177D01*
X627317Y442843D01*
X627900Y442760D01*
X628483Y442843D01*
X628983Y443177D01*
X629317Y443760D01*
G01Y442760D02*
Y446093D01*
G01X633500Y447760D02*
Y442760D01*
G01X632333Y446093D02*
X634667D01*
G01X643200Y441093D02*
Y446093D01*
G01Y445343D02*
X643617Y445760D01*
X644033Y446010D01*
X644700Y446093D01*
X645283Y446010D01*
X645867Y445593D01*
X646117Y445010D01*
X646200Y444427D01*
X646117Y443843D01*
X645867Y443260D01*
X645367Y442927D01*
X644700Y442760D01*
X644117Y442843D01*
X643533Y443093D01*
X643200Y443427D01*
G01X650300Y442760D02*
Y447760D01*
G01X657400Y442760D02*
Y446093D01*
G01Y445510D02*
X657067Y445843D01*
X656567Y446010D01*
X655983Y446093D01*
X655400Y445927D01*
X654900Y445593D01*
X654567Y445093D01*
X654400Y444427D01*
X654567Y443760D01*
X654900Y443260D01*
X655400Y442927D01*
X655983Y442760D01*
X656567Y442843D01*
X657067Y443093D01*
X657400Y443427D01*
G01X661500Y447760D02*
Y442760D01*
G01X660333Y446093D02*
X662667D01*
G01X667100D02*
Y442760D01*
G01Y447427D02*
X666933Y447510D01*
Y447677D01*
X667100Y447760D01*
X667267Y447677D01*
Y447510D01*
X667100Y447427D01*
G01X671283Y442760D02*
Y446093D01*
G01Y445260D02*
X671617Y445677D01*
X672117Y446010D01*
X672783Y446093D01*
X673367Y446010D01*
X673867Y445677D01*
X674117Y445093D01*
Y442760D01*
G01X677133Y441510D02*
X677717Y441177D01*
X678383Y441093D01*
X678967Y441177D01*
X679467Y441593D01*
X679800Y442177D01*
Y446093D01*
G01Y445427D02*
X679467Y445760D01*
X678967Y446010D01*
X678383Y446093D01*
X677717Y445927D01*
X677300Y445593D01*
X676967Y445010D01*
X676800Y444427D01*
X676883Y443927D01*
X677217Y443343D01*
X677717Y442927D01*
X678383Y442760D01*
X678883Y442843D01*
X679467Y443177D01*
X679800Y443510D01*
G01X689083Y441093D02*
X688250Y441927D01*
X687833Y442760D01*
Y446093D01*
X688250Y446927D01*
X689083Y447760D01*
G01X695767Y445427D02*
X696100Y445677D01*
X696350Y446093D01*
X696517Y446677D01*
X696350Y447177D01*
X696017Y447510D01*
X695433Y447760D01*
X693183D01*
Y442760D01*
X695933D01*
X696517Y443093D01*
X696850Y443593D01*
X697017Y444177D01*
X696850Y444760D01*
X696350Y445260D01*
X695767Y445427D01*
X693183D01*
G01X701117Y441093D02*
X701950Y441927D01*
X702367Y442760D01*
Y446093D01*
X701950Y446927D01*
X701117Y447760D01*
G01X508600Y426300D02*
X808100D01*
G01X518100Y755633D02*
Y752300D01*
G01Y756967D02*
X517933Y757050D01*
Y757217D01*
X518100Y757300D01*
X518267Y757217D01*
Y757050D01*
X518100Y756967D01*
G01X523700Y757300D02*
Y752300D01*
G01X522533Y755633D02*
X524867D01*
G01X528050Y754550D02*
X530717D01*
X530467Y755133D01*
X530050Y755467D01*
X529467Y755633D01*
X528883Y755550D01*
X528383Y755300D01*
X528050Y754717D01*
X527883Y754217D01*
Y753717D01*
X528050Y753217D01*
X528467Y752717D01*
X528967Y752383D01*
X529550Y752300D01*
X530133Y752467D01*
X530717Y752967D01*
G01X532400Y752300D02*
Y755633D01*
G01Y754717D02*
X532650Y755133D01*
X533067Y755467D01*
X533650Y755633D01*
X534233Y755467D01*
X534650Y755133D01*
X534900Y754717D01*
Y752300D01*
G01Y754717D02*
X535150Y755133D01*
X535567Y755467D01*
X536150Y755633D01*
X536733Y755467D01*
X537150Y755133D01*
X537400Y754633D01*
Y752300D01*
G01X721100Y73800D02*
X720433Y73633D01*
X719933Y73217D01*
X719600Y72717D01*
X719350Y72050D01*
X719267Y71300D01*
X719350Y70550D01*
X719600Y69883D01*
X719933Y69383D01*
X720433Y68967D01*
X721100Y68800D01*
X721767Y68967D01*
X722267Y69383D01*
X722600Y69883D01*
X722850Y70550D01*
X722933Y71300D01*
X722850Y72050D01*
X722600Y72717D01*
X722267Y73217D01*
X721767Y73633D01*
X721100Y73800D01*
G01X726700Y68633D02*
X726533Y68717D01*
Y68883D01*
X726700Y68967D01*
X726867Y68883D01*
Y68717D01*
X726700Y68633D01*
G01X730467Y69800D02*
X730967Y69217D01*
X731633Y68883D01*
X732383Y68800D01*
X733050Y68883D01*
X733717Y69300D01*
X734133Y69800D01*
X734217Y70300D01*
X734050Y70883D01*
X733467Y71300D01*
X732883Y71467D01*
X732133D01*
G01X732883D02*
X733383Y71717D01*
X733800Y72133D01*
X733967Y72633D01*
X733800Y73133D01*
X733383Y73550D01*
X732633Y73800D01*
X731883Y73717D01*
X731133Y73383D01*
G01X735400Y70467D02*
X736233Y72133D01*
X737067D01*
X738733Y68800D01*
X739567D01*
X740400Y70467D01*
G01X743500Y73800D02*
X742833Y73633D01*
X742333Y73217D01*
X742000Y72717D01*
X741750Y72050D01*
X741667Y71300D01*
X741750Y70550D01*
X742000Y69883D01*
X742333Y69383D01*
X742833Y68967D01*
X743500Y68800D01*
X744167Y68967D01*
X744667Y69383D01*
X745000Y69883D01*
X745250Y70550D01*
X745333Y71300D01*
X745250Y72050D01*
X745000Y72717D01*
X744667Y73217D01*
X744167Y73633D01*
X743500Y73800D01*
G01X749100Y68633D02*
X748933Y68717D01*
Y68883D01*
X749100Y68967D01*
X749267Y68883D01*
Y68717D01*
X749100Y68633D01*
G01X754533Y68800D02*
X754700Y69883D01*
X754950Y70800D01*
X755283Y71633D01*
X755700Y72550D01*
X756367Y73800D01*
X753033D01*
G01X757800Y68800D02*
Y72133D01*
G01Y71217D02*
X758050Y71633D01*
X758467Y71967D01*
X759050Y72133D01*
X759633Y71967D01*
X760050Y71633D01*
X760300Y71217D01*
Y68800D01*
G01Y71217D02*
X760550Y71633D01*
X760967Y71967D01*
X761550Y72133D01*
X762133Y71967D01*
X762550Y71633D01*
X762800Y71133D01*
Y68800D01*
G01X765900Y72133D02*
Y68800D01*
G01Y73467D02*
X765733Y73550D01*
Y73717D01*
X765900Y73800D01*
X766067Y73717D01*
Y73550D01*
X765900Y73467D01*
G01X771500Y68800D02*
Y73800D01*
G01X721100Y60300D02*
X720433Y60133D01*
X719933Y59717D01*
X719600Y59217D01*
X719350Y58550D01*
X719267Y57800D01*
X719350Y57050D01*
X719600Y56383D01*
X719933Y55883D01*
X720433Y55467D01*
X721100Y55300D01*
X721767Y55467D01*
X722267Y55883D01*
X722600Y56383D01*
X722850Y57050D01*
X722933Y57800D01*
X722850Y58550D01*
X722600Y59217D01*
X722267Y59717D01*
X721767Y60133D01*
X721100Y60300D01*
G01X726700Y55133D02*
X726533Y55217D01*
Y55383D01*
X726700Y55467D01*
X726867Y55383D01*
Y55217D01*
X726700Y55133D01*
G01X730467Y56300D02*
X730967Y55717D01*
X731633Y55383D01*
X732383Y55300D01*
X733050Y55383D01*
X733717Y55800D01*
X734133Y56300D01*
X734217Y56800D01*
X734050Y57383D01*
X733467Y57800D01*
X732883Y57967D01*
X732133D01*
G01X732883D02*
X733383Y58217D01*
X733800Y58633D01*
X733967Y59133D01*
X733800Y59633D01*
X733383Y60050D01*
X732633Y60300D01*
X731883Y60217D01*
X731133Y59883D01*
G01X735400Y56967D02*
X736233Y58633D01*
X737067D01*
X738733Y55300D01*
X739567D01*
X740400Y56967D01*
G01X743500Y60300D02*
X742833Y60133D01*
X742333Y59717D01*
X742000Y59217D01*
X741750Y58550D01*
X741667Y57800D01*
X741750Y57050D01*
X742000Y56383D01*
X742333Y55883D01*
X742833Y55467D01*
X743500Y55300D01*
X744167Y55467D01*
X744667Y55883D01*
X745000Y56383D01*
X745250Y57050D01*
X745333Y57800D01*
X745250Y58550D01*
X745000Y59217D01*
X744667Y59717D01*
X744167Y60133D01*
X743500Y60300D01*
G01X749100Y55133D02*
X748933Y55217D01*
Y55383D01*
X749100Y55467D01*
X749267Y55383D01*
Y55217D01*
X749100Y55133D01*
G01X754533Y55300D02*
X754700Y56383D01*
X754950Y57300D01*
X755283Y58133D01*
X755700Y59050D01*
X756367Y60300D01*
X753033D01*
G01X757800Y55300D02*
Y58633D01*
G01Y57717D02*
X758050Y58133D01*
X758467Y58467D01*
X759050Y58633D01*
X759633Y58467D01*
X760050Y58133D01*
X760300Y57717D01*
Y55300D01*
G01Y57717D02*
X760550Y58133D01*
X760967Y58467D01*
X761550Y58633D01*
X762133Y58467D01*
X762550Y58133D01*
X762800Y57633D01*
Y55300D01*
G01X765900Y58633D02*
Y55300D01*
G01Y59967D02*
X765733Y60050D01*
Y60217D01*
X765900Y60300D01*
X766067Y60217D01*
Y60050D01*
X765900Y59967D01*
G01X771500Y55300D02*
Y60300D01*
G01X722767Y40300D02*
X719433Y41967D01*
X722767Y43633D01*
G01X725617Y41217D02*
X727783D01*
G01Y42717D02*
X725617D01*
G01X732300Y40300D02*
Y45300D01*
X731300Y44300D01*
G01Y40300D02*
X733300D01*
G01X737900Y40133D02*
X737733Y40217D01*
Y40383D01*
X737900Y40467D01*
X738067Y40383D01*
Y40217D01*
X737900Y40133D01*
G01X744500Y40300D02*
Y45300D01*
X741417Y41717D01*
X745583D01*
G01X746600Y40300D02*
Y43633D01*
G01Y42717D02*
X746850Y43133D01*
X747267Y43467D01*
X747850Y43633D01*
X748433Y43467D01*
X748850Y43133D01*
X749100Y42717D01*
Y40300D01*
G01Y42717D02*
X749350Y43133D01*
X749767Y43467D01*
X750350Y43633D01*
X750933Y43467D01*
X751350Y43133D01*
X751600Y42633D01*
Y40300D01*
G01X754700Y43633D02*
Y40300D01*
G01Y44967D02*
X754533Y45050D01*
Y45217D01*
X754700Y45300D01*
X754867Y45217D01*
Y45050D01*
X754700Y44967D01*
G01X760300Y40300D02*
Y45300D01*
G01X718933Y23800D02*
Y28800D01*
X721100Y24633D01*
X723267Y28800D01*
Y23800D01*
G01X725283Y27133D02*
Y24800D01*
X725617Y24217D01*
X726117Y23883D01*
X726700Y23800D01*
X727283Y23883D01*
X727783Y24217D01*
X728117Y24800D01*
G01Y23800D02*
Y27133D01*
G01X731050Y24383D02*
X731467Y24050D01*
X732050Y23800D01*
X732550D01*
X733050Y23967D01*
X733383Y24217D01*
X733550Y24550D01*
X733467Y25050D01*
X733133Y25300D01*
X731633Y25800D01*
X731300Y26383D01*
X731467Y26800D01*
X731800Y27050D01*
X732300Y27133D01*
X732800Y27050D01*
X733300Y26800D01*
G01X737900Y28800D02*
Y23800D01*
G01X736733Y27133D02*
X739067D01*
G01X748600Y23800D02*
Y28050D01*
X748767Y28467D01*
X749100Y28717D01*
X749600Y28800D01*
X750100Y28633D01*
X750350Y28217D01*
G01X749350Y26800D02*
X747683D01*
G01X754700Y23800D02*
X754200Y23883D01*
X753700Y24217D01*
X753367Y24800D01*
X753200Y25467D01*
X753367Y26133D01*
X753700Y26717D01*
X754200Y27050D01*
X754700Y27133D01*
X755200Y27050D01*
X755700Y26717D01*
X756033Y26133D01*
X756117Y25467D01*
X756033Y24800D01*
X755700Y24217D01*
X755200Y23883D01*
X754700Y23800D01*
G01X760300D02*
Y28800D01*
G01X765900Y23800D02*
Y28800D01*
G01X771500Y23800D02*
X771000Y23883D01*
X770500Y24217D01*
X770167Y24800D01*
X770000Y25467D01*
X770167Y26133D01*
X770500Y26717D01*
X771000Y27050D01*
X771500Y27133D01*
X772000Y27050D01*
X772500Y26717D01*
X772833Y26133D01*
X772917Y25467D01*
X772833Y24800D01*
X772500Y24217D01*
X772000Y23883D01*
X771500Y23800D01*
G01X775017Y27133D02*
X776017Y23800D01*
X777100Y27133D01*
X778183Y23800D01*
X779183Y27133D01*
G01X709100Y19300D02*
Y526800D01*
G01X720183Y86967D02*
X722183D01*
G01X721100Y88050D02*
Y85883D01*
G01X725200Y85133D02*
X728200Y90300D01*
G01X731217Y86967D02*
X733383D01*
G01X737900Y85300D02*
Y90300D01*
X736900Y89300D01*
G01Y85300D02*
X738900D01*
G01X741000D02*
Y88633D01*
G01Y87717D02*
X741250Y88133D01*
X741667Y88467D01*
X742250Y88633D01*
X742833Y88467D01*
X743250Y88133D01*
X743500Y87717D01*
Y85300D01*
G01Y87717D02*
X743750Y88133D01*
X744167Y88467D01*
X744750Y88633D01*
X745333Y88467D01*
X745750Y88133D01*
X746000Y87633D01*
Y85300D01*
G01X749100Y88633D02*
Y85300D01*
G01Y89967D02*
X748933Y90050D01*
Y90217D01*
X749100Y90300D01*
X749267Y90217D01*
Y90050D01*
X749100Y89967D01*
G01X754700Y85300D02*
Y90300D01*
G01X720183Y113467D02*
X722183D01*
G01X721100Y114550D02*
Y112383D01*
G01X725200Y111633D02*
X728200Y116800D01*
G01X731217Y113467D02*
X733383D01*
G01X737900Y111800D02*
Y116800D01*
X736900Y115800D01*
G01Y111800D02*
X738900D01*
G01X741000D02*
Y115133D01*
G01Y114217D02*
X741250Y114633D01*
X741667Y114967D01*
X742250Y115133D01*
X742833Y114967D01*
X743250Y114633D01*
X743500Y114217D01*
Y111800D01*
G01Y114217D02*
X743750Y114633D01*
X744167Y114967D01*
X744750Y115133D01*
X745333Y114967D01*
X745750Y114633D01*
X746000Y114133D01*
Y111800D01*
G01X749100Y115133D02*
Y111800D01*
G01Y116467D02*
X748933Y116550D01*
Y116717D01*
X749100Y116800D01*
X749267Y116717D01*
Y116550D01*
X749100Y116467D01*
G01X754700Y111800D02*
Y116800D01*
G01X720183Y101967D02*
X722183D01*
G01X721100Y103050D02*
Y100883D01*
G01X725200Y100133D02*
X728200Y105300D01*
G01X731217Y101967D02*
X733383D01*
G01X736317Y104467D02*
X736817Y104967D01*
X737400Y105217D01*
X738067Y105300D01*
X738900Y105133D01*
X739483Y104717D01*
X739650Y104217D01*
X739567Y103717D01*
X739233Y103300D01*
X737567Y102467D01*
X736817Y101883D01*
X736317Y101050D01*
X736150Y100300D01*
X739650D01*
G01X741000D02*
Y103633D01*
G01Y102717D02*
X741250Y103133D01*
X741667Y103467D01*
X742250Y103633D01*
X742833Y103467D01*
X743250Y103133D01*
X743500Y102717D01*
Y100300D01*
G01Y102717D02*
X743750Y103133D01*
X744167Y103467D01*
X744750Y103633D01*
X745333Y103467D01*
X745750Y103133D01*
X746000Y102633D01*
Y100300D01*
G01X749100Y103633D02*
Y100300D01*
G01Y104967D02*
X748933Y105050D01*
Y105217D01*
X749100Y105300D01*
X749267Y105217D01*
Y105050D01*
X749100Y104967D01*
G01X754700Y100300D02*
Y105300D01*
G01X720183Y156967D02*
X722183D01*
G01X721100Y158050D02*
Y155883D01*
G01X725200Y155133D02*
X728200Y160300D01*
G01X731217Y156967D02*
X733383D01*
G01X737900Y155300D02*
Y160300D01*
X736900Y159300D01*
G01Y155300D02*
X738900D01*
G01X741667Y156050D02*
X742167Y155633D01*
X742750Y155383D01*
X743500Y155300D01*
X744250Y155467D01*
X744833Y155800D01*
X745250Y156383D01*
X745333Y157050D01*
X745167Y157717D01*
X744750Y158133D01*
X744167Y158467D01*
X743583Y158550D01*
X743000Y158467D01*
X742250Y158133D01*
X742500Y160300D01*
X744750D01*
G01X747600Y155133D02*
X750600Y160300D01*
G01X747600D02*
X747100Y160133D01*
X746850Y159883D01*
X746683Y159383D01*
X746850Y158883D01*
X747100Y158633D01*
X747600Y158467D01*
X748100Y158633D01*
X748350Y158883D01*
X748517Y159383D01*
X748350Y159883D01*
X748100Y160133D01*
X747600Y160300D01*
G01X750600Y156967D02*
X750100Y156800D01*
X749850Y156550D01*
X749683Y156050D01*
X749850Y155550D01*
X750100Y155300D01*
X750600Y155133D01*
X751100Y155300D01*
X751350Y155550D01*
X751517Y156050D01*
X751350Y156550D01*
X751100Y156800D01*
X750600Y156967D01*
G01X720183Y137467D02*
X722183D01*
G01X721100Y138550D02*
Y136383D01*
G01X725200Y135633D02*
X728200Y140800D01*
G01X731217Y137467D02*
X733383D01*
G01X736317Y139967D02*
X736817Y140467D01*
X737400Y140717D01*
X738067Y140800D01*
X738900Y140633D01*
X739483Y140217D01*
X739650Y139717D01*
X739567Y139217D01*
X739233Y138800D01*
X737567Y137967D01*
X736817Y137383D01*
X736317Y136550D01*
X736150Y135800D01*
X739650D01*
G01X741000D02*
Y139133D01*
G01Y138217D02*
X741250Y138633D01*
X741667Y138967D01*
X742250Y139133D01*
X742833Y138967D01*
X743250Y138633D01*
X743500Y138217D01*
Y135800D01*
G01Y138217D02*
X743750Y138633D01*
X744167Y138967D01*
X744750Y139133D01*
X745333Y138967D01*
X745750Y138633D01*
X746000Y138133D01*
Y135800D01*
G01X749100Y139133D02*
Y135800D01*
G01Y140467D02*
X748933Y140550D01*
Y140717D01*
X749100Y140800D01*
X749267Y140717D01*
Y140550D01*
X749100Y140467D01*
G01X754700Y135800D02*
Y140800D01*
G01X720183Y186967D02*
X722183D01*
G01X721100Y188050D02*
Y185883D01*
G01X725200Y185133D02*
X728200Y190300D01*
G01X731217Y186967D02*
X733383D01*
G01X736317Y189467D02*
X736817Y189967D01*
X737400Y190217D01*
X738067Y190300D01*
X738900Y190133D01*
X739483Y189717D01*
X739650Y189217D01*
X739567Y188717D01*
X739233Y188300D01*
X737567Y187467D01*
X736817Y186883D01*
X736317Y186050D01*
X736150Y185300D01*
X739650D01*
G01X743500Y190300D02*
X742833Y190133D01*
X742333Y189717D01*
X742000Y189217D01*
X741750Y188550D01*
X741667Y187800D01*
X741750Y187050D01*
X742000Y186383D01*
X742333Y185883D01*
X742833Y185467D01*
X743500Y185300D01*
X744167Y185467D01*
X744667Y185883D01*
X745000Y186383D01*
X745250Y187050D01*
X745333Y187800D01*
X745250Y188550D01*
X745000Y189217D01*
X744667Y189717D01*
X744167Y190133D01*
X743500Y190300D01*
G01X747600Y185133D02*
X750600Y190300D01*
G01X747600D02*
X747100Y190133D01*
X746850Y189883D01*
X746683Y189383D01*
X746850Y188883D01*
X747100Y188633D01*
X747600Y188467D01*
X748100Y188633D01*
X748350Y188883D01*
X748517Y189383D01*
X748350Y189883D01*
X748100Y190133D01*
X747600Y190300D01*
G01X750600Y186967D02*
X750100Y186800D01*
X749850Y186550D01*
X749683Y186050D01*
X749850Y185550D01*
X750100Y185300D01*
X750600Y185133D01*
X751100Y185300D01*
X751350Y185550D01*
X751517Y186050D01*
X751350Y186550D01*
X751100Y186800D01*
X750600Y186967D01*
G01X720183Y201967D02*
X722183D01*
G01X721100Y203050D02*
Y200883D01*
G01X725200Y200133D02*
X728200Y205300D01*
G01X731217Y201967D02*
X733383D01*
G01X736067Y201300D02*
X736567Y200717D01*
X737233Y200383D01*
X737983Y200300D01*
X738650Y200383D01*
X739317Y200800D01*
X739733Y201300D01*
X739817Y201800D01*
X739650Y202383D01*
X739067Y202800D01*
X738483Y202967D01*
X737733D01*
G01X738483D02*
X738983Y203217D01*
X739400Y203633D01*
X739567Y204133D01*
X739400Y204633D01*
X738983Y205050D01*
X738233Y205300D01*
X737483Y205217D01*
X736733Y204883D01*
G01X741000Y200300D02*
Y203633D01*
G01Y202717D02*
X741250Y203133D01*
X741667Y203467D01*
X742250Y203633D01*
X742833Y203467D01*
X743250Y203133D01*
X743500Y202717D01*
Y200300D01*
G01Y202717D02*
X743750Y203133D01*
X744167Y203467D01*
X744750Y203633D01*
X745333Y203467D01*
X745750Y203133D01*
X746000Y202633D01*
Y200300D01*
G01X749100Y203633D02*
Y200300D01*
G01Y204967D02*
X748933Y205050D01*
Y205217D01*
X749100Y205300D01*
X749267Y205217D01*
Y205050D01*
X749100Y204967D01*
G01X754700Y200300D02*
Y205300D01*
G01X720183Y171967D02*
X722183D01*
G01X721100Y173050D02*
Y170883D01*
G01X725200Y170133D02*
X728200Y175300D01*
G01X731217Y171967D02*
X733383D01*
G01X737900Y170300D02*
Y175300D01*
X736900Y174300D01*
G01Y170300D02*
X738900D01*
G01X741000D02*
Y173633D01*
G01Y172717D02*
X741250Y173133D01*
X741667Y173467D01*
X742250Y173633D01*
X742833Y173467D01*
X743250Y173133D01*
X743500Y172717D01*
Y170300D01*
G01Y172717D02*
X743750Y173133D01*
X744167Y173467D01*
X744750Y173633D01*
X745333Y173467D01*
X745750Y173133D01*
X746000Y172633D01*
Y170300D01*
G01X749100Y173633D02*
Y170300D01*
G01Y174967D02*
X748933Y175050D01*
Y175217D01*
X749100Y175300D01*
X749267Y175217D01*
Y175050D01*
X749100Y174967D01*
G01X754700Y170300D02*
Y175300D01*
G01X719433Y255300D02*
X722767Y256967D01*
X719433Y258633D01*
G01X725617Y256217D02*
X727783D01*
G01Y257717D02*
X725617D01*
G01X732300Y255300D02*
Y260300D01*
X731300Y259300D01*
G01Y255300D02*
X733300D01*
G01X737900Y255133D02*
X737733Y255217D01*
Y255383D01*
X737900Y255467D01*
X738067Y255383D01*
Y255217D01*
X737900Y255133D01*
G01X741667Y256300D02*
X742167Y255717D01*
X742833Y255383D01*
X743583Y255300D01*
X744250Y255383D01*
X744917Y255800D01*
X745333Y256300D01*
X745417Y256800D01*
X745250Y257383D01*
X744667Y257800D01*
X744083Y257967D01*
X743333D01*
G01X744083D02*
X744583Y258217D01*
X745000Y258633D01*
X745167Y259133D01*
X745000Y259633D01*
X744583Y260050D01*
X743833Y260300D01*
X743083Y260217D01*
X742333Y259883D01*
G01X746600Y255300D02*
Y258633D01*
G01Y257717D02*
X746850Y258133D01*
X747267Y258467D01*
X747850Y258633D01*
X748433Y258467D01*
X748850Y258133D01*
X749100Y257717D01*
Y255300D01*
G01Y257717D02*
X749350Y258133D01*
X749767Y258467D01*
X750350Y258633D01*
X750933Y258467D01*
X751350Y258133D01*
X751600Y257633D01*
Y255300D01*
G01X754700Y258633D02*
Y255300D01*
G01Y259967D02*
X754533Y260050D01*
Y260217D01*
X754700Y260300D01*
X754867Y260217D01*
Y260050D01*
X754700Y259967D01*
G01X760300Y255300D02*
Y260300D01*
G01X719433Y232800D02*
X722767Y234467D01*
X719433Y236133D01*
G01X725617Y233717D02*
X727783D01*
G01Y235217D02*
X725617D01*
G01X732300Y232800D02*
Y237800D01*
X731300Y236800D01*
G01Y232800D02*
X733300D01*
G01X737900Y232633D02*
X737733Y232717D01*
Y232883D01*
X737900Y232967D01*
X738067Y232883D01*
Y232717D01*
X737900Y232633D01*
G01X741667Y233550D02*
X742167Y233133D01*
X742750Y232883D01*
X743500Y232800D01*
X744250Y232967D01*
X744833Y233300D01*
X745250Y233883D01*
X745333Y234550D01*
X745167Y235217D01*
X744750Y235633D01*
X744167Y235967D01*
X743583Y236050D01*
X743000Y235967D01*
X742250Y235633D01*
X742500Y237800D01*
X744750D01*
G01X746600Y232800D02*
Y236133D01*
G01Y235217D02*
X746850Y235633D01*
X747267Y235967D01*
X747850Y236133D01*
X748433Y235967D01*
X748850Y235633D01*
X749100Y235217D01*
Y232800D01*
G01Y235217D02*
X749350Y235633D01*
X749767Y235967D01*
X750350Y236133D01*
X750933Y235967D01*
X751350Y235633D01*
X751600Y235133D01*
Y232800D01*
G01X754700Y236133D02*
Y232800D01*
G01Y237467D02*
X754533Y237550D01*
Y237717D01*
X754700Y237800D01*
X754867Y237717D01*
Y237550D01*
X754700Y237467D01*
G01X760300Y232800D02*
Y237800D01*
G01X719433Y215300D02*
X722767Y216967D01*
X719433Y218633D01*
G01X725617Y216217D02*
X727783D01*
G01Y217717D02*
X725617D01*
G01X732300Y215300D02*
Y220300D01*
X731300Y219300D01*
G01Y215300D02*
X733300D01*
G01X737900Y215133D02*
X737733Y215217D01*
Y215383D01*
X737900Y215467D01*
X738067Y215383D01*
Y215217D01*
X737900Y215133D01*
G01X743500Y220300D02*
X742833Y220133D01*
X742333Y219717D01*
X742000Y219217D01*
X741750Y218550D01*
X741667Y217800D01*
X741750Y217050D01*
X742000Y216383D01*
X742333Y215883D01*
X742833Y215467D01*
X743500Y215300D01*
X744167Y215467D01*
X744667Y215883D01*
X745000Y216383D01*
X745250Y217050D01*
X745333Y217800D01*
X745250Y218550D01*
X745000Y219217D01*
X744667Y219717D01*
X744167Y220133D01*
X743500Y220300D01*
G01X746600Y215300D02*
Y218633D01*
G01Y217717D02*
X746850Y218133D01*
X747267Y218467D01*
X747850Y218633D01*
X748433Y218467D01*
X748850Y218133D01*
X749100Y217717D01*
Y215300D01*
G01Y217717D02*
X749350Y218133D01*
X749767Y218467D01*
X750350Y218633D01*
X750933Y218467D01*
X751350Y218133D01*
X751600Y217633D01*
Y215300D01*
G01X754700Y218633D02*
Y215300D01*
G01Y219967D02*
X754533Y220050D01*
Y220217D01*
X754700Y220300D01*
X754867Y220217D01*
Y220050D01*
X754700Y219967D01*
G01X760300Y215300D02*
Y220300D01*
G01X726577Y289290D02*
X723243Y290957D01*
X726577Y292623D01*
G01X730510Y294290D02*
X729843Y294123D01*
X729343Y293707D01*
X729010Y293207D01*
X728760Y292540D01*
X728677Y291790D01*
X728760Y291040D01*
X729010Y290373D01*
X729343Y289873D01*
X729843Y289457D01*
X730510Y289290D01*
X731177Y289457D01*
X731677Y289873D01*
X732010Y290373D01*
X732260Y291040D01*
X732343Y291790D01*
X732260Y292540D01*
X732010Y293207D01*
X731677Y293707D01*
X731177Y294123D01*
X730510Y294290D01*
G01X736110Y289123D02*
X735943Y289207D01*
Y289373D01*
X736110Y289457D01*
X736277Y289373D01*
Y289207D01*
X736110Y289123D01*
G01X739877Y290290D02*
X740377Y289707D01*
X741043Y289373D01*
X741793Y289290D01*
X742460Y289373D01*
X743127Y289790D01*
X743543Y290290D01*
X743627Y290790D01*
X743460Y291373D01*
X742877Y291790D01*
X742293Y291957D01*
X741543D01*
G01X742293D02*
X742793Y292207D01*
X743210Y292623D01*
X743377Y293123D01*
X743210Y293623D01*
X742793Y294040D01*
X742043Y294290D01*
X741293Y294207D01*
X740543Y293873D01*
G01X744810Y289290D02*
Y292623D01*
G01Y291707D02*
X745060Y292123D01*
X745477Y292457D01*
X746060Y292623D01*
X746643Y292457D01*
X747060Y292123D01*
X747310Y291707D01*
Y289290D01*
G01Y291707D02*
X747560Y292123D01*
X747977Y292457D01*
X748560Y292623D01*
X749143Y292457D01*
X749560Y292123D01*
X749810Y291623D01*
Y289290D01*
G01X752910Y292623D02*
Y289290D01*
G01Y293957D02*
X752743Y294040D01*
Y294207D01*
X752910Y294290D01*
X753077Y294207D01*
Y294040D01*
X752910Y293957D01*
G01X758510Y289290D02*
Y294290D01*
G01X725977Y344480D02*
X722643Y346147D01*
X725977Y347813D01*
G01X729910Y344480D02*
Y349480D01*
X728910Y348480D01*
G01Y344480D02*
X730910D01*
G01X733010D02*
Y347813D01*
G01Y346897D02*
X733260Y347313D01*
X733677Y347647D01*
X734260Y347813D01*
X734843Y347647D01*
X735260Y347313D01*
X735510Y346897D01*
Y344480D01*
G01Y346897D02*
X735760Y347313D01*
X736177Y347647D01*
X736760Y347813D01*
X737343Y347647D01*
X737760Y347313D01*
X738010Y346813D01*
Y344480D01*
G01X741110Y347813D02*
Y344480D01*
G01Y349147D02*
X740943Y349230D01*
Y349397D01*
X741110Y349480D01*
X741277Y349397D01*
Y349230D01*
X741110Y349147D01*
G01X746710Y344480D02*
Y349480D01*
G01X715720Y399270D02*
Y402603D01*
G01Y401687D02*
X715970Y402103D01*
X716387Y402437D01*
X716970Y402603D01*
X717553Y402437D01*
X717970Y402103D01*
X718220Y401687D01*
Y399270D01*
G01Y401687D02*
X718470Y402103D01*
X718887Y402437D01*
X719470Y402603D01*
X720053Y402437D01*
X720470Y402103D01*
X720720Y401603D01*
Y399270D01*
G01X722403Y402603D02*
Y400270D01*
X722737Y399687D01*
X723237Y399353D01*
X723820Y399270D01*
X724403Y399353D01*
X724903Y399687D01*
X725237Y400270D01*
G01Y399270D02*
Y402603D01*
G01X728170Y399853D02*
X728587Y399520D01*
X729170Y399270D01*
X729670D01*
X730170Y399437D01*
X730503Y399687D01*
X730670Y400020D01*
X730587Y400520D01*
X730253Y400770D01*
X728753Y401270D01*
X728420Y401853D01*
X728587Y402270D01*
X728920Y402520D01*
X729420Y402603D01*
X729920Y402520D01*
X730420Y402270D01*
G01X735020Y404270D02*
Y399270D01*
G01X733853Y402603D02*
X736187D01*
G01X742287Y399270D02*
X738953Y400937D01*
X742287Y402603D01*
G01X744137Y399270D02*
X746220Y404270D01*
X748303Y399270D01*
G01X747553Y401020D02*
X744887D01*
G01X758920Y404270D02*
Y399270D01*
G01Y400020D02*
X758587Y399603D01*
X758087Y399353D01*
X757503Y399270D01*
X756837Y399437D01*
X756337Y399853D01*
X756003Y400353D01*
X755920Y400937D01*
X756003Y401520D01*
X756337Y402020D01*
X756837Y402437D01*
X757503Y402603D01*
X758087Y402520D01*
X758503Y402353D01*
X758920Y402020D01*
G01X763020Y402603D02*
Y399270D01*
G01Y403937D02*
X762853Y404020D01*
Y404187D01*
X763020Y404270D01*
X763187Y404187D01*
Y404020D01*
X763020Y403937D01*
G01X770120Y399270D02*
Y402603D01*
G01Y402020D02*
X769787Y402353D01*
X769287Y402520D01*
X768703Y402603D01*
X768120Y402437D01*
X767620Y402103D01*
X767287Y401603D01*
X767120Y400937D01*
X767287Y400270D01*
X767620Y399770D01*
X768120Y399437D01*
X768703Y399270D01*
X769287Y399353D01*
X769787Y399603D01*
X770120Y399937D01*
G01X771720Y399270D02*
Y402603D01*
G01Y401687D02*
X771970Y402103D01*
X772387Y402437D01*
X772970Y402603D01*
X773553Y402437D01*
X773970Y402103D01*
X774220Y401687D01*
Y399270D01*
G01Y401687D02*
X774470Y402103D01*
X774887Y402437D01*
X775470Y402603D01*
X776053Y402437D01*
X776470Y402103D01*
X776720Y401603D01*
Y399270D01*
G01X778570Y401520D02*
X781237D01*
X780987Y402103D01*
X780570Y402437D01*
X779987Y402603D01*
X779403Y402520D01*
X778903Y402270D01*
X778570Y401687D01*
X778403Y401187D01*
Y400687D01*
X778570Y400187D01*
X778987Y399687D01*
X779487Y399353D01*
X780070Y399270D01*
X780653Y399437D01*
X781237Y399937D01*
G01X785420Y404270D02*
Y399270D01*
G01X784253Y402603D02*
X786587D01*
G01X789770Y401520D02*
X792437D01*
X792187Y402103D01*
X791770Y402437D01*
X791187Y402603D01*
X790603Y402520D01*
X790103Y402270D01*
X789770Y401687D01*
X789603Y401187D01*
Y400687D01*
X789770Y400187D01*
X790187Y399687D01*
X790687Y399353D01*
X791270Y399270D01*
X791853Y399437D01*
X792437Y399937D01*
G01X795453Y399270D02*
Y402603D01*
G01Y401937D02*
X795870Y402270D01*
X796287Y402520D01*
X796870Y402603D01*
X797287Y402520D01*
X797787Y402270D01*
G01X721997Y384030D02*
X718663Y385697D01*
X721997Y387363D01*
G01X724513Y384613D02*
X725097Y384197D01*
X725763Y384030D01*
X726430Y384197D01*
X727013Y384697D01*
X727430Y385447D01*
X727597Y386197D01*
Y387113D01*
X727430Y387863D01*
X727013Y388530D01*
X726513Y388863D01*
X725930Y389030D01*
X725263Y388863D01*
X724763Y388530D01*
X724430Y388030D01*
X724263Y387363D01*
X724430Y386780D01*
X724847Y386197D01*
X725347Y385863D01*
X725930Y385780D01*
X726597Y385947D01*
X727097Y386363D01*
X727597Y387113D01*
G01X731530Y389030D02*
X730863Y388863D01*
X730363Y388447D01*
X730030Y387947D01*
X729780Y387280D01*
X729697Y386530D01*
X729780Y385780D01*
X730030Y385113D01*
X730363Y384613D01*
X730863Y384197D01*
X731530Y384030D01*
X732197Y384197D01*
X732697Y384613D01*
X733030Y385113D01*
X733280Y385780D01*
X733363Y386530D01*
X733280Y387280D01*
X733030Y387947D01*
X732697Y388447D01*
X732197Y388863D01*
X731530Y389030D01*
G01X744230D02*
Y384030D01*
G01Y384780D02*
X743897Y384363D01*
X743397Y384113D01*
X742813Y384030D01*
X742147Y384197D01*
X741647Y384613D01*
X741313Y385113D01*
X741230Y385697D01*
X741313Y386280D01*
X741647Y386780D01*
X742147Y387197D01*
X742813Y387363D01*
X743397Y387280D01*
X743813Y387113D01*
X744230Y386780D01*
G01X747080Y386280D02*
X749747D01*
X749497Y386863D01*
X749080Y387197D01*
X748497Y387363D01*
X747913Y387280D01*
X747413Y387030D01*
X747080Y386447D01*
X746913Y385947D01*
Y385447D01*
X747080Y384947D01*
X747497Y384447D01*
X747997Y384113D01*
X748580Y384030D01*
X749163Y384197D01*
X749747Y384697D01*
G01X752763Y382780D02*
X753347Y382447D01*
X754013Y382363D01*
X754597Y382447D01*
X755097Y382863D01*
X755430Y383447D01*
Y387363D01*
G01Y386697D02*
X755097Y387030D01*
X754597Y387280D01*
X754013Y387363D01*
X753347Y387197D01*
X752930Y386863D01*
X752597Y386280D01*
X752430Y385697D01*
X752513Y385197D01*
X752847Y384613D01*
X753347Y384197D01*
X754013Y384030D01*
X754513Y384113D01*
X755097Y384447D01*
X755430Y384780D01*
G01X758363Y384030D02*
Y387363D01*
G01Y386697D02*
X758780Y387030D01*
X759197Y387280D01*
X759780Y387363D01*
X760197Y387280D01*
X760697Y387030D01*
G01X763880Y386280D02*
X766547D01*
X766297Y386863D01*
X765880Y387197D01*
X765297Y387363D01*
X764713Y387280D01*
X764213Y387030D01*
X763880Y386447D01*
X763713Y385947D01*
Y385447D01*
X763880Y384947D01*
X764297Y384447D01*
X764797Y384113D01*
X765380Y384030D01*
X765963Y384197D01*
X766547Y384697D01*
G01X769480Y386280D02*
X772147D01*
X771897Y386863D01*
X771480Y387197D01*
X770897Y387363D01*
X770313Y387280D01*
X769813Y387030D01*
X769480Y386447D01*
X769313Y385947D01*
Y385447D01*
X769480Y384947D01*
X769897Y384447D01*
X770397Y384113D01*
X770980Y384030D01*
X771563Y384197D01*
X772147Y384697D01*
G01X716300Y408040D02*
Y413040D01*
G01Y410540D02*
X716717Y411040D01*
X717217Y411290D01*
X717717Y411373D01*
X718467Y411207D01*
X718967Y410873D01*
X719300Y410290D01*
Y409623D01*
X719133Y408957D01*
X718800Y408457D01*
X718217Y408123D01*
X717717Y408040D01*
X717217Y408123D01*
X716717Y408373D01*
X716300Y408790D01*
G01X721983Y411373D02*
Y409040D01*
X722317Y408457D01*
X722817Y408123D01*
X723400Y408040D01*
X723983Y408123D01*
X724483Y408457D01*
X724817Y409040D01*
G01Y408040D02*
Y411373D01*
G01X729000Y413040D02*
Y408040D01*
G01X727833Y411373D02*
X730167D01*
G01X740867Y410707D02*
X741200Y410957D01*
X741450Y411373D01*
X741617Y411957D01*
X741450Y412457D01*
X741117Y412790D01*
X740533Y413040D01*
X738283D01*
Y408040D01*
X741033D01*
X741617Y408373D01*
X741950Y408873D01*
X742117Y409457D01*
X741950Y410040D01*
X741450Y410540D01*
X740867Y410707D01*
X738283D01*
G01X752900Y413040D02*
Y408040D01*
G01Y408790D02*
X752567Y408373D01*
X752067Y408123D01*
X751483Y408040D01*
X750817Y408207D01*
X750317Y408623D01*
X749983Y409123D01*
X749900Y409707D01*
X749983Y410290D01*
X750317Y410790D01*
X750817Y411207D01*
X751483Y411373D01*
X752067Y411290D01*
X752483Y411123D01*
X752900Y410790D01*
G01X757000Y411373D02*
Y408040D01*
G01Y412707D02*
X756833Y412790D01*
Y412957D01*
X757000Y413040D01*
X757167Y412957D01*
Y412790D01*
X757000Y412707D01*
G01X764100Y408040D02*
Y411373D01*
G01Y410790D02*
X763767Y411123D01*
X763267Y411290D01*
X762683Y411373D01*
X762100Y411207D01*
X761600Y410873D01*
X761267Y410373D01*
X761100Y409707D01*
X761267Y409040D01*
X761600Y408540D01*
X762100Y408207D01*
X762683Y408040D01*
X763267Y408123D01*
X763767Y408373D01*
X764100Y408707D01*
G01X765700Y408040D02*
Y411373D01*
G01Y410457D02*
X765950Y410873D01*
X766367Y411207D01*
X766950Y411373D01*
X767533Y411207D01*
X767950Y410873D01*
X768200Y410457D01*
Y408040D01*
G01Y410457D02*
X768450Y410873D01*
X768867Y411207D01*
X769450Y411373D01*
X770033Y411207D01*
X770450Y410873D01*
X770700Y410373D01*
Y408040D01*
G01X772550Y410290D02*
X775217D01*
X774967Y410873D01*
X774550Y411207D01*
X773967Y411373D01*
X773383Y411290D01*
X772883Y411040D01*
X772550Y410457D01*
X772383Y409957D01*
Y409457D01*
X772550Y408957D01*
X772967Y408457D01*
X773467Y408123D01*
X774050Y408040D01*
X774633Y408207D01*
X775217Y408707D01*
G01X779400Y413040D02*
Y408040D01*
G01X778233Y411373D02*
X780567D01*
G01X783750Y410290D02*
X786417D01*
X786167Y410873D01*
X785750Y411207D01*
X785167Y411373D01*
X784583Y411290D01*
X784083Y411040D01*
X783750Y410457D01*
X783583Y409957D01*
Y409457D01*
X783750Y408957D01*
X784167Y408457D01*
X784667Y408123D01*
X785250Y408040D01*
X785833Y408207D01*
X786417Y408707D01*
G01X789433Y408040D02*
Y411373D01*
G01Y410707D02*
X789850Y411040D01*
X790267Y411290D01*
X790850Y411373D01*
X791267Y411290D01*
X791767Y411040D01*
G01X717383Y418060D02*
X720717Y419727D01*
X717383Y421393D01*
G01X723567Y418977D02*
X725733D01*
G01Y420477D02*
X723567D01*
G01X730083Y418060D02*
X730250Y419143D01*
X730500Y420060D01*
X730833Y420893D01*
X731250Y421810D01*
X731917Y423060D01*
X728583D01*
G01X735850D02*
X735183Y422893D01*
X734683Y422477D01*
X734350Y421977D01*
X734100Y421310D01*
X734017Y420560D01*
X734100Y419810D01*
X734350Y419143D01*
X734683Y418643D01*
X735183Y418227D01*
X735850Y418060D01*
X736517Y418227D01*
X737017Y418643D01*
X737350Y419143D01*
X737600Y419810D01*
X737683Y420560D01*
X737600Y421310D01*
X737350Y421977D01*
X737017Y422477D01*
X736517Y422893D01*
X735850Y423060D01*
G01X739950Y417893D02*
X742950Y423060D01*
G01X739950D02*
X739450Y422893D01*
X739200Y422643D01*
X739033Y422143D01*
X739200Y421643D01*
X739450Y421393D01*
X739950Y421227D01*
X740450Y421393D01*
X740700Y421643D01*
X740867Y422143D01*
X740700Y422643D01*
X740450Y422893D01*
X739950Y423060D01*
G01X742950Y419727D02*
X742450Y419560D01*
X742200Y419310D01*
X742033Y418810D01*
X742200Y418310D01*
X742450Y418060D01*
X742950Y417893D01*
X743450Y418060D01*
X743700Y418310D01*
X743867Y418810D01*
X743700Y419310D01*
X743450Y419560D01*
X742950Y419727D01*
G01X746883Y417143D02*
X747217Y418227D01*
G01X719363Y438487D02*
X721363D01*
G01X720280Y439570D02*
Y437403D01*
G01X724380Y436653D02*
X727380Y441820D01*
G01X730397Y438487D02*
X732563D01*
G01X737080Y436820D02*
Y441820D01*
X736080Y440820D01*
G01Y436820D02*
X738080D01*
G01X740180D02*
Y440153D01*
G01Y439237D02*
X740430Y439653D01*
X740847Y439987D01*
X741430Y440153D01*
X742013Y439987D01*
X742430Y439653D01*
X742680Y439237D01*
Y436820D01*
G01Y439237D02*
X742930Y439653D01*
X743347Y439987D01*
X743930Y440153D01*
X744513Y439987D01*
X744930Y439653D01*
X745180Y439153D01*
Y436820D01*
G01X748280Y440153D02*
Y436820D01*
G01Y441487D02*
X748113Y441570D01*
Y441737D01*
X748280Y441820D01*
X748447Y441737D01*
Y441570D01*
X748280Y441487D01*
G01X753880Y436820D02*
Y441820D01*
G01X721933Y481800D02*
Y486800D01*
X724100Y482633D01*
X726267Y486800D01*
Y481800D01*
G01X728283Y485133D02*
Y482800D01*
X728617Y482217D01*
X729117Y481883D01*
X729700Y481800D01*
X730283Y481883D01*
X730783Y482217D01*
X731117Y482800D01*
G01Y481800D02*
Y485133D01*
G01X734050Y482383D02*
X734467Y482050D01*
X735050Y481800D01*
X735550D01*
X736050Y481967D01*
X736383Y482217D01*
X736550Y482550D01*
X736467Y483050D01*
X736133Y483300D01*
X734633Y483800D01*
X734300Y484383D01*
X734467Y484800D01*
X734800Y485050D01*
X735300Y485133D01*
X735800Y485050D01*
X736300Y484800D01*
G01X740900Y486800D02*
Y481800D01*
G01X739733Y485133D02*
X742067D01*
G01X751600Y481800D02*
Y486050D01*
X751767Y486467D01*
X752100Y486717D01*
X752600Y486800D01*
X753100Y486633D01*
X753350Y486217D01*
G01X752350Y484800D02*
X750683D01*
G01X757700Y481800D02*
X757200Y481883D01*
X756700Y482217D01*
X756367Y482800D01*
X756200Y483467D01*
X756367Y484133D01*
X756700Y484717D01*
X757200Y485050D01*
X757700Y485133D01*
X758200Y485050D01*
X758700Y484717D01*
X759033Y484133D01*
X759117Y483467D01*
X759033Y482800D01*
X758700Y482217D01*
X758200Y481883D01*
X757700Y481800D01*
G01X763300D02*
Y486800D01*
G01X768900Y481800D02*
Y486800D01*
G01X774500Y481800D02*
X774000Y481883D01*
X773500Y482217D01*
X773167Y482800D01*
X773000Y483467D01*
X773167Y484133D01*
X773500Y484717D01*
X774000Y485050D01*
X774500Y485133D01*
X775000Y485050D01*
X775500Y484717D01*
X775833Y484133D01*
X775917Y483467D01*
X775833Y482800D01*
X775500Y482217D01*
X775000Y481883D01*
X774500Y481800D01*
G01X778017Y485133D02*
X779017Y481800D01*
X780100Y485133D01*
X781183Y481800D01*
X782183Y485133D01*
G01X709100Y767800D02*
Y484800D01*
G01X719410Y518790D02*
Y523040D01*
X719577Y523457D01*
X719910Y523707D01*
X720410Y523790D01*
X720910Y523623D01*
X721160Y523207D01*
G01X720160Y521790D02*
X718493D01*
G01X725510Y518790D02*
X725010Y518873D01*
X724510Y519207D01*
X724177Y519790D01*
X724010Y520457D01*
X724177Y521123D01*
X724510Y521707D01*
X725010Y522040D01*
X725510Y522123D01*
X726010Y522040D01*
X726510Y521707D01*
X726843Y521123D01*
X726927Y520457D01*
X726843Y519790D01*
X726510Y519207D01*
X726010Y518873D01*
X725510Y518790D01*
G01X731110D02*
Y523790D01*
G01X736710Y518790D02*
Y523790D01*
G01X742310Y518790D02*
X741810Y518873D01*
X741310Y519207D01*
X740977Y519790D01*
X740810Y520457D01*
X740977Y521123D01*
X741310Y521707D01*
X741810Y522040D01*
X742310Y522123D01*
X742810Y522040D01*
X743310Y521707D01*
X743643Y521123D01*
X743727Y520457D01*
X743643Y519790D01*
X743310Y519207D01*
X742810Y518873D01*
X742310Y518790D01*
G01X745827Y522123D02*
X746827Y518790D01*
X747910Y522123D01*
X748993Y518790D01*
X749993Y522123D01*
G01X760610Y523790D02*
Y518790D01*
G01Y519540D02*
X760277Y519123D01*
X759777Y518873D01*
X759193Y518790D01*
X758527Y518957D01*
X758027Y519373D01*
X757693Y519873D01*
X757610Y520457D01*
X757693Y521040D01*
X758027Y521540D01*
X758527Y521957D01*
X759193Y522123D01*
X759777Y522040D01*
X760193Y521873D01*
X760610Y521540D01*
G01X763543Y518790D02*
Y522123D01*
G01Y521457D02*
X763960Y521790D01*
X764377Y522040D01*
X764960Y522123D01*
X765377Y522040D01*
X765877Y521790D01*
G01X771810Y518790D02*
Y522123D01*
G01Y521540D02*
X771477Y521873D01*
X770977Y522040D01*
X770393Y522123D01*
X769810Y521957D01*
X769310Y521623D01*
X768977Y521123D01*
X768810Y520457D01*
X768977Y519790D01*
X769310Y519290D01*
X769810Y518957D01*
X770393Y518790D01*
X770977Y518873D01*
X771477Y519123D01*
X771810Y519457D01*
G01X773827Y522123D02*
X774827Y518790D01*
X775910Y522123D01*
X776993Y518790D01*
X777993Y522123D01*
G01X781510D02*
Y518790D01*
G01Y523457D02*
X781343Y523540D01*
Y523707D01*
X781510Y523790D01*
X781677Y523707D01*
Y523540D01*
X781510Y523457D01*
G01X785693Y518790D02*
Y522123D01*
G01Y521290D02*
X786027Y521707D01*
X786527Y522040D01*
X787193Y522123D01*
X787777Y522040D01*
X788277Y521707D01*
X788527Y521123D01*
Y518790D01*
G01X791543Y517540D02*
X792127Y517207D01*
X792793Y517123D01*
X793377Y517207D01*
X793877Y517623D01*
X794210Y518207D01*
Y522123D01*
G01Y521457D02*
X793877Y521790D01*
X793377Y522040D01*
X792793Y522123D01*
X792127Y521957D01*
X791710Y521623D01*
X791377Y521040D01*
X791210Y520457D01*
X791293Y519957D01*
X791627Y519373D01*
X792127Y518957D01*
X792793Y518790D01*
X793293Y518873D01*
X793877Y519207D01*
X794210Y519540D01*
G01X798727Y517123D02*
X799560Y517957D01*
X799977Y518790D01*
Y522123D01*
X799560Y522957D01*
X798727Y523790D01*
G01X720503Y529387D02*
X722503D01*
G01X721420Y530470D02*
Y528303D01*
G01X725520Y527553D02*
X728520Y532720D01*
G01X731537Y529387D02*
X733703D01*
G01X736387Y528470D02*
X736887Y528053D01*
X737470Y527803D01*
X738220Y527720D01*
X738970Y527887D01*
X739553Y528220D01*
X739970Y528803D01*
X740053Y529470D01*
X739887Y530137D01*
X739470Y530553D01*
X738887Y530887D01*
X738303Y530970D01*
X737720Y530887D01*
X736970Y530553D01*
X737220Y532720D01*
X739470D01*
G01X741320Y527720D02*
Y531053D01*
G01Y530137D02*
X741570Y530553D01*
X741987Y530887D01*
X742570Y531053D01*
X743153Y530887D01*
X743570Y530553D01*
X743820Y530137D01*
Y527720D01*
G01Y530137D02*
X744070Y530553D01*
X744487Y530887D01*
X745070Y531053D01*
X745653Y530887D01*
X746070Y530553D01*
X746320Y530053D01*
Y527720D01*
G01X749420Y531053D02*
Y527720D01*
G01Y532387D02*
X749253Y532470D01*
Y532637D01*
X749420Y532720D01*
X749587Y532637D01*
Y532470D01*
X749420Y532387D01*
G01X755020Y527720D02*
Y532720D01*
G01X721100Y540800D02*
Y545800D01*
X720100Y544800D01*
G01Y540800D02*
X722100D01*
G01X726700Y540633D02*
X726533Y540717D01*
Y540883D01*
X726700Y540967D01*
X726867Y540883D01*
Y540717D01*
X726700Y540633D01*
G01X732300Y545800D02*
X731633Y545633D01*
X731133Y545217D01*
X730800Y544717D01*
X730550Y544050D01*
X730467Y543300D01*
X730550Y542550D01*
X730800Y541883D01*
X731133Y541383D01*
X731633Y540967D01*
X732300Y540800D01*
X732967Y540967D01*
X733467Y541383D01*
X733800Y541883D01*
X734050Y542550D01*
X734133Y543300D01*
X734050Y544050D01*
X733800Y544717D01*
X733467Y545217D01*
X732967Y545633D01*
X732300Y545800D01*
G01X735400Y540800D02*
Y544133D01*
G01Y543217D02*
X735650Y543633D01*
X736067Y543967D01*
X736650Y544133D01*
X737233Y543967D01*
X737650Y543633D01*
X737900Y543217D01*
Y540800D01*
G01Y543217D02*
X738150Y543633D01*
X738567Y543967D01*
X739150Y544133D01*
X739733Y543967D01*
X740150Y543633D01*
X740400Y543133D01*
Y540800D01*
G01X743500Y544133D02*
Y540800D01*
G01Y545467D02*
X743333Y545550D01*
Y545717D01*
X743500Y545800D01*
X743667Y545717D01*
Y545550D01*
X743500Y545467D01*
G01X749100Y540800D02*
Y545800D01*
G01X757800Y540800D02*
Y544133D01*
G01Y543217D02*
X758050Y543633D01*
X758467Y543967D01*
X759050Y544133D01*
X759633Y543967D01*
X760050Y543633D01*
X760300Y543217D01*
Y540800D01*
G01Y543217D02*
X760550Y543633D01*
X760967Y543967D01*
X761550Y544133D01*
X762133Y543967D01*
X762550Y543633D01*
X762800Y543133D01*
Y540800D01*
G01X767400D02*
Y544133D01*
G01Y543550D02*
X767067Y543883D01*
X766567Y544050D01*
X765983Y544133D01*
X765400Y543967D01*
X764900Y543633D01*
X764567Y543133D01*
X764400Y542467D01*
X764567Y541800D01*
X764900Y541300D01*
X765400Y540967D01*
X765983Y540800D01*
X766567Y540883D01*
X767067Y541133D01*
X767400Y541467D01*
G01X770250Y544133D02*
X772750Y540800D01*
G01Y544133D02*
X770250Y540800D01*
G01X720183Y560467D02*
X722183D01*
G01X721100Y561550D02*
Y559383D01*
G01X725200Y558633D02*
X728200Y563800D01*
G01X731217Y560467D02*
X733383D01*
G01X736067Y559550D02*
X736567Y559133D01*
X737150Y558883D01*
X737900Y558800D01*
X738650Y558967D01*
X739233Y559300D01*
X739650Y559883D01*
X739733Y560550D01*
X739567Y561217D01*
X739150Y561633D01*
X738567Y561967D01*
X737983Y562050D01*
X737400Y561967D01*
X736650Y561633D01*
X736900Y563800D01*
X739150D01*
G01X741000Y558800D02*
Y562133D01*
G01Y561217D02*
X741250Y561633D01*
X741667Y561967D01*
X742250Y562133D01*
X742833Y561967D01*
X743250Y561633D01*
X743500Y561217D01*
Y558800D01*
G01Y561217D02*
X743750Y561633D01*
X744167Y561967D01*
X744750Y562133D01*
X745333Y561967D01*
X745750Y561633D01*
X746000Y561133D01*
Y558800D01*
G01X749100Y562133D02*
Y558800D01*
G01Y563467D02*
X748933Y563550D01*
Y563717D01*
X749100Y563800D01*
X749267Y563717D01*
Y563550D01*
X749100Y563467D01*
G01X754700Y558800D02*
Y563800D01*
G01X720183Y575467D02*
X722183D01*
G01X721100Y576550D02*
Y574383D01*
G01X725200Y573633D02*
X728200Y578800D01*
G01X731217Y575467D02*
X733383D01*
G01X736067Y574550D02*
X736567Y574133D01*
X737150Y573883D01*
X737900Y573800D01*
X738650Y573967D01*
X739233Y574300D01*
X739650Y574883D01*
X739733Y575550D01*
X739567Y576217D01*
X739150Y576633D01*
X738567Y576967D01*
X737983Y577050D01*
X737400Y576967D01*
X736650Y576633D01*
X736900Y578800D01*
X739150D01*
G01X741000Y573800D02*
Y577133D01*
G01Y576217D02*
X741250Y576633D01*
X741667Y576967D01*
X742250Y577133D01*
X742833Y576967D01*
X743250Y576633D01*
X743500Y576217D01*
Y573800D01*
G01Y576217D02*
X743750Y576633D01*
X744167Y576967D01*
X744750Y577133D01*
X745333Y576967D01*
X745750Y576633D01*
X746000Y576133D01*
Y573800D01*
G01X749100Y577133D02*
Y573800D01*
G01Y578467D02*
X748933Y578550D01*
Y578717D01*
X749100Y578800D01*
X749267Y578717D01*
Y578550D01*
X749100Y578467D01*
G01X754700Y573800D02*
Y578800D01*
G01X720183Y590467D02*
X722183D01*
G01X721100Y591550D02*
Y589383D01*
G01X724867Y589800D02*
X725367Y589217D01*
X726033Y588883D01*
X726783Y588800D01*
X727450Y588883D01*
X728117Y589300D01*
X728533Y589800D01*
X728617Y590300D01*
X728450Y590883D01*
X727867Y591300D01*
X727283Y591467D01*
X726533D01*
G01X727283D02*
X727783Y591717D01*
X728200Y592133D01*
X728367Y592633D01*
X728200Y593133D01*
X727783Y593550D01*
X727033Y593800D01*
X726283Y593717D01*
X725533Y593383D01*
G01X730800Y588633D02*
X733800Y593800D01*
G01X736817Y590467D02*
X738983D01*
G01X743500Y593800D02*
X742833Y593633D01*
X742333Y593217D01*
X742000Y592717D01*
X741750Y592050D01*
X741667Y591300D01*
X741750Y590550D01*
X742000Y589883D01*
X742333Y589383D01*
X742833Y588967D01*
X743500Y588800D01*
X744167Y588967D01*
X744667Y589383D01*
X745000Y589883D01*
X745250Y590550D01*
X745333Y591300D01*
X745250Y592050D01*
X745000Y592717D01*
X744667Y593217D01*
X744167Y593633D01*
X743500Y593800D01*
G01X746600Y588800D02*
Y592133D01*
G01Y591217D02*
X746850Y591633D01*
X747267Y591967D01*
X747850Y592133D01*
X748433Y591967D01*
X748850Y591633D01*
X749100Y591217D01*
Y588800D01*
G01Y591217D02*
X749350Y591633D01*
X749767Y591967D01*
X750350Y592133D01*
X750933Y591967D01*
X751350Y591633D01*
X751600Y591133D01*
Y588800D01*
G01X754700Y592133D02*
Y588800D01*
G01Y593467D02*
X754533Y593550D01*
Y593717D01*
X754700Y593800D01*
X754867Y593717D01*
Y593550D01*
X754700Y593467D01*
G01X760300Y588800D02*
Y593800D01*
G01X720183Y635467D02*
X722183D01*
G01X721100Y636550D02*
Y634383D01*
G01X725200Y633633D02*
X728200Y638800D01*
G01X731217Y635467D02*
X733383D01*
G01X736317Y637967D02*
X736817Y638467D01*
X737400Y638717D01*
X738067Y638800D01*
X738900Y638633D01*
X739483Y638217D01*
X739650Y637717D01*
X739567Y637217D01*
X739233Y636800D01*
X737567Y635967D01*
X736817Y635383D01*
X736317Y634550D01*
X736150Y633800D01*
X739650D01*
G01X741000D02*
Y637133D01*
G01Y636217D02*
X741250Y636633D01*
X741667Y636967D01*
X742250Y637133D01*
X742833Y636967D01*
X743250Y636633D01*
X743500Y636217D01*
Y633800D01*
G01Y636217D02*
X743750Y636633D01*
X744167Y636967D01*
X744750Y637133D01*
X745333Y636967D01*
X745750Y636633D01*
X746000Y636133D01*
Y633800D01*
G01X749100Y637133D02*
Y633800D01*
G01Y638467D02*
X748933Y638550D01*
Y638717D01*
X749100Y638800D01*
X749267Y638717D01*
Y638550D01*
X749100Y638467D01*
G01X754700Y633800D02*
Y638800D01*
G01X720183Y605467D02*
X722183D01*
G01X721100Y606550D02*
Y604383D01*
G01X725200Y603633D02*
X728200Y608800D01*
G01X731217Y605467D02*
X733383D01*
G01X736317Y607967D02*
X736817Y608467D01*
X737400Y608717D01*
X738067Y608800D01*
X738900Y608633D01*
X739483Y608217D01*
X739650Y607717D01*
X739567Y607217D01*
X739233Y606800D01*
X737567Y605967D01*
X736817Y605383D01*
X736317Y604550D01*
X736150Y603800D01*
X739650D01*
G01X741000D02*
Y607133D01*
G01Y606217D02*
X741250Y606633D01*
X741667Y606967D01*
X742250Y607133D01*
X742833Y606967D01*
X743250Y606633D01*
X743500Y606217D01*
Y603800D01*
G01Y606217D02*
X743750Y606633D01*
X744167Y606967D01*
X744750Y607133D01*
X745333Y606967D01*
X745750Y606633D01*
X746000Y606133D01*
Y603800D01*
G01X749100Y607133D02*
Y603800D01*
G01Y608467D02*
X748933Y608550D01*
Y608717D01*
X749100Y608800D01*
X749267Y608717D01*
Y608550D01*
X749100Y608467D01*
G01X754700Y603800D02*
Y608800D01*
G01X720183Y618967D02*
X722183D01*
G01X721100Y620050D02*
Y617883D01*
G01X725200Y617133D02*
X728200Y622300D01*
G01X731217Y618967D02*
X733383D01*
G01X736067Y618300D02*
X736567Y617717D01*
X737233Y617383D01*
X737983Y617300D01*
X738650Y617383D01*
X739317Y617800D01*
X739733Y618300D01*
X739817Y618800D01*
X739650Y619383D01*
X739067Y619800D01*
X738483Y619967D01*
X737733D01*
G01X738483D02*
X738983Y620217D01*
X739400Y620633D01*
X739567Y621133D01*
X739400Y621633D01*
X738983Y622050D01*
X738233Y622300D01*
X737483Y622217D01*
X736733Y621883D01*
G01X741000Y617300D02*
Y620633D01*
G01Y619717D02*
X741250Y620133D01*
X741667Y620467D01*
X742250Y620633D01*
X742833Y620467D01*
X743250Y620133D01*
X743500Y619717D01*
Y617300D01*
G01Y619717D02*
X743750Y620133D01*
X744167Y620467D01*
X744750Y620633D01*
X745333Y620467D01*
X745750Y620133D01*
X746000Y619633D01*
Y617300D01*
G01X749100Y620633D02*
Y617300D01*
G01Y621967D02*
X748933Y622050D01*
Y622217D01*
X749100Y622300D01*
X749267Y622217D01*
Y622050D01*
X749100Y621967D01*
G01X754700Y617300D02*
Y622300D01*
G01X720183Y650467D02*
X722183D01*
G01X721100Y651550D02*
Y649383D01*
G01X725200Y648633D02*
X728200Y653800D01*
G01X731217Y650467D02*
X733383D01*
G01X736317Y652967D02*
X736817Y653467D01*
X737400Y653717D01*
X738067Y653800D01*
X738900Y653633D01*
X739483Y653217D01*
X739650Y652717D01*
X739567Y652217D01*
X739233Y651800D01*
X737567Y650967D01*
X736817Y650383D01*
X736317Y649550D01*
X736150Y648800D01*
X739650D01*
G01X741000D02*
Y652133D01*
G01Y651217D02*
X741250Y651633D01*
X741667Y651967D01*
X742250Y652133D01*
X742833Y651967D01*
X743250Y651633D01*
X743500Y651217D01*
Y648800D01*
G01Y651217D02*
X743750Y651633D01*
X744167Y651967D01*
X744750Y652133D01*
X745333Y651967D01*
X745750Y651633D01*
X746000Y651133D01*
Y648800D01*
G01X749100Y652133D02*
Y648800D01*
G01Y653467D02*
X748933Y653550D01*
Y653717D01*
X749100Y653800D01*
X749267Y653717D01*
Y653550D01*
X749100Y653467D01*
G01X754700Y648800D02*
Y653800D01*
G01X720183Y680467D02*
X722183D01*
G01X721100Y681550D02*
Y679383D01*
G01X725200Y678633D02*
X728200Y683800D01*
G01X731217Y680467D02*
X733383D01*
G01X736067Y679800D02*
X736567Y679217D01*
X737233Y678883D01*
X737983Y678800D01*
X738650Y678883D01*
X739317Y679300D01*
X739733Y679800D01*
X739817Y680300D01*
X739650Y680883D01*
X739067Y681300D01*
X738483Y681467D01*
X737733D01*
G01X738483D02*
X738983Y681717D01*
X739400Y682133D01*
X739567Y682633D01*
X739400Y683133D01*
X738983Y683550D01*
X738233Y683800D01*
X737483Y683717D01*
X736733Y683383D01*
G01X741000Y678800D02*
Y682133D01*
G01Y681217D02*
X741250Y681633D01*
X741667Y681967D01*
X742250Y682133D01*
X742833Y681967D01*
X743250Y681633D01*
X743500Y681217D01*
Y678800D01*
G01Y681217D02*
X743750Y681633D01*
X744167Y681967D01*
X744750Y682133D01*
X745333Y681967D01*
X745750Y681633D01*
X746000Y681133D01*
Y678800D01*
G01X749100Y682133D02*
Y678800D01*
G01Y683467D02*
X748933Y683550D01*
Y683717D01*
X749100Y683800D01*
X749267Y683717D01*
Y683550D01*
X749100Y683467D01*
G01X754700Y678800D02*
Y683800D01*
G01X719017Y692300D02*
X721100Y697300D01*
X723183Y692300D01*
G01X722433Y694050D02*
X719767D01*
G01X726700Y692300D02*
Y697300D01*
G01X732300Y692300D02*
Y697300D01*
G01X737900Y692300D02*
X737400Y692383D01*
X736900Y692717D01*
X736567Y693300D01*
X736400Y693967D01*
X736567Y694633D01*
X736900Y695217D01*
X737400Y695550D01*
X737900Y695633D01*
X738400Y695550D01*
X738900Y695217D01*
X739233Y694633D01*
X739317Y693967D01*
X739233Y693300D01*
X738900Y692717D01*
X738400Y692383D01*
X737900Y692300D01*
G01X741417Y695633D02*
X742417Y692300D01*
X743500Y695633D01*
X744583Y692300D01*
X745583Y695633D01*
G01X720183Y663967D02*
X722183D01*
G01X721100Y665050D02*
Y662883D01*
G01X725117Y666467D02*
X725617Y666967D01*
X726200Y667217D01*
X726867Y667300D01*
X727700Y667133D01*
X728283Y666717D01*
X728450Y666217D01*
X728367Y665717D01*
X728033Y665300D01*
X726367Y664467D01*
X725617Y663883D01*
X725117Y663050D01*
X724950Y662300D01*
X728450D01*
G01X730800Y662133D02*
X733800Y667300D01*
G01X736817Y663967D02*
X738983D01*
G01X744500Y662300D02*
Y667300D01*
X741417Y663717D01*
X745583D01*
G01X746600Y662300D02*
Y665633D01*
G01Y664717D02*
X746850Y665133D01*
X747267Y665467D01*
X747850Y665633D01*
X748433Y665467D01*
X748850Y665133D01*
X749100Y664717D01*
Y662300D01*
G01Y664717D02*
X749350Y665133D01*
X749767Y665467D01*
X750350Y665633D01*
X750933Y665467D01*
X751350Y665133D01*
X751600Y664633D01*
Y662300D01*
G01X754700Y665633D02*
Y662300D01*
G01Y666967D02*
X754533Y667050D01*
Y667217D01*
X754700Y667300D01*
X754867Y667217D01*
Y667050D01*
X754700Y666967D01*
G01X760300Y662300D02*
Y667300D01*
G01X720183Y708967D02*
X722183D01*
G01X721100Y710050D02*
Y707883D01*
G01X725200Y707133D02*
X728200Y712300D01*
G01X731217Y708967D02*
X733383D01*
G01X736317Y711467D02*
X736817Y711967D01*
X737400Y712217D01*
X738067Y712300D01*
X738900Y712133D01*
X739483Y711717D01*
X739650Y711217D01*
X739567Y710717D01*
X739233Y710300D01*
X737567Y709467D01*
X736817Y708883D01*
X736317Y708050D01*
X736150Y707300D01*
X739650D01*
G01X741000D02*
Y710633D01*
G01Y709717D02*
X741250Y710133D01*
X741667Y710467D01*
X742250Y710633D01*
X742833Y710467D01*
X743250Y710133D01*
X743500Y709717D01*
Y707300D01*
G01Y709717D02*
X743750Y710133D01*
X744167Y710467D01*
X744750Y710633D01*
X745333Y710467D01*
X745750Y710133D01*
X746000Y709633D01*
Y707300D01*
G01X749100Y710633D02*
Y707300D01*
G01Y711967D02*
X748933Y712050D01*
Y712217D01*
X749100Y712300D01*
X749267Y712217D01*
Y712050D01*
X749100Y711967D01*
G01X754700Y707300D02*
Y712300D01*
G01X718953Y727500D02*
Y732500D01*
X721120Y728333D01*
X723287Y732500D01*
Y727500D01*
G01X725303Y730833D02*
Y728500D01*
X725637Y727917D01*
X726137Y727583D01*
X726720Y727500D01*
X727303Y727583D01*
X727803Y727917D01*
X728137Y728500D01*
G01Y727500D02*
Y730833D01*
G01X731070Y728083D02*
X731487Y727750D01*
X732070Y727500D01*
X732570D01*
X733070Y727667D01*
X733403Y727917D01*
X733570Y728250D01*
X733487Y728750D01*
X733153Y729000D01*
X731653Y729500D01*
X731320Y730083D01*
X731487Y730500D01*
X731820Y730750D01*
X732320Y730833D01*
X732820Y730750D01*
X733320Y730500D01*
G01X737920Y732500D02*
Y727500D01*
G01X736753Y730833D02*
X739087D01*
G01X748620Y727500D02*
Y731750D01*
X748787Y732167D01*
X749120Y732417D01*
X749620Y732500D01*
X750120Y732333D01*
X750370Y731917D01*
G01X749370Y730500D02*
X747703D01*
G01X754720Y727500D02*
X754220Y727583D01*
X753720Y727917D01*
X753387Y728500D01*
X753220Y729167D01*
X753387Y729833D01*
X753720Y730417D01*
X754220Y730750D01*
X754720Y730833D01*
X755220Y730750D01*
X755720Y730417D01*
X756053Y729833D01*
X756137Y729167D01*
X756053Y728500D01*
X755720Y727917D01*
X755220Y727583D01*
X754720Y727500D01*
G01X760320D02*
Y732500D01*
G01X765920Y727500D02*
Y732500D01*
G01X771520Y727500D02*
X771020Y727583D01*
X770520Y727917D01*
X770187Y728500D01*
X770020Y729167D01*
X770187Y729833D01*
X770520Y730417D01*
X771020Y730750D01*
X771520Y730833D01*
X772020Y730750D01*
X772520Y730417D01*
X772853Y729833D01*
X772937Y729167D01*
X772853Y728500D01*
X772520Y727917D01*
X772020Y727583D01*
X771520Y727500D01*
G01X775037Y730833D02*
X776037Y727500D01*
X777120Y730833D01*
X778203Y727500D01*
X779203Y730833D01*
G01X731100Y757300D02*
Y752300D01*
G01X729183Y757300D02*
X733017D01*
G01X736700Y752300D02*
X736200Y752383D01*
X735700Y752717D01*
X735367Y753300D01*
X735200Y753967D01*
X735367Y754633D01*
X735700Y755217D01*
X736200Y755550D01*
X736700Y755633D01*
X737200Y755550D01*
X737700Y755217D01*
X738033Y754633D01*
X738117Y753967D01*
X738033Y753300D01*
X737700Y752717D01*
X737200Y752383D01*
X736700Y752300D01*
G01X742300D02*
Y757300D01*
G01X746650Y754550D02*
X749317D01*
X749067Y755133D01*
X748650Y755467D01*
X748067Y755633D01*
X747483Y755550D01*
X746983Y755300D01*
X746650Y754717D01*
X746483Y754217D01*
Y753717D01*
X746650Y753217D01*
X747067Y752717D01*
X747567Y752383D01*
X748150Y752300D01*
X748733Y752467D01*
X749317Y752967D01*
G01X752333Y752300D02*
Y755633D01*
G01Y754967D02*
X752750Y755300D01*
X753167Y755550D01*
X753750Y755633D01*
X754167Y755550D01*
X754667Y755300D01*
G01X760600Y752300D02*
Y755633D01*
G01Y755050D02*
X760267Y755383D01*
X759767Y755550D01*
X759183Y755633D01*
X758600Y755467D01*
X758100Y755133D01*
X757767Y754633D01*
X757600Y753967D01*
X757767Y753300D01*
X758100Y752800D01*
X758600Y752467D01*
X759183Y752300D01*
X759767Y752383D01*
X760267Y752633D01*
X760600Y752967D01*
G01X763283Y752300D02*
Y755633D01*
G01Y754800D02*
X763617Y755217D01*
X764117Y755550D01*
X764783Y755633D01*
X765367Y755550D01*
X765867Y755217D01*
X766117Y754633D01*
Y752300D01*
G01X771633Y755217D02*
X771050Y755550D01*
X770550Y755633D01*
X769883Y755467D01*
X769383Y755133D01*
X769050Y754550D01*
X768967Y753967D01*
X769050Y753383D01*
X769383Y752883D01*
X769883Y752467D01*
X770550Y752300D01*
X771133Y752467D01*
X771633Y752800D01*
G01X774650Y754550D02*
X777317D01*
X777067Y755133D01*
X776650Y755467D01*
X776067Y755633D01*
X775483Y755550D01*
X774983Y755300D01*
X774650Y754717D01*
X774483Y754217D01*
Y753717D01*
X774650Y753217D01*
X775067Y752717D01*
X775567Y752383D01*
X776150Y752300D01*
X776733Y752467D01*
X777317Y752967D01*
G01X704017Y948800D02*
X706100Y943800D01*
X708183Y948800D01*
G01X709867Y944800D02*
X710367Y944217D01*
X711033Y943883D01*
X711783Y943800D01*
X712450Y943883D01*
X713117Y944300D01*
X713533Y944800D01*
X713617Y945300D01*
X713450Y945883D01*
X712867Y946300D01*
X712283Y946467D01*
X711533D01*
G01X712283D02*
X712783Y946717D01*
X713200Y947133D01*
X713367Y947633D01*
X713200Y948133D01*
X712783Y948550D01*
X712033Y948800D01*
X711283Y948717D01*
X710533Y948383D01*
G01X717300Y943633D02*
X717133Y943717D01*
Y943883D01*
X717300Y943967D01*
X717467Y943883D01*
Y943717D01*
X717300Y943633D01*
G01X723900Y943800D02*
Y948800D01*
X720817Y945217D01*
X724983D01*
G01X728500Y943633D02*
X728333Y943717D01*
Y943883D01*
X728500Y943967D01*
X728667Y943883D01*
Y943717D01*
X728500Y943633D01*
G01X734100Y943800D02*
Y948800D01*
X733100Y947800D01*
G01Y943800D02*
X735100D01*
G01X754917Y947967D02*
X755417Y948467D01*
X756000Y948717D01*
X756667Y948800D01*
X757500Y948633D01*
X758083Y948217D01*
X758250Y947717D01*
X758167Y947217D01*
X757833Y946800D01*
X756167Y945967D01*
X755417Y945383D01*
X754917Y944550D01*
X754750Y943800D01*
X758250D01*
G01X762100Y948800D02*
X761433Y948633D01*
X760933Y948217D01*
X760600Y947717D01*
X760350Y947050D01*
X760267Y946300D01*
X760350Y945550D01*
X760600Y944883D01*
X760933Y944383D01*
X761433Y943967D01*
X762100Y943800D01*
X762767Y943967D01*
X763267Y944383D01*
X763600Y944883D01*
X763850Y945550D01*
X763933Y946300D01*
X763850Y947050D01*
X763600Y947717D01*
X763267Y948217D01*
X762767Y948633D01*
X762100Y948800D01*
G01X767700Y943800D02*
Y948800D01*
X766700Y947800D01*
G01Y943800D02*
X768700D01*
G01X771467Y944550D02*
X771967Y944133D01*
X772550Y943883D01*
X773300Y943800D01*
X774050Y943967D01*
X774633Y944300D01*
X775050Y944883D01*
X775133Y945550D01*
X774967Y946217D01*
X774550Y946633D01*
X773967Y946967D01*
X773383Y947050D01*
X772800Y946967D01*
X772050Y946633D01*
X772300Y948800D01*
X774550D01*
G01X777400Y943633D02*
X780400Y948800D01*
G01X784500D02*
X783833Y948633D01*
X783333Y948217D01*
X783000Y947717D01*
X782750Y947050D01*
X782667Y946300D01*
X782750Y945550D01*
X783000Y944883D01*
X783333Y944383D01*
X783833Y943967D01*
X784500Y943800D01*
X785167Y943967D01*
X785667Y944383D01*
X786000Y944883D01*
X786250Y945550D01*
X786333Y946300D01*
X786250Y947050D01*
X786000Y947717D01*
X785667Y948217D01*
X785167Y948633D01*
X784500Y948800D01*
G01X788517Y945883D02*
X789100Y946467D01*
X789600Y946800D01*
X790267Y946967D01*
X790850Y946800D01*
X791267Y946467D01*
X791600Y945967D01*
X791683Y945383D01*
X791600Y944883D01*
X791267Y944383D01*
X790767Y943967D01*
X790183Y943800D01*
X789517Y943967D01*
X788933Y944467D01*
X788600Y945217D01*
X788517Y946050D01*
X788683Y947133D01*
X788933Y947717D01*
X789350Y948300D01*
X789933Y948717D01*
X790517Y948800D01*
X791100Y948633D01*
X791517Y948217D01*
G01X764453Y526953D02*
X763620Y527787D01*
X763203Y528620D01*
Y531953D01*
X763620Y532787D01*
X764453Y533620D01*
G01X770470Y528620D02*
X769970Y528703D01*
X769470Y529037D01*
X769137Y529620D01*
X768970Y530287D01*
X769137Y530953D01*
X769470Y531537D01*
X769970Y531870D01*
X770470Y531953D01*
X770970Y531870D01*
X771470Y531537D01*
X771803Y530953D01*
X771887Y530287D01*
X771803Y529620D01*
X771470Y529037D01*
X770970Y528703D01*
X770470Y528620D01*
G01X774903D02*
Y531953D01*
G01Y531287D02*
X775320Y531620D01*
X775737Y531870D01*
X776320Y531953D01*
X776737Y531870D01*
X777237Y531620D01*
G01X826600Y939300D02*
Y15800D01*
X1456600D01*
Y870800D01*
X826600D01*
G01X836267Y50550D02*
X836767Y50133D01*
X837350Y49883D01*
X838100Y49800D01*
X838850Y49967D01*
X839433Y50300D01*
X839850Y50883D01*
X839933Y51550D01*
X839767Y52217D01*
X839350Y52633D01*
X838767Y52967D01*
X838183Y53050D01*
X837600Y52967D01*
X836850Y52633D01*
X837100Y54800D01*
X839350D01*
G01X843700Y49633D02*
X843533Y49717D01*
Y49883D01*
X843700Y49967D01*
X843867Y49883D01*
Y49717D01*
X843700Y49633D01*
G01X853233Y49800D02*
Y54800D01*
X855317D01*
X855983Y54550D01*
X856400Y54217D01*
X856567Y53550D01*
X856400Y52883D01*
X855900Y52467D01*
X855317Y52217D01*
X853233D01*
G01X855317D02*
X856567Y49800D01*
G01X859250Y52050D02*
X861917D01*
X861667Y52633D01*
X861250Y52967D01*
X860667Y53133D01*
X860083Y53050D01*
X859583Y52800D01*
X859250Y52217D01*
X859083Y51717D01*
Y51217D01*
X859250Y50717D01*
X859667Y50217D01*
X860167Y49883D01*
X860750Y49800D01*
X861333Y49967D01*
X861917Y50467D01*
G01X863600Y49800D02*
Y53133D01*
G01Y52217D02*
X863850Y52633D01*
X864267Y52967D01*
X864850Y53133D01*
X865433Y52967D01*
X865850Y52633D01*
X866100Y52217D01*
Y49800D01*
G01Y52217D02*
X866350Y52633D01*
X866767Y52967D01*
X867350Y53133D01*
X867933Y52967D01*
X868350Y52633D01*
X868600Y52133D01*
Y49800D01*
G01X873200D02*
Y53133D01*
G01Y52550D02*
X872867Y52883D01*
X872367Y53050D01*
X871783Y53133D01*
X871200Y52967D01*
X870700Y52633D01*
X870367Y52133D01*
X870200Y51467D01*
X870367Y50800D01*
X870700Y50300D01*
X871200Y49967D01*
X871783Y49800D01*
X872367Y49883D01*
X872867Y50133D01*
X873200Y50467D01*
G01X876133Y49800D02*
Y53133D01*
G01Y52467D02*
X876550Y52800D01*
X876967Y53050D01*
X877550Y53133D01*
X877967Y53050D01*
X878467Y52800D01*
G01X881483Y49800D02*
Y54800D01*
G01X884150Y53133D02*
X881483Y51217D01*
G01X882567Y51967D02*
X884317Y49800D01*
G01X886667Y49633D02*
X890333Y53300D01*
G01X888500Y53967D02*
Y48967D01*
G01X890333Y49633D02*
X886667Y53300D01*
G01X886000Y51467D02*
X891000D01*
G01X826600Y35800D02*
X1456600D01*
G01X826600Y65800D02*
X1456600D01*
G01X808100Y804800D02*
Y19300D01*
G01X826600Y174300D02*
X1456600D01*
G01X839100Y438300D02*
Y443300D01*
X836017Y439717D01*
X840183D01*
G01X843700Y438133D02*
X843533Y438217D01*
Y438383D01*
X843700Y438467D01*
X843867Y438383D01*
Y438217D01*
X843700Y438133D01*
G01X853400Y438300D02*
Y443300D01*
G01Y440800D02*
X853817Y441300D01*
X854317Y441550D01*
X854817Y441633D01*
X855567Y441467D01*
X856067Y441133D01*
X856400Y440550D01*
Y439883D01*
X856233Y439217D01*
X855900Y438717D01*
X855317Y438383D01*
X854817Y438300D01*
X854317Y438383D01*
X853817Y438633D01*
X853400Y439050D01*
G01X862000Y438300D02*
Y441633D01*
G01Y441050D02*
X861667Y441383D01*
X861167Y441550D01*
X860583Y441633D01*
X860000Y441467D01*
X859500Y441133D01*
X859167Y440633D01*
X859000Y439967D01*
X859167Y439300D01*
X859500Y438800D01*
X860000Y438467D01*
X860583Y438300D01*
X861167Y438383D01*
X861667Y438633D01*
X862000Y438967D01*
G01X867433Y441217D02*
X866850Y441550D01*
X866350Y441633D01*
X865683Y441467D01*
X865183Y441133D01*
X864850Y440550D01*
X864767Y439967D01*
X864850Y439383D01*
X865183Y438883D01*
X865683Y438467D01*
X866350Y438300D01*
X866933Y438467D01*
X867433Y438800D01*
G01X870283Y438300D02*
Y443300D01*
G01X872950Y441633D02*
X870283Y439717D01*
G01X871367Y440467D02*
X873117Y438300D01*
G01X878800Y443300D02*
Y438300D01*
G01Y439050D02*
X878467Y438633D01*
X877967Y438383D01*
X877383Y438300D01*
X876717Y438467D01*
X876217Y438883D01*
X875883Y439383D01*
X875800Y439967D01*
X875883Y440550D01*
X876217Y441050D01*
X876717Y441467D01*
X877383Y441633D01*
X877967Y441550D01*
X878383Y441383D01*
X878800Y441050D01*
G01X881733Y438300D02*
Y441633D01*
G01Y440967D02*
X882150Y441300D01*
X882567Y441550D01*
X883150Y441633D01*
X883567Y441550D01*
X884067Y441300D01*
G01X888500Y441633D02*
Y438300D01*
G01Y442967D02*
X888333Y443050D01*
Y443217D01*
X888500Y443300D01*
X888667Y443217D01*
Y443050D01*
X888500Y442967D01*
G01X894100Y438300D02*
Y443300D01*
G01X899700Y438300D02*
Y443300D01*
G01X912400Y438300D02*
Y441633D01*
G01Y441050D02*
X912067Y441383D01*
X911567Y441550D01*
X910983Y441633D01*
X910400Y441467D01*
X909900Y441133D01*
X909567Y440633D01*
X909400Y439967D01*
X909567Y439300D01*
X909900Y438800D01*
X910400Y438467D01*
X910983Y438300D01*
X911567Y438383D01*
X912067Y438633D01*
X912400Y438967D01*
G01X915083Y438300D02*
Y441633D01*
G01Y440800D02*
X915417Y441217D01*
X915917Y441550D01*
X916583Y441633D01*
X917167Y441550D01*
X917667Y441217D01*
X917917Y440633D01*
Y438300D01*
G01X923600Y443300D02*
Y438300D01*
G01Y439050D02*
X923267Y438633D01*
X922767Y438383D01*
X922183Y438300D01*
X921517Y438467D01*
X921017Y438883D01*
X920683Y439383D01*
X920600Y439967D01*
X920683Y440550D01*
X921017Y441050D01*
X921517Y441467D01*
X922183Y441633D01*
X922767Y441550D01*
X923183Y441383D01*
X923600Y441050D01*
G01X932050Y438883D02*
X932467Y438550D01*
X933050Y438300D01*
X933550D01*
X934050Y438467D01*
X934383Y438717D01*
X934550Y439050D01*
X934467Y439550D01*
X934133Y439800D01*
X932633Y440300D01*
X932300Y440883D01*
X932467Y441300D01*
X932800Y441550D01*
X933300Y441633D01*
X933800Y441550D01*
X934300Y441300D01*
G01X940400Y436633D02*
Y441633D01*
G01Y440883D02*
X939983Y441300D01*
X939483Y441550D01*
X938900Y441633D01*
X938400Y441550D01*
X937817Y441133D01*
X937483Y440550D01*
X937400Y439967D01*
X937483Y439383D01*
X937817Y438800D01*
X938400Y438383D01*
X938900Y438300D01*
X939483Y438383D01*
X939983Y438633D01*
X940400Y439050D01*
G01X943083Y441633D02*
Y439300D01*
X943417Y438717D01*
X943917Y438383D01*
X944500Y438300D01*
X945083Y438383D01*
X945583Y438717D01*
X945917Y439300D01*
G01Y438300D02*
Y441633D01*
G01X951600Y438300D02*
Y441633D01*
G01Y441050D02*
X951267Y441383D01*
X950767Y441550D01*
X950183Y441633D01*
X949600Y441467D01*
X949100Y441133D01*
X948767Y440633D01*
X948600Y439967D01*
X948767Y439300D01*
X949100Y438800D01*
X949600Y438467D01*
X950183Y438300D01*
X950767Y438383D01*
X951267Y438633D01*
X951600Y438967D01*
G01X954533Y438300D02*
Y441633D01*
G01Y440967D02*
X954950Y441300D01*
X955367Y441550D01*
X955950Y441633D01*
X956367Y441550D01*
X956867Y441300D01*
G01X960050Y440550D02*
X962717D01*
X962467Y441133D01*
X962050Y441467D01*
X961467Y441633D01*
X960883Y441550D01*
X960383Y441300D01*
X960050Y440717D01*
X959883Y440217D01*
Y439717D01*
X960050Y439217D01*
X960467Y438717D01*
X960967Y438383D01*
X961550Y438300D01*
X962133Y438467D01*
X962717Y438967D01*
G01X971083Y438300D02*
Y443300D01*
G01Y440883D02*
X971500Y441300D01*
X971917Y441550D01*
X972583Y441633D01*
X973083Y441550D01*
X973667Y441217D01*
X973917Y440717D01*
Y438300D01*
G01X978100D02*
X977600Y438383D01*
X977100Y438717D01*
X976767Y439300D01*
X976600Y439967D01*
X976767Y440633D01*
X977100Y441217D01*
X977600Y441550D01*
X978100Y441633D01*
X978600Y441550D01*
X979100Y441217D01*
X979433Y440633D01*
X979517Y439967D01*
X979433Y439300D01*
X979100Y438717D01*
X978600Y438383D01*
X978100Y438300D01*
G01X983700D02*
Y443300D01*
G01X988050Y440550D02*
X990717D01*
X990467Y441133D01*
X990050Y441467D01*
X989467Y441633D01*
X988883Y441550D01*
X988383Y441300D01*
X988050Y440717D01*
X987883Y440217D01*
Y439717D01*
X988050Y439217D01*
X988467Y438717D01*
X988967Y438383D01*
X989550Y438300D01*
X990133Y438467D01*
X990717Y438967D01*
G01X994900Y438133D02*
X994733Y438217D01*
Y438383D01*
X994900Y438467D01*
X995067Y438383D01*
Y438217D01*
X994900Y438133D01*
G01Y440383D02*
X994733Y440467D01*
Y440633D01*
X994900Y440717D01*
X995067Y440633D01*
Y440467D01*
X994900Y440383D01*
G01X826600Y424300D02*
X1456600D01*
G01X835007Y463473D02*
X838673Y467140D01*
G01X836840Y467807D02*
Y462807D01*
G01X838673Y463473D02*
X835007Y467140D01*
G01X834340Y465307D02*
X839340D01*
G01X842023Y461973D02*
X841190Y462807D01*
X840773Y463640D01*
Y466973D01*
X841190Y467807D01*
X842023Y468640D01*
G01X846207Y464390D02*
X846707Y463973D01*
X847290Y463723D01*
X848040Y463640D01*
X848790Y463807D01*
X849373Y464140D01*
X849790Y464723D01*
X849873Y465390D01*
X849707Y466057D01*
X849290Y466473D01*
X848707Y466807D01*
X848123Y466890D01*
X847540Y466807D01*
X846790Y466473D01*
X847040Y468640D01*
X849290D01*
G01X853640Y463473D02*
X853473Y463557D01*
Y463723D01*
X853640Y463807D01*
X853807Y463723D01*
Y463557D01*
X853640Y463473D01*
G01X859240Y463640D02*
Y468640D01*
X858240Y467640D01*
G01Y463640D02*
X860240D01*
G01X865257Y461973D02*
X866090Y462807D01*
X866507Y463640D01*
Y466973D01*
X866090Y467807D01*
X865257Y468640D01*
G01X834707Y497103D02*
X838373Y500770D01*
G01X836540Y501437D02*
Y496437D01*
G01X838373Y497103D02*
X834707Y500770D01*
G01X834040Y498937D02*
X839040D01*
G01X841723Y495603D02*
X840890Y496437D01*
X840473Y497270D01*
Y500603D01*
X840890Y501437D01*
X841723Y502270D01*
G01X845907Y498020D02*
X846407Y497603D01*
X846990Y497353D01*
X847740Y497270D01*
X848490Y497437D01*
X849073Y497770D01*
X849490Y498353D01*
X849573Y499020D01*
X849407Y499687D01*
X848990Y500103D01*
X848407Y500437D01*
X847823Y500520D01*
X847240Y500437D01*
X846490Y500103D01*
X846740Y502270D01*
X848990D01*
G01X853340Y497103D02*
X853173Y497187D01*
Y497353D01*
X853340Y497437D01*
X853507Y497353D01*
Y497187D01*
X853340Y497103D01*
G01X858940Y497270D02*
Y502270D01*
X857940Y501270D01*
G01Y497270D02*
X859940D01*
G01X864957Y495603D02*
X865790Y496437D01*
X866207Y497270D01*
Y500603D01*
X865790Y501437D01*
X864957Y502270D01*
G01X834817Y480540D02*
X836900Y475540D01*
X838983Y480540D01*
G01X842500Y478873D02*
Y475540D01*
G01Y480207D02*
X842333Y480290D01*
Y480457D01*
X842500Y480540D01*
X842667Y480457D01*
Y480290D01*
X842500Y480207D01*
G01X849600Y475540D02*
Y478873D01*
G01Y478290D02*
X849267Y478623D01*
X848767Y478790D01*
X848183Y478873D01*
X847600Y478707D01*
X847100Y478373D01*
X846767Y477873D01*
X846600Y477207D01*
X846767Y476540D01*
X847100Y476040D01*
X847600Y475707D01*
X848183Y475540D01*
X848767Y475623D01*
X849267Y475873D01*
X849600Y476207D01*
G01X858300Y480540D02*
X860300D01*
G01X859300D02*
Y475540D01*
G01X858300D02*
X860300D01*
G01X863483D02*
Y478873D01*
G01Y478040D02*
X863817Y478457D01*
X864317Y478790D01*
X864983Y478873D01*
X865567Y478790D01*
X866067Y478457D01*
X866317Y477873D01*
Y475540D01*
G01X874433D02*
Y480540D01*
X876433D01*
X877100Y480290D01*
X877600Y479707D01*
X877767Y479040D01*
X877600Y478373D01*
X877183Y477873D01*
X876433Y477623D01*
X874433D01*
G01X883200Y475540D02*
Y478873D01*
G01Y478290D02*
X882867Y478623D01*
X882367Y478790D01*
X881783Y478873D01*
X881200Y478707D01*
X880700Y478373D01*
X880367Y477873D01*
X880200Y477207D01*
X880367Y476540D01*
X880700Y476040D01*
X881200Y475707D01*
X881783Y475540D01*
X882367Y475623D01*
X882867Y475873D01*
X883200Y476207D01*
G01X888800Y480540D02*
Y475540D01*
G01Y476290D02*
X888467Y475873D01*
X887967Y475623D01*
X887383Y475540D01*
X886717Y475707D01*
X886217Y476123D01*
X885883Y476623D01*
X885800Y477207D01*
X885883Y477790D01*
X886217Y478290D01*
X886717Y478707D01*
X887383Y478873D01*
X887967Y478790D01*
X888383Y478623D01*
X888800Y478290D01*
G01X892483Y473873D02*
X891650Y474707D01*
X891233Y475540D01*
Y478873D01*
X891650Y479707D01*
X892483Y480540D01*
G01X896417D02*
X898500Y475540D01*
X900583Y480540D01*
G01X903100D02*
X905100D01*
G01X904100D02*
Y475540D01*
G01X903100D02*
X905100D01*
G01X908033D02*
Y480540D01*
X910033D01*
X910700Y480290D01*
X911200Y479707D01*
X911367Y479040D01*
X911200Y478373D01*
X910783Y477873D01*
X910033Y477623D01*
X908033D01*
G01X915717Y473873D02*
X916550Y474707D01*
X916967Y475540D01*
Y478873D01*
X916550Y479707D01*
X915717Y480540D01*
G01X826600Y454300D02*
X1456600D01*
G01X826600Y489300D02*
X1456600D01*
G01X834517Y513300D02*
X836600Y508300D01*
X838683Y513300D01*
G01X842200Y511633D02*
Y508300D01*
G01Y512967D02*
X842033Y513050D01*
Y513217D01*
X842200Y513300D01*
X842367Y513217D01*
Y513050D01*
X842200Y512967D01*
G01X849300Y508300D02*
Y511633D01*
G01Y511050D02*
X848967Y511383D01*
X848467Y511550D01*
X847883Y511633D01*
X847300Y511467D01*
X846800Y511133D01*
X846467Y510633D01*
X846300Y509967D01*
X846467Y509300D01*
X846800Y508800D01*
X847300Y508467D01*
X847883Y508300D01*
X848467Y508383D01*
X848967Y508633D01*
X849300Y508967D01*
G01X859000Y508300D02*
X858333Y508383D01*
X857750Y508717D01*
X857250Y509217D01*
X856917Y509800D01*
X856750Y510467D01*
Y511133D01*
X856917Y511800D01*
X857250Y512383D01*
X857750Y512883D01*
X858333Y513217D01*
X859000Y513300D01*
X859667Y513217D01*
X860250Y512883D01*
X860750Y512383D01*
X861083Y511800D01*
X861250Y511133D01*
Y510467D01*
X861083Y509800D01*
X860750Y509217D01*
X860250Y508717D01*
X859667Y508383D01*
X859000Y508300D01*
G01X863183D02*
Y511633D01*
G01Y510800D02*
X863517Y511217D01*
X864017Y511550D01*
X864683Y511633D01*
X865267Y511550D01*
X865767Y511217D01*
X866017Y510633D01*
Y508300D01*
G01X874133D02*
Y513300D01*
X876133D01*
X876800Y513050D01*
X877300Y512467D01*
X877467Y511800D01*
X877300Y511133D01*
X876883Y510633D01*
X876133Y510383D01*
X874133D01*
G01X882900Y508300D02*
Y511633D01*
G01Y511050D02*
X882567Y511383D01*
X882067Y511550D01*
X881483Y511633D01*
X880900Y511467D01*
X880400Y511133D01*
X880067Y510633D01*
X879900Y509967D01*
X880067Y509300D01*
X880400Y508800D01*
X880900Y508467D01*
X881483Y508300D01*
X882067Y508383D01*
X882567Y508633D01*
X882900Y508967D01*
G01X888500Y513300D02*
Y508300D01*
G01Y509050D02*
X888167Y508633D01*
X887667Y508383D01*
X887083Y508300D01*
X886417Y508467D01*
X885917Y508883D01*
X885583Y509383D01*
X885500Y509967D01*
X885583Y510550D01*
X885917Y511050D01*
X886417Y511467D01*
X887083Y511633D01*
X887667Y511550D01*
X888083Y511383D01*
X888500Y511050D01*
G01X892183Y506633D02*
X891350Y507467D01*
X890933Y508300D01*
Y511633D01*
X891350Y512467D01*
X892183Y513300D01*
G01X896117D02*
X898200Y508300D01*
X900283Y513300D01*
G01X903800Y508300D02*
X903133Y508383D01*
X902550Y508717D01*
X902050Y509217D01*
X901717Y509800D01*
X901550Y510467D01*
Y511133D01*
X901717Y511800D01*
X902050Y512383D01*
X902550Y512883D01*
X903133Y513217D01*
X903800Y513300D01*
X904467Y513217D01*
X905050Y512883D01*
X905550Y512383D01*
X905883Y511800D01*
X906050Y511133D01*
Y510467D01*
X905883Y509800D01*
X905550Y509217D01*
X905050Y508717D01*
X904467Y508383D01*
X903800Y508300D01*
G01X907733D02*
Y513300D01*
X909733D01*
X910400Y513050D01*
X910900Y512467D01*
X911067Y511800D01*
X910900Y511133D01*
X910483Y510633D01*
X909733Y510383D01*
X907733D01*
G01X915417Y506633D02*
X916250Y507467D01*
X916667Y508300D01*
Y511633D01*
X916250Y512467D01*
X915417Y513300D01*
G01X837267Y531967D02*
X837600Y532217D01*
X837850Y532633D01*
X838017Y533217D01*
X837850Y533717D01*
X837517Y534050D01*
X836933Y534300D01*
X834683D01*
Y529300D01*
X837433D01*
X838017Y529633D01*
X838350Y530133D01*
X838517Y530717D01*
X838350Y531300D01*
X837850Y531800D01*
X837267Y531967D01*
X834683D01*
G01X840783Y532633D02*
Y530300D01*
X841117Y529717D01*
X841617Y529383D01*
X842200Y529300D01*
X842783Y529383D01*
X843283Y529717D01*
X843617Y530300D01*
G01Y529300D02*
Y532633D01*
G01X846633Y529300D02*
Y532633D01*
G01Y531967D02*
X847050Y532300D01*
X847467Y532550D01*
X848050Y532633D01*
X848467Y532550D01*
X848967Y532300D01*
G01X853400Y532633D02*
Y529300D01*
G01Y533967D02*
X853233Y534050D01*
Y534217D01*
X853400Y534300D01*
X853567Y534217D01*
Y534050D01*
X853400Y533967D01*
G01X857750Y531550D02*
X860417D01*
X860167Y532133D01*
X859750Y532467D01*
X859167Y532633D01*
X858583Y532550D01*
X858083Y532300D01*
X857750Y531717D01*
X857583Y531217D01*
Y530717D01*
X857750Y530217D01*
X858167Y529717D01*
X858667Y529383D01*
X859250Y529300D01*
X859833Y529467D01*
X860417Y529967D01*
G01X866100Y534300D02*
Y529300D01*
G01Y530050D02*
X865767Y529633D01*
X865267Y529383D01*
X864683Y529300D01*
X864017Y529467D01*
X863517Y529883D01*
X863183Y530383D01*
X863100Y530967D01*
X863183Y531550D01*
X863517Y532050D01*
X864017Y532467D01*
X864683Y532633D01*
X865267Y532550D01*
X865683Y532383D01*
X866100Y532050D01*
G01X874383Y529300D02*
Y534300D01*
G01Y531883D02*
X874800Y532300D01*
X875217Y532550D01*
X875883Y532633D01*
X876383Y532550D01*
X876967Y532217D01*
X877217Y531717D01*
Y529300D01*
G01X881400D02*
X880900Y529383D01*
X880400Y529717D01*
X880067Y530300D01*
X879900Y530967D01*
X880067Y531633D01*
X880400Y532217D01*
X880900Y532550D01*
X881400Y532633D01*
X881900Y532550D01*
X882400Y532217D01*
X882733Y531633D01*
X882817Y530967D01*
X882733Y530300D01*
X882400Y529717D01*
X881900Y529383D01*
X881400Y529300D01*
G01X887000D02*
Y534300D01*
G01X891350Y531550D02*
X894017D01*
X893767Y532133D01*
X893350Y532467D01*
X892767Y532633D01*
X892183Y532550D01*
X891683Y532300D01*
X891350Y531717D01*
X891183Y531217D01*
Y530717D01*
X891350Y530217D01*
X891767Y529717D01*
X892267Y529383D01*
X892850Y529300D01*
X893433Y529467D01*
X894017Y529967D01*
G01X835017Y550300D02*
Y555300D01*
X838183D01*
G01X837017Y552883D02*
X835017D01*
G01X840783Y553633D02*
Y551300D01*
X841117Y550717D01*
X841617Y550383D01*
X842200Y550300D01*
X842783Y550383D01*
X843283Y550717D01*
X843617Y551300D01*
G01Y550300D02*
Y553633D01*
G01X847800Y550300D02*
Y555300D01*
G01X853400Y550300D02*
Y555300D01*
G01X863100Y548633D02*
Y553633D01*
G01Y552883D02*
X863517Y553300D01*
X863933Y553550D01*
X864600Y553633D01*
X865183Y553550D01*
X865767Y553133D01*
X866017Y552550D01*
X866100Y551967D01*
X866017Y551383D01*
X865767Y550800D01*
X865267Y550467D01*
X864600Y550300D01*
X864017Y550383D01*
X863433Y550633D01*
X863100Y550967D01*
G01X870200Y550300D02*
Y555300D01*
G01X874383Y553633D02*
Y551300D01*
X874717Y550717D01*
X875217Y550383D01*
X875800Y550300D01*
X876383Y550383D01*
X876883Y550717D01*
X877217Y551300D01*
G01Y550300D02*
Y553633D01*
G01X880233Y549050D02*
X880817Y548717D01*
X881483Y548633D01*
X882067Y548717D01*
X882567Y549133D01*
X882900Y549717D01*
Y553633D01*
G01Y552967D02*
X882567Y553300D01*
X882067Y553550D01*
X881483Y553633D01*
X880817Y553467D01*
X880400Y553133D01*
X880067Y552550D01*
X879900Y551967D01*
X879983Y551467D01*
X880317Y550883D01*
X880817Y550467D01*
X881483Y550300D01*
X881983Y550383D01*
X882567Y550717D01*
X882900Y551050D01*
G01X885833Y549050D02*
X886417Y548717D01*
X887083Y548633D01*
X887667Y548717D01*
X888167Y549133D01*
X888500Y549717D01*
Y553633D01*
G01Y552967D02*
X888167Y553300D01*
X887667Y553550D01*
X887083Y553633D01*
X886417Y553467D01*
X886000Y553133D01*
X885667Y552550D01*
X885500Y551967D01*
X885583Y551467D01*
X885917Y550883D01*
X886417Y550467D01*
X887083Y550300D01*
X887583Y550383D01*
X888167Y550717D01*
X888500Y551050D01*
G01X892600Y553633D02*
Y550300D01*
G01Y554967D02*
X892433Y555050D01*
Y555217D01*
X892600Y555300D01*
X892767Y555217D01*
Y555050D01*
X892600Y554967D01*
G01X896783Y550300D02*
Y553633D01*
G01Y552800D02*
X897117Y553217D01*
X897617Y553550D01*
X898283Y553633D01*
X898867Y553550D01*
X899367Y553217D01*
X899617Y552633D01*
Y550300D01*
G01X902633Y549050D02*
X903217Y548717D01*
X903883Y548633D01*
X904467Y548717D01*
X904967Y549133D01*
X905300Y549717D01*
Y553633D01*
G01Y552967D02*
X904967Y553300D01*
X904467Y553550D01*
X903883Y553633D01*
X903217Y553467D01*
X902800Y553133D01*
X902467Y552550D01*
X902300Y551967D01*
X902383Y551467D01*
X902717Y550883D01*
X903217Y550467D01*
X903883Y550300D01*
X904383Y550383D01*
X904967Y550717D01*
X905300Y551050D01*
G01X826600Y524300D02*
X1456600D01*
G01X826600Y539300D02*
X1456600D01*
G01X826600Y566300D02*
X1456600D01*
G01X834850Y618800D02*
Y623800D01*
G01X838350D02*
Y618800D01*
G01Y621300D02*
X834850D01*
G01X843700Y618800D02*
Y622133D01*
G01Y621550D02*
X843367Y621883D01*
X842867Y622050D01*
X842283Y622133D01*
X841700Y621967D01*
X841200Y621633D01*
X840867Y621133D01*
X840700Y620467D01*
X840867Y619800D01*
X841200Y619300D01*
X841700Y618967D01*
X842283Y618800D01*
X842867Y618883D01*
X843367Y619133D01*
X843700Y619467D01*
G01X847800Y618800D02*
Y623800D01*
G01X852900Y618800D02*
Y623050D01*
X853067Y623467D01*
X853400Y623717D01*
X853900Y623800D01*
X854400Y623633D01*
X854650Y623217D01*
G01X853650Y621800D02*
X851983D01*
G01X862933Y618800D02*
Y623800D01*
X864933D01*
X865600Y623550D01*
X866100Y622967D01*
X866267Y622300D01*
X866100Y621633D01*
X865683Y621133D01*
X864933Y620883D01*
X862933D01*
G01X870200Y618800D02*
Y623800D01*
G01X874383Y622133D02*
Y619800D01*
X874717Y619217D01*
X875217Y618883D01*
X875800Y618800D01*
X876383Y618883D01*
X876883Y619217D01*
X877217Y619800D01*
G01Y618800D02*
Y622133D01*
G01X880233Y617550D02*
X880817Y617217D01*
X881483Y617133D01*
X882067Y617217D01*
X882567Y617633D01*
X882900Y618217D01*
Y622133D01*
G01Y621467D02*
X882567Y621800D01*
X882067Y622050D01*
X881483Y622133D01*
X880817Y621967D01*
X880400Y621633D01*
X880067Y621050D01*
X879900Y620467D01*
X879983Y619967D01*
X880317Y619383D01*
X880817Y618967D01*
X881483Y618800D01*
X881983Y618883D01*
X882567Y619217D01*
X882900Y619550D01*
G01X885833Y617550D02*
X886417Y617217D01*
X887083Y617133D01*
X887667Y617217D01*
X888167Y617633D01*
X888500Y618217D01*
Y622133D01*
G01Y621467D02*
X888167Y621800D01*
X887667Y622050D01*
X887083Y622133D01*
X886417Y621967D01*
X886000Y621633D01*
X885667Y621050D01*
X885500Y620467D01*
X885583Y619967D01*
X885917Y619383D01*
X886417Y618967D01*
X887083Y618800D01*
X887583Y618883D01*
X888167Y619217D01*
X888500Y619550D01*
G01X892600Y622133D02*
Y618800D01*
G01Y623467D02*
X892433Y623550D01*
Y623717D01*
X892600Y623800D01*
X892767Y623717D01*
Y623550D01*
X892600Y623467D01*
G01X896783Y618800D02*
Y622133D01*
G01Y621300D02*
X897117Y621717D01*
X897617Y622050D01*
X898283Y622133D01*
X898867Y622050D01*
X899367Y621717D01*
X899617Y621133D01*
Y618800D01*
G01X902633Y617550D02*
X903217Y617217D01*
X903883Y617133D01*
X904467Y617217D01*
X904967Y617633D01*
X905300Y618217D01*
Y622133D01*
G01Y621467D02*
X904967Y621800D01*
X904467Y622050D01*
X903883Y622133D01*
X903217Y621967D01*
X902800Y621633D01*
X902467Y621050D01*
X902300Y620467D01*
X902383Y619967D01*
X902717Y619383D01*
X903217Y618967D01*
X903883Y618800D01*
X904383Y618883D01*
X904967Y619217D01*
X905300Y619550D01*
G01X836433Y677800D02*
Y682800D01*
X838433D01*
X839100Y682550D01*
X839600Y681967D01*
X839767Y681300D01*
X839600Y680633D01*
X839183Y680133D01*
X838433Y679883D01*
X836433D01*
G01X843700Y677800D02*
Y682800D01*
G01X847883Y681133D02*
Y678800D01*
X848217Y678217D01*
X848717Y677883D01*
X849300Y677800D01*
X849883Y677883D01*
X850383Y678217D01*
X850717Y678800D01*
G01Y677800D02*
Y681133D01*
G01X853733Y676550D02*
X854317Y676217D01*
X854983Y676133D01*
X855567Y676217D01*
X856067Y676633D01*
X856400Y677217D01*
Y681133D01*
G01Y680467D02*
X856067Y680800D01*
X855567Y681050D01*
X854983Y681133D01*
X854317Y680967D01*
X853900Y680633D01*
X853567Y680050D01*
X853400Y679467D01*
X853483Y678967D01*
X853817Y678383D01*
X854317Y677967D01*
X854983Y677800D01*
X855483Y677883D01*
X856067Y678217D01*
X856400Y678550D01*
G01X859333Y676550D02*
X859917Y676217D01*
X860583Y676133D01*
X861167Y676217D01*
X861667Y676633D01*
X862000Y677217D01*
Y681133D01*
G01Y680467D02*
X861667Y680800D01*
X861167Y681050D01*
X860583Y681133D01*
X859917Y680967D01*
X859500Y680633D01*
X859167Y680050D01*
X859000Y679467D01*
X859083Y678967D01*
X859417Y678383D01*
X859917Y677967D01*
X860583Y677800D01*
X861083Y677883D01*
X861667Y678217D01*
X862000Y678550D01*
G01X866100Y681133D02*
Y677800D01*
G01Y682467D02*
X865933Y682550D01*
Y682717D01*
X866100Y682800D01*
X866267Y682717D01*
Y682550D01*
X866100Y682467D01*
G01X870283Y677800D02*
Y681133D01*
G01Y680300D02*
X870617Y680717D01*
X871117Y681050D01*
X871783Y681133D01*
X872367Y681050D01*
X872867Y680717D01*
X873117Y680133D01*
Y677800D01*
G01X876133Y676550D02*
X876717Y676217D01*
X877383Y676133D01*
X877967Y676217D01*
X878467Y676633D01*
X878800Y677217D01*
Y681133D01*
G01Y680467D02*
X878467Y680800D01*
X877967Y681050D01*
X877383Y681133D01*
X876717Y680967D01*
X876300Y680633D01*
X875967Y680050D01*
X875800Y679467D01*
X875883Y678967D01*
X876217Y678383D01*
X876717Y677967D01*
X877383Y677800D01*
X877883Y677883D01*
X878467Y678217D01*
X878800Y678550D01*
G01X890000Y682800D02*
Y677800D01*
G01Y678550D02*
X889667Y678133D01*
X889167Y677883D01*
X888583Y677800D01*
X887917Y677967D01*
X887417Y678383D01*
X887083Y678883D01*
X887000Y679467D01*
X887083Y680050D01*
X887417Y680550D01*
X887917Y680967D01*
X888583Y681133D01*
X889167Y681050D01*
X889583Y680883D01*
X890000Y680550D01*
G01X892850Y680050D02*
X895517D01*
X895267Y680633D01*
X894850Y680967D01*
X894267Y681133D01*
X893683Y681050D01*
X893183Y680800D01*
X892850Y680217D01*
X892683Y679717D01*
Y679217D01*
X892850Y678717D01*
X893267Y678217D01*
X893767Y677883D01*
X894350Y677800D01*
X894933Y677967D01*
X895517Y678467D01*
G01X899200Y677800D02*
Y682050D01*
X899367Y682467D01*
X899700Y682717D01*
X900200Y682800D01*
X900700Y682633D01*
X900950Y682217D01*
G01X899950Y680800D02*
X898283D01*
G01X905300Y681133D02*
Y677800D01*
G01Y682467D02*
X905133Y682550D01*
Y682717D01*
X905300Y682800D01*
X905467Y682717D01*
Y682550D01*
X905300Y682467D01*
G01X909483Y677800D02*
Y681133D01*
G01Y680300D02*
X909817Y680717D01*
X910317Y681050D01*
X910983Y681133D01*
X911567Y681050D01*
X912067Y680717D01*
X912317Y680133D01*
Y677800D01*
G01X915250Y680050D02*
X917917D01*
X917667Y680633D01*
X917250Y680967D01*
X916667Y681133D01*
X916083Y681050D01*
X915583Y680800D01*
X915250Y680217D01*
X915083Y679717D01*
Y679217D01*
X915250Y678717D01*
X915667Y678217D01*
X916167Y677883D01*
X916750Y677800D01*
X917333Y677967D01*
X917917Y678467D01*
G01X826600Y668300D02*
X1456600D01*
G01X826600Y693300D02*
X1456600D01*
G01X826600Y840800D02*
X1458100D01*
G01X836267Y853800D02*
X836767Y853217D01*
X837433Y852883D01*
X838183Y852800D01*
X838850Y852883D01*
X839517Y853300D01*
X839933Y853800D01*
X840017Y854300D01*
X839850Y854883D01*
X839267Y855300D01*
X838683Y855467D01*
X837933D01*
G01X838683D02*
X839183Y855717D01*
X839600Y856133D01*
X839767Y856633D01*
X839600Y857133D01*
X839183Y857550D01*
X838433Y857800D01*
X837683Y857717D01*
X836933Y857383D01*
G01X843700Y852633D02*
X843533Y852717D01*
Y852883D01*
X843700Y852967D01*
X843867Y852883D01*
Y852717D01*
X843700Y852633D01*
G01X853233Y852800D02*
Y857800D01*
X855233D01*
X855900Y857550D01*
X856400Y856967D01*
X856567Y856300D01*
X856400Y855633D01*
X855983Y855133D01*
X855233Y854883D01*
X853233D01*
G01X860500Y852800D02*
Y857800D01*
G01X864683Y856133D02*
Y853800D01*
X865017Y853217D01*
X865517Y852883D01*
X866100Y852800D01*
X866683Y852883D01*
X867183Y853217D01*
X867517Y853800D01*
G01Y852800D02*
Y856133D01*
G01X870533Y851550D02*
X871117Y851217D01*
X871783Y851133D01*
X872367Y851217D01*
X872867Y851633D01*
X873200Y852217D01*
Y856133D01*
G01Y855467D02*
X872867Y855800D01*
X872367Y856050D01*
X871783Y856133D01*
X871117Y855967D01*
X870700Y855633D01*
X870367Y855050D01*
X870200Y854467D01*
X870283Y853967D01*
X870617Y853383D01*
X871117Y852967D01*
X871783Y852800D01*
X872283Y852883D01*
X872867Y853217D01*
X873200Y853550D01*
G01X881400Y856133D02*
X882900Y852800D01*
X884400Y856133D01*
G01X888500D02*
Y852800D01*
G01Y857467D02*
X888333Y857550D01*
Y857717D01*
X888500Y857800D01*
X888667Y857717D01*
Y857550D01*
X888500Y857467D01*
G01X895600Y852800D02*
Y856133D01*
G01Y855550D02*
X895267Y855883D01*
X894767Y856050D01*
X894183Y856133D01*
X893600Y855967D01*
X893100Y855633D01*
X892767Y855133D01*
X892600Y854467D01*
X892767Y853800D01*
X893100Y853300D01*
X893600Y852967D01*
X894183Y852800D01*
X894767Y852883D01*
X895267Y853133D01*
X895600Y853467D01*
G01X903800Y852633D02*
X906800Y857800D01*
G01X908817D02*
X910900Y852800D01*
X912983Y857800D01*
G01X916500Y852800D02*
X915833Y852883D01*
X915250Y853217D01*
X914750Y853717D01*
X914417Y854300D01*
X914250Y854967D01*
Y855633D01*
X914417Y856300D01*
X914750Y856883D01*
X915250Y857383D01*
X915833Y857717D01*
X916500Y857800D01*
X917167Y857717D01*
X917750Y857383D01*
X918250Y856883D01*
X918583Y856300D01*
X918750Y855633D01*
Y854967D01*
X918583Y854300D01*
X918250Y853717D01*
X917750Y853217D01*
X917167Y852883D01*
X916500Y852800D01*
G01X920433D02*
Y857800D01*
X922433D01*
X923100Y857550D01*
X923600Y856967D01*
X923767Y856300D01*
X923600Y855633D01*
X923183Y855133D01*
X922433Y854883D01*
X920433D01*
G01X926200Y852633D02*
X929200Y857800D01*
G01X931217D02*
X933300Y852800D01*
X935383Y857800D01*
G01X937900D02*
X939900D01*
G01X938900D02*
Y852800D01*
G01X937900D02*
X939900D01*
G01X942833D02*
Y857800D01*
X944833D01*
X945500Y857550D01*
X946000Y856967D01*
X946167Y856300D01*
X946000Y855633D01*
X945583Y855133D01*
X944833Y854883D01*
X942833D01*
G01X950100Y852633D02*
X949933Y852717D01*
Y852883D01*
X950100Y852967D01*
X950267Y852883D01*
Y852717D01*
X950100Y852633D01*
G01Y854883D02*
X949933Y854967D01*
Y855133D01*
X950100Y855217D01*
X950267Y855133D01*
Y854967D01*
X950100Y854883D01*
G01X838413Y901800D02*
Y906800D01*
X840497D01*
X841163Y906550D01*
X841580Y906217D01*
X841747Y905550D01*
X841580Y904883D01*
X841080Y904467D01*
X840497Y904217D01*
X838413D01*
G01X840497D02*
X841747Y901800D01*
G01X845680D02*
X845180Y901883D01*
X844680Y902217D01*
X844347Y902800D01*
X844180Y903467D01*
X844347Y904133D01*
X844680Y904717D01*
X845180Y905050D01*
X845680Y905133D01*
X846180Y905050D01*
X846680Y904717D01*
X847013Y904133D01*
X847097Y903467D01*
X847013Y902800D01*
X846680Y902217D01*
X846180Y901883D01*
X845680Y901800D01*
G01X849863Y905133D02*
Y902800D01*
X850197Y902217D01*
X850697Y901883D01*
X851280Y901800D01*
X851863Y901883D01*
X852363Y902217D01*
X852697Y902800D01*
G01Y901800D02*
Y905133D01*
G01X856880Y906800D02*
Y901800D01*
G01X855713Y905133D02*
X858047D01*
G01X862480D02*
Y901800D01*
G01Y906467D02*
X862313Y906550D01*
Y906717D01*
X862480Y906800D01*
X862647Y906717D01*
Y906550D01*
X862480Y906467D01*
G01X866663Y901800D02*
Y905133D01*
G01Y904300D02*
X866997Y904717D01*
X867497Y905050D01*
X868163Y905133D01*
X868747Y905050D01*
X869247Y904717D01*
X869497Y904133D01*
Y901800D01*
G01X872513Y900550D02*
X873097Y900217D01*
X873763Y900133D01*
X874347Y900217D01*
X874847Y900633D01*
X875180Y901217D01*
Y905133D01*
G01Y904467D02*
X874847Y904800D01*
X874347Y905050D01*
X873763Y905133D01*
X873097Y904967D01*
X872680Y904633D01*
X872347Y904050D01*
X872180Y903467D01*
X872263Y902967D01*
X872597Y902383D01*
X873097Y901967D01*
X873763Y901800D01*
X874263Y901883D01*
X874847Y902217D01*
X875180Y902550D01*
G01X826580Y939300D02*
X1456600D01*
G01X850537Y23480D02*
X851037Y23063D01*
X851620Y22813D01*
X852370Y22730D01*
X853120Y22897D01*
X853703Y23230D01*
X854120Y23813D01*
X854203Y24480D01*
X854037Y25147D01*
X853620Y25563D01*
X853037Y25897D01*
X852453Y25980D01*
X851870Y25897D01*
X851120Y25563D01*
X851370Y27730D01*
X853620D01*
G01X857970Y22563D02*
X857803Y22647D01*
Y22813D01*
X857970Y22897D01*
X858137Y22813D01*
Y22647D01*
X857970Y22563D01*
G01X863570Y22730D02*
Y27730D01*
X862570Y26730D01*
G01Y22730D02*
X864570D01*
G01X873770Y27730D02*
X875770D01*
G01X874770D02*
Y22730D01*
G01X873770D02*
X875770D01*
G01X879870D02*
Y26980D01*
X880037Y27397D01*
X880370Y27647D01*
X880870Y27730D01*
X881370Y27563D01*
X881620Y27147D01*
G01X880620Y25730D02*
X878953D01*
G01X892070Y25230D02*
X893737D01*
Y23730D01*
X893237Y23230D01*
X892653Y22897D01*
X891820Y22730D01*
X890987Y22897D01*
X890403Y23230D01*
X889903Y23730D01*
X889570Y24313D01*
X889403Y24980D01*
Y25563D01*
X889570Y26063D01*
X889903Y26647D01*
X890403Y27147D01*
X890903Y27480D01*
X891570Y27730D01*
X892153D01*
X892820Y27563D01*
X893320Y27230D01*
G01X895920Y24980D02*
X898587D01*
X898337Y25563D01*
X897920Y25897D01*
X897337Y26063D01*
X896753Y25980D01*
X896253Y25730D01*
X895920Y25147D01*
X895753Y24647D01*
Y24147D01*
X895920Y23647D01*
X896337Y23147D01*
X896837Y22813D01*
X897420Y22730D01*
X898003Y22897D01*
X898587Y23397D01*
G01X901603Y22730D02*
Y26063D01*
G01Y25397D02*
X902020Y25730D01*
X902437Y25980D01*
X903020Y26063D01*
X903437Y25980D01*
X903937Y25730D01*
G01X906870Y22730D02*
Y27730D01*
G01Y25230D02*
X907287Y25730D01*
X907787Y25980D01*
X908287Y26063D01*
X909037Y25897D01*
X909537Y25563D01*
X909870Y24980D01*
Y24313D01*
X909703Y23647D01*
X909370Y23147D01*
X908787Y22813D01*
X908287Y22730D01*
X907787Y22813D01*
X907287Y23063D01*
X906870Y23480D01*
G01X912720Y24980D02*
X915387D01*
X915137Y25563D01*
X914720Y25897D01*
X914137Y26063D01*
X913553Y25980D01*
X913053Y25730D01*
X912720Y25147D01*
X912553Y24647D01*
Y24147D01*
X912720Y23647D01*
X913137Y23147D01*
X913637Y22813D01*
X914220Y22730D01*
X914803Y22897D01*
X915387Y23397D01*
G01X918403Y22730D02*
Y26063D01*
G01Y25397D02*
X918820Y25730D01*
X919237Y25980D01*
X919820Y26063D01*
X920237Y25980D01*
X920737Y25730D01*
G01X929353Y22730D02*
Y27730D01*
G01Y25313D02*
X929770Y25730D01*
X930187Y25980D01*
X930853Y26063D01*
X931353Y25980D01*
X931937Y25647D01*
X932187Y25147D01*
Y22730D01*
G01X937870D02*
Y26063D01*
G01Y25480D02*
X937537Y25813D01*
X937037Y25980D01*
X936453Y26063D01*
X935870Y25897D01*
X935370Y25563D01*
X935037Y25063D01*
X934870Y24397D01*
X935037Y23730D01*
X935370Y23230D01*
X935870Y22897D01*
X936453Y22730D01*
X937037Y22813D01*
X937537Y23063D01*
X937870Y23397D01*
G01X940720Y23313D02*
X941137Y22980D01*
X941720Y22730D01*
X942220D01*
X942720Y22897D01*
X943053Y23147D01*
X943220Y23480D01*
X943137Y23980D01*
X942803Y24230D01*
X941303Y24730D01*
X940970Y25313D01*
X941137Y25730D01*
X941470Y25980D01*
X941970Y26063D01*
X942470Y25980D01*
X942970Y25730D01*
G01X953170Y27730D02*
Y22730D01*
G01X952003Y26063D02*
X954337D01*
G01X957353Y22730D02*
Y27730D01*
G01Y25313D02*
X957770Y25730D01*
X958187Y25980D01*
X958853Y26063D01*
X959353Y25980D01*
X959937Y25647D01*
X960187Y25147D01*
Y22730D01*
G01X964370Y26063D02*
Y22730D01*
G01Y27397D02*
X964203Y27480D01*
Y27647D01*
X964370Y27730D01*
X964537Y27647D01*
Y27480D01*
X964370Y27397D01*
G01X968720Y23313D02*
X969137Y22980D01*
X969720Y22730D01*
X970220D01*
X970720Y22897D01*
X971053Y23147D01*
X971220Y23480D01*
X971137Y23980D01*
X970803Y24230D01*
X969303Y24730D01*
X968970Y25313D01*
X969137Y25730D01*
X969470Y25980D01*
X969970Y26063D01*
X970470Y25980D01*
X970970Y25730D01*
G01X979753Y22730D02*
Y27730D01*
G01X982420Y26063D02*
X979753Y24147D01*
G01X980837Y24897D02*
X982587Y22730D01*
G01X986770Y26063D02*
Y22730D01*
G01Y27397D02*
X986603Y27480D01*
Y27647D01*
X986770Y27730D01*
X986937Y27647D01*
Y27480D01*
X986770Y27397D01*
G01X990953Y22730D02*
Y26063D01*
G01Y25230D02*
X991287Y25647D01*
X991787Y25980D01*
X992453Y26063D01*
X993037Y25980D01*
X993537Y25647D01*
X993787Y25063D01*
Y22730D01*
G01X999470Y27730D02*
Y22730D01*
G01Y23480D02*
X999137Y23063D01*
X998637Y22813D01*
X998053Y22730D01*
X997387Y22897D01*
X996887Y23313D01*
X996553Y23813D01*
X996470Y24397D01*
X996553Y24980D01*
X996887Y25480D01*
X997387Y25897D01*
X998053Y26063D01*
X998637Y25980D01*
X999053Y25813D01*
X999470Y25480D01*
G01X1009170Y22730D02*
X1008670Y22813D01*
X1008170Y23147D01*
X1007837Y23730D01*
X1007670Y24397D01*
X1007837Y25063D01*
X1008170Y25647D01*
X1008670Y25980D01*
X1009170Y26063D01*
X1009670Y25980D01*
X1010170Y25647D01*
X1010503Y25063D01*
X1010587Y24397D01*
X1010503Y23730D01*
X1010170Y23147D01*
X1009670Y22813D01*
X1009170Y22730D01*
G01X1014270D02*
Y26980D01*
X1014437Y27397D01*
X1014770Y27647D01*
X1015270Y27730D01*
X1015770Y27563D01*
X1016020Y27147D01*
G01X1015020Y25730D02*
X1013353D01*
G01X1027470Y27730D02*
Y22730D01*
G01Y23480D02*
X1027137Y23063D01*
X1026637Y22813D01*
X1026053Y22730D01*
X1025387Y22897D01*
X1024887Y23313D01*
X1024553Y23813D01*
X1024470Y24397D01*
X1024553Y24980D01*
X1024887Y25480D01*
X1025387Y25897D01*
X1026053Y26063D01*
X1026637Y25980D01*
X1027053Y25813D01*
X1027470Y25480D01*
G01X1030320Y24980D02*
X1032987D01*
X1032737Y25563D01*
X1032320Y25897D01*
X1031737Y26063D01*
X1031153Y25980D01*
X1030653Y25730D01*
X1030320Y25147D01*
X1030153Y24647D01*
Y24147D01*
X1030320Y23647D01*
X1030737Y23147D01*
X1031237Y22813D01*
X1031820Y22730D01*
X1032403Y22897D01*
X1032987Y23397D01*
G01X1035920Y23313D02*
X1036337Y22980D01*
X1036920Y22730D01*
X1037420D01*
X1037920Y22897D01*
X1038253Y23147D01*
X1038420Y23480D01*
X1038337Y23980D01*
X1038003Y24230D01*
X1036503Y24730D01*
X1036170Y25313D01*
X1036337Y25730D01*
X1036670Y25980D01*
X1037170Y26063D01*
X1037670Y25980D01*
X1038170Y25730D01*
G01X1042770Y26063D02*
Y22730D01*
G01Y27397D02*
X1042603Y27480D01*
Y27647D01*
X1042770Y27730D01*
X1042937Y27647D01*
Y27480D01*
X1042770Y27397D01*
G01X1047203Y21480D02*
X1047787Y21147D01*
X1048453Y21063D01*
X1049037Y21147D01*
X1049537Y21563D01*
X1049870Y22147D01*
Y26063D01*
G01Y25397D02*
X1049537Y25730D01*
X1049037Y25980D01*
X1048453Y26063D01*
X1047787Y25897D01*
X1047370Y25563D01*
X1047037Y24980D01*
X1046870Y24397D01*
X1046953Y23897D01*
X1047287Y23313D01*
X1047787Y22897D01*
X1048453Y22730D01*
X1048953Y22813D01*
X1049537Y23147D01*
X1049870Y23480D01*
G01X1052553Y22730D02*
Y26063D01*
G01Y25230D02*
X1052887Y25647D01*
X1053387Y25980D01*
X1054053Y26063D01*
X1054637Y25980D01*
X1055137Y25647D01*
X1055387Y25063D01*
Y22730D01*
G01X1059403Y21813D02*
X1059737Y22897D01*
G01X1069270Y21063D02*
Y26063D01*
G01Y25313D02*
X1069687Y25730D01*
X1070103Y25980D01*
X1070770Y26063D01*
X1071353Y25980D01*
X1071937Y25563D01*
X1072187Y24980D01*
X1072270Y24397D01*
X1072187Y23813D01*
X1071937Y23230D01*
X1071437Y22897D01*
X1070770Y22730D01*
X1070187Y22813D01*
X1069603Y23063D01*
X1069270Y23397D01*
G01X1076370Y22730D02*
Y27730D01*
G01X1080720Y24980D02*
X1083387D01*
X1083137Y25563D01*
X1082720Y25897D01*
X1082137Y26063D01*
X1081553Y25980D01*
X1081053Y25730D01*
X1080720Y25147D01*
X1080553Y24647D01*
Y24147D01*
X1080720Y23647D01*
X1081137Y23147D01*
X1081637Y22813D01*
X1082220Y22730D01*
X1082803Y22897D01*
X1083387Y23397D01*
G01X1089070Y22730D02*
Y26063D01*
G01Y25480D02*
X1088737Y25813D01*
X1088237Y25980D01*
X1087653Y26063D01*
X1087070Y25897D01*
X1086570Y25563D01*
X1086237Y25063D01*
X1086070Y24397D01*
X1086237Y23730D01*
X1086570Y23230D01*
X1087070Y22897D01*
X1087653Y22730D01*
X1088237Y22813D01*
X1088737Y23063D01*
X1089070Y23397D01*
G01X1091920Y23313D02*
X1092337Y22980D01*
X1092920Y22730D01*
X1093420D01*
X1093920Y22897D01*
X1094253Y23147D01*
X1094420Y23480D01*
X1094337Y23980D01*
X1094003Y24230D01*
X1092503Y24730D01*
X1092170Y25313D01*
X1092337Y25730D01*
X1092670Y25980D01*
X1093170Y26063D01*
X1093670Y25980D01*
X1094170Y25730D01*
G01X1097520Y24980D02*
X1100187D01*
X1099937Y25563D01*
X1099520Y25897D01*
X1098937Y26063D01*
X1098353Y25980D01*
X1097853Y25730D01*
X1097520Y25147D01*
X1097353Y24647D01*
Y24147D01*
X1097520Y23647D01*
X1097937Y23147D01*
X1098437Y22813D01*
X1099020Y22730D01*
X1099603Y22897D01*
X1100187Y23397D01*
G01X1109470Y22730D02*
Y26980D01*
X1109637Y27397D01*
X1109970Y27647D01*
X1110470Y27730D01*
X1110970Y27563D01*
X1111220Y27147D01*
G01X1110220Y25730D02*
X1108553D01*
G01X1115570Y22730D02*
X1115070Y22813D01*
X1114570Y23147D01*
X1114237Y23730D01*
X1114070Y24397D01*
X1114237Y25063D01*
X1114570Y25647D01*
X1115070Y25980D01*
X1115570Y26063D01*
X1116070Y25980D01*
X1116570Y25647D01*
X1116903Y25063D01*
X1116987Y24397D01*
X1116903Y23730D01*
X1116570Y23147D01*
X1116070Y22813D01*
X1115570Y22730D01*
G01X1121170D02*
Y27730D01*
G01X1126770Y22730D02*
Y27730D01*
G01X1132370Y22730D02*
X1131870Y22813D01*
X1131370Y23147D01*
X1131037Y23730D01*
X1130870Y24397D01*
X1131037Y25063D01*
X1131370Y25647D01*
X1131870Y25980D01*
X1132370Y26063D01*
X1132870Y25980D01*
X1133370Y25647D01*
X1133703Y25063D01*
X1133787Y24397D01*
X1133703Y23730D01*
X1133370Y23147D01*
X1132870Y22813D01*
X1132370Y22730D01*
G01X1135887Y26063D02*
X1136887Y22730D01*
X1137970Y26063D01*
X1139053Y22730D01*
X1140053Y26063D01*
G01X1143570Y22563D02*
X1143403Y22647D01*
Y22813D01*
X1143570Y22897D01*
X1143737Y22813D01*
Y22647D01*
X1143570Y22563D01*
G01X1153770Y27730D02*
X1155770D01*
G01X1154770D02*
Y22730D01*
G01X1153770D02*
X1155770D01*
G01X1159870D02*
Y26980D01*
X1160037Y27397D01*
X1160370Y27647D01*
X1160870Y27730D01*
X1161370Y27563D01*
X1161620Y27147D01*
G01X1160620Y25730D02*
X1158953D01*
G01X1170153Y22730D02*
Y26063D01*
G01Y25230D02*
X1170487Y25647D01*
X1170987Y25980D01*
X1171653Y26063D01*
X1172237Y25980D01*
X1172737Y25647D01*
X1172987Y25063D01*
Y22730D01*
G01X1177170D02*
X1176670Y22813D01*
X1176170Y23147D01*
X1175837Y23730D01*
X1175670Y24397D01*
X1175837Y25063D01*
X1176170Y25647D01*
X1176670Y25980D01*
X1177170Y26063D01*
X1177670Y25980D01*
X1178170Y25647D01*
X1178503Y25063D01*
X1178587Y24397D01*
X1178503Y23730D01*
X1178170Y23147D01*
X1177670Y22813D01*
X1177170Y22730D01*
G01X1182770Y27730D02*
Y22730D01*
G01X1181603Y26063D02*
X1183937D01*
G01X1188203Y21813D02*
X1188537Y22897D01*
G01X1198070Y21063D02*
Y26063D01*
G01Y25313D02*
X1198487Y25730D01*
X1198903Y25980D01*
X1199570Y26063D01*
X1200153Y25980D01*
X1200737Y25563D01*
X1200987Y24980D01*
X1201070Y24397D01*
X1200987Y23813D01*
X1200737Y23230D01*
X1200237Y22897D01*
X1199570Y22730D01*
X1198987Y22813D01*
X1198403Y23063D01*
X1198070Y23397D01*
G01X1205170Y22730D02*
Y27730D01*
G01X1209520Y24980D02*
X1212187D01*
X1211937Y25563D01*
X1211520Y25897D01*
X1210937Y26063D01*
X1210353Y25980D01*
X1209853Y25730D01*
X1209520Y25147D01*
X1209353Y24647D01*
Y24147D01*
X1209520Y23647D01*
X1209937Y23147D01*
X1210437Y22813D01*
X1211020Y22730D01*
X1211603Y22897D01*
X1212187Y23397D01*
G01X1217870Y22730D02*
Y26063D01*
G01Y25480D02*
X1217537Y25813D01*
X1217037Y25980D01*
X1216453Y26063D01*
X1215870Y25897D01*
X1215370Y25563D01*
X1215037Y25063D01*
X1214870Y24397D01*
X1215037Y23730D01*
X1215370Y23230D01*
X1215870Y22897D01*
X1216453Y22730D01*
X1217037Y22813D01*
X1217537Y23063D01*
X1217870Y23397D01*
G01X1220720Y23313D02*
X1221137Y22980D01*
X1221720Y22730D01*
X1222220D01*
X1222720Y22897D01*
X1223053Y23147D01*
X1223220Y23480D01*
X1223137Y23980D01*
X1222803Y24230D01*
X1221303Y24730D01*
X1220970Y25313D01*
X1221137Y25730D01*
X1221470Y25980D01*
X1221970Y26063D01*
X1222470Y25980D01*
X1222970Y25730D01*
G01X1226320Y24980D02*
X1228987D01*
X1228737Y25563D01*
X1228320Y25897D01*
X1227737Y26063D01*
X1227153Y25980D01*
X1226653Y25730D01*
X1226320Y25147D01*
X1226153Y24647D01*
Y24147D01*
X1226320Y23647D01*
X1226737Y23147D01*
X1227237Y22813D01*
X1227820Y22730D01*
X1228403Y22897D01*
X1228987Y23397D01*
G01X1238770Y26063D02*
Y22730D01*
G01Y27397D02*
X1238603Y27480D01*
Y27647D01*
X1238770Y27730D01*
X1238937Y27647D01*
Y27480D01*
X1238770Y27397D01*
G01X1245870Y21063D02*
Y26063D01*
G01Y25313D02*
X1245453Y25730D01*
X1244953Y25980D01*
X1244370Y26063D01*
X1243870Y25980D01*
X1243287Y25563D01*
X1242953Y24980D01*
X1242870Y24397D01*
X1242953Y23813D01*
X1243287Y23230D01*
X1243870Y22813D01*
X1244370Y22730D01*
X1244953Y22813D01*
X1245453Y23063D01*
X1245870Y23480D01*
G01X1248553Y22730D02*
Y26063D01*
G01Y25230D02*
X1248887Y25647D01*
X1249387Y25980D01*
X1250053Y26063D01*
X1250637Y25980D01*
X1251137Y25647D01*
X1251387Y25063D01*
Y22730D01*
G01X1255570D02*
X1255070Y22813D01*
X1254570Y23147D01*
X1254237Y23730D01*
X1254070Y24397D01*
X1254237Y25063D01*
X1254570Y25647D01*
X1255070Y25980D01*
X1255570Y26063D01*
X1256070Y25980D01*
X1256570Y25647D01*
X1256903Y25063D01*
X1256987Y24397D01*
X1256903Y23730D01*
X1256570Y23147D01*
X1256070Y22813D01*
X1255570Y22730D01*
G01X1260003D02*
Y26063D01*
G01Y25397D02*
X1260420Y25730D01*
X1260837Y25980D01*
X1261420Y26063D01*
X1261837Y25980D01*
X1262337Y25730D01*
G01X1265520Y24980D02*
X1268187D01*
X1267937Y25563D01*
X1267520Y25897D01*
X1266937Y26063D01*
X1266353Y25980D01*
X1265853Y25730D01*
X1265520Y25147D01*
X1265353Y24647D01*
Y24147D01*
X1265520Y23647D01*
X1265937Y23147D01*
X1266437Y22813D01*
X1267020Y22730D01*
X1267603Y22897D01*
X1268187Y23397D01*
G01X1277970Y27730D02*
Y22730D01*
G01X1276803Y26063D02*
X1279137D01*
G01X1282153Y22730D02*
Y27730D01*
G01Y25313D02*
X1282570Y25730D01*
X1282987Y25980D01*
X1283653Y26063D01*
X1284153Y25980D01*
X1284737Y25647D01*
X1284987Y25147D01*
Y22730D01*
G01X1289170Y26063D02*
Y22730D01*
G01Y27397D02*
X1289003Y27480D01*
Y27647D01*
X1289170Y27730D01*
X1289337Y27647D01*
Y27480D01*
X1289170Y27397D01*
G01X1293520Y23313D02*
X1293937Y22980D01*
X1294520Y22730D01*
X1295020D01*
X1295520Y22897D01*
X1295853Y23147D01*
X1296020Y23480D01*
X1295937Y23980D01*
X1295603Y24230D01*
X1294103Y24730D01*
X1293770Y25313D01*
X1293937Y25730D01*
X1294270Y25980D01*
X1294770Y26063D01*
X1295270Y25980D01*
X1295770Y25730D01*
G01X1304803Y22730D02*
Y26063D01*
G01Y25397D02*
X1305220Y25730D01*
X1305637Y25980D01*
X1306220Y26063D01*
X1306637Y25980D01*
X1307137Y25730D01*
G01X1310320Y24980D02*
X1312987D01*
X1312737Y25563D01*
X1312320Y25897D01*
X1311737Y26063D01*
X1311153Y25980D01*
X1310653Y25730D01*
X1310320Y25147D01*
X1310153Y24647D01*
Y24147D01*
X1310320Y23647D01*
X1310737Y23147D01*
X1311237Y22813D01*
X1311820Y22730D01*
X1312403Y22897D01*
X1312987Y23397D01*
G01X1318670Y21063D02*
Y26063D01*
G01Y25313D02*
X1318253Y25730D01*
X1317753Y25980D01*
X1317170Y26063D01*
X1316670Y25980D01*
X1316087Y25563D01*
X1315753Y24980D01*
X1315670Y24397D01*
X1315753Y23813D01*
X1316087Y23230D01*
X1316670Y22813D01*
X1317170Y22730D01*
X1317753Y22813D01*
X1318253Y23063D01*
X1318670Y23480D01*
G01X1321353Y26063D02*
Y23730D01*
X1321687Y23147D01*
X1322187Y22813D01*
X1322770Y22730D01*
X1323353Y22813D01*
X1323853Y23147D01*
X1324187Y23730D01*
G01Y22730D02*
Y26063D01*
G01X1327120Y24980D02*
X1329787D01*
X1329537Y25563D01*
X1329120Y25897D01*
X1328537Y26063D01*
X1327953Y25980D01*
X1327453Y25730D01*
X1327120Y25147D01*
X1326953Y24647D01*
Y24147D01*
X1327120Y23647D01*
X1327537Y23147D01*
X1328037Y22813D01*
X1328620Y22730D01*
X1329203Y22897D01*
X1329787Y23397D01*
G01X1332720Y23313D02*
X1333137Y22980D01*
X1333720Y22730D01*
X1334220D01*
X1334720Y22897D01*
X1335053Y23147D01*
X1335220Y23480D01*
X1335137Y23980D01*
X1334803Y24230D01*
X1333303Y24730D01*
X1332970Y25313D01*
X1333137Y25730D01*
X1333470Y25980D01*
X1333970Y26063D01*
X1334470Y25980D01*
X1334970Y25730D01*
G01X1339570Y27730D02*
Y22730D01*
G01X1338403Y26063D02*
X1340737D01*
G01X1345170Y22563D02*
X1345003Y22647D01*
Y22813D01*
X1345170Y22897D01*
X1345337Y22813D01*
Y22647D01*
X1345170Y22563D01*
G01X890767Y211800D02*
Y216800D01*
X892433D01*
X893100Y216550D01*
X893600Y216217D01*
X894017Y215717D01*
X894350Y215133D01*
X894433Y214300D01*
X894350Y213467D01*
X894017Y212883D01*
X893600Y212383D01*
X893100Y212050D01*
X892433Y211800D01*
X890767D01*
G01X897033D02*
Y215133D01*
G01Y214467D02*
X897450Y214800D01*
X897867Y215050D01*
X898450Y215133D01*
X898867Y215050D01*
X899367Y214800D01*
G01X903800Y215133D02*
Y211800D01*
G01Y216467D02*
X903633Y216550D01*
Y216717D01*
X903800Y216800D01*
X903967Y216717D01*
Y216550D01*
X903800Y216467D01*
G01X909400Y211800D02*
Y216800D01*
G01X915000Y211800D02*
Y216800D01*
G01X924617Y211800D02*
Y216800D01*
X927783D01*
G01X926617Y214383D02*
X924617D01*
G01X930633Y211800D02*
Y215133D01*
G01Y214467D02*
X931050Y214800D01*
X931467Y215050D01*
X932050Y215133D01*
X932467Y215050D01*
X932967Y214800D01*
G01X937400Y211800D02*
X936900Y211883D01*
X936400Y212217D01*
X936067Y212800D01*
X935900Y213467D01*
X936067Y214133D01*
X936400Y214717D01*
X936900Y215050D01*
X937400Y215133D01*
X937900Y215050D01*
X938400Y214717D01*
X938733Y214133D01*
X938817Y213467D01*
X938733Y212800D01*
X938400Y212217D01*
X937900Y211883D01*
X937400Y211800D01*
G01X940500D02*
Y215133D01*
G01Y214217D02*
X940750Y214633D01*
X941167Y214967D01*
X941750Y215133D01*
X942333Y214967D01*
X942750Y214633D01*
X943000Y214217D01*
Y211800D01*
G01Y214217D02*
X943250Y214633D01*
X943667Y214967D01*
X944250Y215133D01*
X944833Y214967D01*
X945250Y214633D01*
X945500Y214133D01*
Y211800D01*
G01X952533Y216800D02*
Y211800D01*
X955867D01*
G01X959800D02*
Y216800D01*
X958800Y215800D01*
G01Y211800D02*
X960800D01*
G01X970583Y210133D02*
X969750Y210967D01*
X969333Y211800D01*
Y215133D01*
X969750Y215967D01*
X970583Y216800D01*
G01X976600D02*
Y211800D01*
G01X974683Y216800D02*
X978517D01*
G01X982200Y211800D02*
X981533Y211883D01*
X980950Y212217D01*
X980450Y212717D01*
X980117Y213300D01*
X979950Y213967D01*
Y214633D01*
X980117Y215300D01*
X980450Y215883D01*
X980950Y216383D01*
X981533Y216717D01*
X982200Y216800D01*
X982867Y216717D01*
X983450Y216383D01*
X983950Y215883D01*
X984283Y215300D01*
X984450Y214633D01*
Y213967D01*
X984283Y213300D01*
X983950Y212717D01*
X983450Y212217D01*
X982867Y211883D01*
X982200Y211800D01*
G01X986133D02*
Y216800D01*
X988133D01*
X988800Y216550D01*
X989300Y215967D01*
X989467Y215300D01*
X989300Y214633D01*
X988883Y214133D01*
X988133Y213883D01*
X986133D01*
G01X993817Y210133D02*
X994650Y210967D01*
X995067Y211800D01*
Y215133D01*
X994650Y215967D01*
X993817Y216800D01*
G01X1004600D02*
Y211800D01*
G01X1003433Y215133D02*
X1005767D01*
G01X1010200Y211800D02*
X1009700Y211883D01*
X1009200Y212217D01*
X1008867Y212800D01*
X1008700Y213467D01*
X1008867Y214133D01*
X1009200Y214717D01*
X1009700Y215050D01*
X1010200Y215133D01*
X1010700Y215050D01*
X1011200Y214717D01*
X1011533Y214133D01*
X1011617Y213467D01*
X1011533Y212800D01*
X1011200Y212217D01*
X1010700Y211883D01*
X1010200Y211800D01*
G01X1019733Y216800D02*
Y211800D01*
X1023067D01*
G01X1025750Y215133D02*
X1028250Y211800D01*
G01Y215133D02*
X1025750Y211800D01*
G01X891183Y193500D02*
Y188500D01*
X894517D01*
G01X897200Y191833D02*
X899700Y188500D01*
G01Y191833D02*
X897200Y188500D01*
G01X904050Y188333D02*
X903883Y188417D01*
Y188583D01*
X904050Y188667D01*
X904217Y188583D01*
Y188417D01*
X904050Y188333D01*
G01Y190583D02*
X903883Y190667D01*
Y190833D01*
X904050Y190917D01*
X904217Y190833D01*
Y190667D01*
X904050Y190583D01*
G01X912750Y188500D02*
Y191833D01*
G01Y190917D02*
X913000Y191333D01*
X913417Y191667D01*
X914000Y191833D01*
X914583Y191667D01*
X915000Y191333D01*
X915250Y190917D01*
Y188500D01*
G01Y190917D02*
X915500Y191333D01*
X915917Y191667D01*
X916500Y191833D01*
X917083Y191667D01*
X917500Y191333D01*
X917750Y190833D01*
Y188500D01*
G01X919433Y191833D02*
Y189500D01*
X919767Y188917D01*
X920267Y188583D01*
X920850Y188500D01*
X921433Y188583D01*
X921933Y188917D01*
X922267Y189500D01*
G01Y188500D02*
Y191833D01*
G01X925200Y189083D02*
X925617Y188750D01*
X926200Y188500D01*
X926700D01*
X927200Y188667D01*
X927533Y188917D01*
X927700Y189250D01*
X927617Y189750D01*
X927283Y190000D01*
X925783Y190500D01*
X925450Y191083D01*
X925617Y191500D01*
X925950Y191750D01*
X926450Y191833D01*
X926950Y191750D01*
X927450Y191500D01*
G01X932050Y193500D02*
Y188500D01*
G01X930883Y191833D02*
X933217D01*
G01X941750Y188500D02*
Y193500D01*
G01Y191000D02*
X942167Y191500D01*
X942667Y191750D01*
X943167Y191833D01*
X943917Y191667D01*
X944417Y191333D01*
X944750Y190750D01*
Y190083D01*
X944583Y189417D01*
X944250Y188917D01*
X943667Y188583D01*
X943167Y188500D01*
X942667Y188583D01*
X942167Y188833D01*
X941750Y189250D01*
G01X947600Y190750D02*
X950267D01*
X950017Y191333D01*
X949600Y191667D01*
X949017Y191833D01*
X948433Y191750D01*
X947933Y191500D01*
X947600Y190917D01*
X947433Y190417D01*
Y189917D01*
X947600Y189417D01*
X948017Y188917D01*
X948517Y188583D01*
X949100Y188500D01*
X949683Y188667D01*
X950267Y189167D01*
G01X958550Y188500D02*
Y193500D01*
G01Y191000D02*
X958967Y191500D01*
X959467Y191750D01*
X959967Y191833D01*
X960717Y191667D01*
X961217Y191333D01*
X961550Y190750D01*
Y190083D01*
X961383Y189417D01*
X961050Y188917D01*
X960467Y188583D01*
X959967Y188500D01*
X959467Y188583D01*
X958967Y188833D01*
X958550Y189250D01*
G01X964483Y188500D02*
Y191833D01*
G01Y191167D02*
X964900Y191500D01*
X965317Y191750D01*
X965900Y191833D01*
X966317Y191750D01*
X966817Y191500D01*
G01X971250Y188500D02*
X970750Y188583D01*
X970250Y188917D01*
X969917Y189500D01*
X969750Y190167D01*
X969917Y190833D01*
X970250Y191417D01*
X970750Y191750D01*
X971250Y191833D01*
X971750Y191750D01*
X972250Y191417D01*
X972583Y190833D01*
X972667Y190167D01*
X972583Y189500D01*
X972250Y188917D01*
X971750Y188583D01*
X971250Y188500D01*
G01X975433D02*
Y193500D01*
G01X978100Y191833D02*
X975433Y189917D01*
G01X976517Y190667D02*
X978267Y188500D01*
G01X981200Y190750D02*
X983867D01*
X983617Y191333D01*
X983200Y191667D01*
X982617Y191833D01*
X982033Y191750D01*
X981533Y191500D01*
X981200Y190917D01*
X981033Y190417D01*
Y189917D01*
X981200Y189417D01*
X981617Y188917D01*
X982117Y188583D01*
X982700Y188500D01*
X983283Y188667D01*
X983867Y189167D01*
G01X986633Y188500D02*
Y191833D01*
G01Y191000D02*
X986967Y191417D01*
X987467Y191750D01*
X988133Y191833D01*
X988717Y191750D01*
X989217Y191417D01*
X989467Y190833D01*
Y188500D01*
G01X999250D02*
Y193500D01*
G01X1006350Y188500D02*
Y191833D01*
G01Y191250D02*
X1006017Y191583D01*
X1005517Y191750D01*
X1004933Y191833D01*
X1004350Y191667D01*
X1003850Y191333D01*
X1003517Y190833D01*
X1003350Y190167D01*
X1003517Y189500D01*
X1003850Y189000D01*
X1004350Y188667D01*
X1004933Y188500D01*
X1005517Y188583D01*
X1006017Y188833D01*
X1006350Y189167D01*
G01X1008700Y187000D02*
X1009200Y186833D01*
X1009867Y187000D01*
X1010283Y187333D01*
X1010617Y187750D01*
X1011117Y189083D01*
X1012200Y191833D01*
G01X1009533D02*
X1011117Y189083D01*
G01X1014800Y190750D02*
X1017467D01*
X1017217Y191333D01*
X1016800Y191667D01*
X1016217Y191833D01*
X1015633Y191750D01*
X1015133Y191500D01*
X1014800Y190917D01*
X1014633Y190417D01*
Y189917D01*
X1014800Y189417D01*
X1015217Y188917D01*
X1015717Y188583D01*
X1016300Y188500D01*
X1016883Y188667D01*
X1017467Y189167D01*
G01X1020483Y188500D02*
Y191833D01*
G01Y191167D02*
X1020900Y191500D01*
X1021317Y191750D01*
X1021900Y191833D01*
X1022317Y191750D01*
X1022817Y191500D01*
G01X890583Y205110D02*
Y200110D01*
X893917D01*
G01X896433D02*
Y203443D01*
G01Y202610D02*
X896767Y203027D01*
X897267Y203360D01*
X897933Y203443D01*
X898517Y203360D01*
X899017Y203027D01*
X899267Y202443D01*
Y200110D01*
G01X903450Y199943D02*
X903283Y200027D01*
Y200193D01*
X903450Y200277D01*
X903617Y200193D01*
Y200027D01*
X903450Y199943D01*
G01Y202193D02*
X903283Y202277D01*
Y202443D01*
X903450Y202527D01*
X903617Y202443D01*
Y202277D01*
X903450Y202193D01*
G01X915983Y203027D02*
X915400Y203360D01*
X914900Y203443D01*
X914233Y203277D01*
X913733Y202943D01*
X913400Y202360D01*
X913317Y201777D01*
X913400Y201193D01*
X913733Y200693D01*
X914233Y200277D01*
X914900Y200110D01*
X915483Y200277D01*
X915983Y200610D01*
G01X921750Y200110D02*
Y203443D01*
G01Y202860D02*
X921417Y203193D01*
X920917Y203360D01*
X920333Y203443D01*
X919750Y203277D01*
X919250Y202943D01*
X918917Y202443D01*
X918750Y201777D01*
X918917Y201110D01*
X919250Y200610D01*
X919750Y200277D01*
X920333Y200110D01*
X920917Y200193D01*
X921417Y200443D01*
X921750Y200777D01*
G01X924433Y200110D02*
Y203443D01*
G01Y202610D02*
X924767Y203027D01*
X925267Y203360D01*
X925933Y203443D01*
X926517Y203360D01*
X927017Y203027D01*
X927267Y202443D01*
Y200110D01*
G01X931450Y203443D02*
X932283Y204485D01*
Y205110D01*
X931658D01*
Y204485D01*
X932283D01*
G01X937050Y205110D02*
Y200110D01*
G01X935883Y203443D02*
X938217D01*
G01X946750Y200110D02*
Y205110D01*
G01Y202610D02*
X947167Y203110D01*
X947667Y203360D01*
X948167Y203443D01*
X948917Y203277D01*
X949417Y202943D01*
X949750Y202360D01*
Y201693D01*
X949583Y201027D01*
X949250Y200527D01*
X948667Y200193D01*
X948167Y200110D01*
X947667Y200193D01*
X947167Y200443D01*
X946750Y200860D01*
G01X952600Y202360D02*
X955267D01*
X955017Y202943D01*
X954600Y203277D01*
X954017Y203443D01*
X953433Y203360D01*
X952933Y203110D01*
X952600Y202527D01*
X952433Y202027D01*
Y201527D01*
X952600Y201027D01*
X953017Y200527D01*
X953517Y200193D01*
X954100Y200110D01*
X954683Y200277D01*
X955267Y200777D01*
G01X963550Y200110D02*
Y205110D01*
G01Y202610D02*
X963967Y203110D01*
X964467Y203360D01*
X964967Y203443D01*
X965717Y203277D01*
X966217Y202943D01*
X966550Y202360D01*
Y201693D01*
X966383Y201027D01*
X966050Y200527D01*
X965467Y200193D01*
X964967Y200110D01*
X964467Y200193D01*
X963967Y200443D01*
X963550Y200860D01*
G01X969483Y200110D02*
Y203443D01*
G01Y202777D02*
X969900Y203110D01*
X970317Y203360D01*
X970900Y203443D01*
X971317Y203360D01*
X971817Y203110D01*
G01X976250Y200110D02*
X975750Y200193D01*
X975250Y200527D01*
X974917Y201110D01*
X974750Y201777D01*
X974917Y202443D01*
X975250Y203027D01*
X975750Y203360D01*
X976250Y203443D01*
X976750Y203360D01*
X977250Y203027D01*
X977583Y202443D01*
X977667Y201777D01*
X977583Y201110D01*
X977250Y200527D01*
X976750Y200193D01*
X976250Y200110D01*
G01X980433D02*
Y205110D01*
G01X983100Y203443D02*
X980433Y201527D01*
G01X981517Y202277D02*
X983267Y200110D01*
G01X986200Y202360D02*
X988867D01*
X988617Y202943D01*
X988200Y203277D01*
X987617Y203443D01*
X987033Y203360D01*
X986533Y203110D01*
X986200Y202527D01*
X986033Y202027D01*
Y201527D01*
X986200Y201027D01*
X986617Y200527D01*
X987117Y200193D01*
X987700Y200110D01*
X988283Y200277D01*
X988867Y200777D01*
G01X991633Y200110D02*
Y203443D01*
G01Y202610D02*
X991967Y203027D01*
X992467Y203360D01*
X993133Y203443D01*
X993717Y203360D01*
X994217Y203027D01*
X994467Y202443D01*
Y200110D01*
G01X1004250D02*
Y205110D01*
G01X1011350Y200110D02*
Y203443D01*
G01Y202860D02*
X1011017Y203193D01*
X1010517Y203360D01*
X1009933Y203443D01*
X1009350Y203277D01*
X1008850Y202943D01*
X1008517Y202443D01*
X1008350Y201777D01*
X1008517Y201110D01*
X1008850Y200610D01*
X1009350Y200277D01*
X1009933Y200110D01*
X1010517Y200193D01*
X1011017Y200443D01*
X1011350Y200777D01*
G01X1013700Y198610D02*
X1014200Y198443D01*
X1014867Y198610D01*
X1015283Y198943D01*
X1015617Y199360D01*
X1016117Y200693D01*
X1017200Y203443D01*
G01X1014533D02*
X1016117Y200693D01*
G01X1019800Y202360D02*
X1022467D01*
X1022217Y202943D01*
X1021800Y203277D01*
X1021217Y203443D01*
X1020633Y203360D01*
X1020133Y203110D01*
X1019800Y202527D01*
X1019633Y202027D01*
Y201527D01*
X1019800Y201027D01*
X1020217Y200527D01*
X1020717Y200193D01*
X1021300Y200110D01*
X1021883Y200277D01*
X1022467Y200777D01*
G01X1025483Y200110D02*
Y203443D01*
G01Y202777D02*
X1025900Y203110D01*
X1026317Y203360D01*
X1026900Y203443D01*
X1027317Y203360D01*
X1027817Y203110D01*
G01X915767Y73300D02*
Y78300D01*
X917433D01*
X918100Y78050D01*
X918600Y77717D01*
X919017Y77217D01*
X919350Y76633D01*
X919433Y75800D01*
X919350Y74967D01*
X919017Y74383D01*
X918600Y73883D01*
X918100Y73550D01*
X917433Y73300D01*
X915767D01*
G01X923200D02*
Y78300D01*
X922200Y77300D01*
G01Y73300D02*
X924200D01*
G01X927217Y75383D02*
X927800Y75967D01*
X928300Y76300D01*
X928967Y76467D01*
X929550Y76300D01*
X929967Y75967D01*
X930300Y75467D01*
X930383Y74883D01*
X930300Y74383D01*
X929967Y73883D01*
X929467Y73467D01*
X928883Y73300D01*
X928217Y73467D01*
X927633Y73967D01*
X927300Y74717D01*
X927217Y75550D01*
X927383Y76633D01*
X927633Y77217D01*
X928050Y77800D01*
X928633Y78217D01*
X929217Y78300D01*
X929800Y78133D01*
X930217Y77717D01*
G01X941267Y239300D02*
Y244300D01*
X942933D01*
X943600Y244050D01*
X944100Y243717D01*
X944517Y243217D01*
X944850Y242633D01*
X944933Y241800D01*
X944850Y240967D01*
X944517Y240383D01*
X944100Y239883D01*
X943600Y239550D01*
X942933Y239300D01*
X941267D01*
G01X948700D02*
Y244300D01*
X947700Y243300D01*
G01Y239300D02*
X949700D01*
G01X939267Y403300D02*
Y408300D01*
X940933D01*
X941600Y408050D01*
X942100Y407717D01*
X942517Y407217D01*
X942850Y406633D01*
X942933Y405800D01*
X942850Y404967D01*
X942517Y404383D01*
X942100Y403883D01*
X941600Y403550D01*
X940933Y403300D01*
X939267D01*
G01X945117Y407467D02*
X945617Y407967D01*
X946200Y408217D01*
X946867Y408300D01*
X947700Y408133D01*
X948283Y407717D01*
X948450Y407217D01*
X948367Y406717D01*
X948033Y406300D01*
X946367Y405467D01*
X945617Y404883D01*
X945117Y404050D01*
X944950Y403300D01*
X948450D01*
G01X935190Y465250D02*
Y468583D01*
G01Y468000D02*
X934857Y468333D01*
X934357Y468500D01*
X933773Y468583D01*
X933190Y468417D01*
X932690Y468083D01*
X932357Y467583D01*
X932190Y466917D01*
X932357Y466250D01*
X932690Y465750D01*
X933190Y465417D01*
X933773Y465250D01*
X934357Y465333D01*
X934857Y465583D01*
X935190Y465917D01*
G01X937873Y465250D02*
Y468583D01*
G01Y467750D02*
X938207Y468167D01*
X938707Y468500D01*
X939373Y468583D01*
X939957Y468500D01*
X940457Y468167D01*
X940707Y467583D01*
Y465250D01*
G01X946390Y470250D02*
Y465250D01*
G01Y466000D02*
X946057Y465583D01*
X945557Y465333D01*
X944973Y465250D01*
X944307Y465417D01*
X943807Y465833D01*
X943473Y466333D01*
X943390Y466917D01*
X943473Y467500D01*
X943807Y468000D01*
X944307Y468417D01*
X944973Y468583D01*
X945557Y468500D01*
X945973Y468333D01*
X946390Y468000D01*
G01X957423Y468167D02*
X956840Y468500D01*
X956340Y468583D01*
X955673Y468417D01*
X955173Y468083D01*
X954840Y467500D01*
X954757Y466917D01*
X954840Y466333D01*
X955173Y465833D01*
X955673Y465417D01*
X956340Y465250D01*
X956923Y465417D01*
X957423Y465750D01*
G01X961690Y465250D02*
X961190Y465333D01*
X960690Y465667D01*
X960357Y466250D01*
X960190Y466917D01*
X960357Y467583D01*
X960690Y468167D01*
X961190Y468500D01*
X961690Y468583D01*
X962190Y468500D01*
X962690Y468167D01*
X963023Y467583D01*
X963107Y466917D01*
X963023Y466250D01*
X962690Y465667D01*
X962190Y465333D01*
X961690Y465250D01*
G01X965790Y468583D02*
X967290Y465250D01*
X968790Y468583D01*
G01X971640Y467500D02*
X974307D01*
X974057Y468083D01*
X973640Y468417D01*
X973057Y468583D01*
X972473Y468500D01*
X971973Y468250D01*
X971640Y467667D01*
X971473Y467167D01*
Y466667D01*
X971640Y466167D01*
X972057Y465667D01*
X972557Y465333D01*
X973140Y465250D01*
X973723Y465417D01*
X974307Y465917D01*
G01X977323Y465250D02*
Y468583D01*
G01Y467917D02*
X977740Y468250D01*
X978157Y468500D01*
X978740Y468583D01*
X979157Y468500D01*
X979657Y468250D01*
G01X982840Y467500D02*
X985507D01*
X985257Y468083D01*
X984840Y468417D01*
X984257Y468583D01*
X983673Y468500D01*
X983173Y468250D01*
X982840Y467667D01*
X982673Y467167D01*
Y466667D01*
X982840Y466167D01*
X983257Y465667D01*
X983757Y465333D01*
X984340Y465250D01*
X984923Y465417D01*
X985507Y465917D01*
G01X991190Y470250D02*
Y465250D01*
G01Y466000D02*
X990857Y465583D01*
X990357Y465333D01*
X989773Y465250D01*
X989107Y465417D01*
X988607Y465833D01*
X988273Y466333D01*
X988190Y466917D01*
X988273Y467500D01*
X988607Y468000D01*
X989107Y468417D01*
X989773Y468583D01*
X990357Y468500D01*
X990773Y468333D01*
X991190Y468000D01*
G01X998807Y468583D02*
X999807Y465250D01*
X1000890Y468583D01*
X1001973Y465250D01*
X1002973Y468583D01*
G01X1006490D02*
Y465250D01*
G01Y469917D02*
X1006323Y470000D01*
Y470167D01*
X1006490Y470250D01*
X1006657Y470167D01*
Y470000D01*
X1006490Y469917D01*
G01X1012090Y470250D02*
Y465250D01*
G01X1010923Y468583D02*
X1013257D01*
G01X1016273Y465250D02*
Y470250D01*
G01Y467833D02*
X1016690Y468250D01*
X1017107Y468500D01*
X1017773Y468583D01*
X1018273Y468500D01*
X1018857Y468167D01*
X1019107Y467667D01*
Y465250D01*
G01X1030223Y468167D02*
X1029640Y468500D01*
X1029140Y468583D01*
X1028473Y468417D01*
X1027973Y468083D01*
X1027640Y467500D01*
X1027557Y466917D01*
X1027640Y466333D01*
X1027973Y465833D01*
X1028473Y465417D01*
X1029140Y465250D01*
X1029723Y465417D01*
X1030223Y465750D01*
G01X1034490Y465250D02*
X1033990Y465333D01*
X1033490Y465667D01*
X1033157Y466250D01*
X1032990Y466917D01*
X1033157Y467583D01*
X1033490Y468167D01*
X1033990Y468500D01*
X1034490Y468583D01*
X1034990Y468500D01*
X1035490Y468167D01*
X1035823Y467583D01*
X1035907Y466917D01*
X1035823Y466250D01*
X1035490Y465667D01*
X1034990Y465333D01*
X1034490Y465250D01*
G01X1038590Y463583D02*
Y468583D01*
G01Y467833D02*
X1039007Y468250D01*
X1039423Y468500D01*
X1040090Y468583D01*
X1040673Y468500D01*
X1041257Y468083D01*
X1041507Y467500D01*
X1041590Y466917D01*
X1041507Y466333D01*
X1041257Y465750D01*
X1040757Y465417D01*
X1040090Y465250D01*
X1039507Y465333D01*
X1038923Y465583D01*
X1038590Y465917D01*
G01X1044190Y463583D02*
Y468583D01*
G01Y467833D02*
X1044607Y468250D01*
X1045023Y468500D01*
X1045690Y468583D01*
X1046273Y468500D01*
X1046857Y468083D01*
X1047107Y467500D01*
X1047190Y466917D01*
X1047107Y466333D01*
X1046857Y465750D01*
X1046357Y465417D01*
X1045690Y465250D01*
X1045107Y465333D01*
X1044523Y465583D01*
X1044190Y465917D01*
G01X1050040Y467500D02*
X1052707D01*
X1052457Y468083D01*
X1052040Y468417D01*
X1051457Y468583D01*
X1050873Y468500D01*
X1050373Y468250D01*
X1050040Y467667D01*
X1049873Y467167D01*
Y466667D01*
X1050040Y466167D01*
X1050457Y465667D01*
X1050957Y465333D01*
X1051540Y465250D01*
X1052123Y465417D01*
X1052707Y465917D01*
G01X1055723Y465250D02*
Y468583D01*
G01Y467917D02*
X1056140Y468250D01*
X1056557Y468500D01*
X1057140Y468583D01*
X1057557Y468500D01*
X1058057Y468250D01*
G01X933190Y478610D02*
Y482860D01*
X933357Y483277D01*
X933690Y483527D01*
X934190Y483610D01*
X934690Y483443D01*
X934940Y483027D01*
G01X933940Y481610D02*
X932273D01*
G01X939290Y478610D02*
X938790Y478693D01*
X938290Y479027D01*
X937957Y479610D01*
X937790Y480277D01*
X937957Y480943D01*
X938290Y481527D01*
X938790Y481860D01*
X939290Y481943D01*
X939790Y481860D01*
X940290Y481527D01*
X940623Y480943D01*
X940707Y480277D01*
X940623Y479610D01*
X940290Y479027D01*
X939790Y478693D01*
X939290Y478610D01*
G01X944890D02*
Y483610D01*
G01X950490Y478610D02*
Y483610D01*
G01X956090Y478610D02*
X955590Y478693D01*
X955090Y479027D01*
X954757Y479610D01*
X954590Y480277D01*
X954757Y480943D01*
X955090Y481527D01*
X955590Y481860D01*
X956090Y481943D01*
X956590Y481860D01*
X957090Y481527D01*
X957423Y480943D01*
X957507Y480277D01*
X957423Y479610D01*
X957090Y479027D01*
X956590Y478693D01*
X956090Y478610D01*
G01X959607Y481943D02*
X960607Y478610D01*
X961690Y481943D01*
X962773Y478610D01*
X963773Y481943D01*
G01X973390Y481110D02*
X975057D01*
Y479610D01*
X974557Y479110D01*
X973973Y478777D01*
X973140Y478610D01*
X972307Y478777D01*
X971723Y479110D01*
X971223Y479610D01*
X970890Y480193D01*
X970723Y480860D01*
Y481443D01*
X970890Y481943D01*
X971223Y482527D01*
X971723Y483027D01*
X972223Y483360D01*
X972890Y483610D01*
X973473D01*
X974140Y483443D01*
X974640Y483110D01*
G01X977240Y480860D02*
X979907D01*
X979657Y481443D01*
X979240Y481777D01*
X978657Y481943D01*
X978073Y481860D01*
X977573Y481610D01*
X977240Y481027D01*
X977073Y480527D01*
Y480027D01*
X977240Y479527D01*
X977657Y479027D01*
X978157Y478693D01*
X978740Y478610D01*
X979323Y478777D01*
X979907Y479277D01*
G01X982923Y478610D02*
Y481943D01*
G01Y481277D02*
X983340Y481610D01*
X983757Y481860D01*
X984340Y481943D01*
X984757Y481860D01*
X985257Y481610D01*
G01X988190Y478610D02*
Y483610D01*
G01Y481110D02*
X988607Y481610D01*
X989107Y481860D01*
X989607Y481943D01*
X990357Y481777D01*
X990857Y481443D01*
X991190Y480860D01*
Y480193D01*
X991023Y479527D01*
X990690Y479027D01*
X990107Y478693D01*
X989607Y478610D01*
X989107Y478693D01*
X988607Y478943D01*
X988190Y479360D01*
G01X994040Y480860D02*
X996707D01*
X996457Y481443D01*
X996040Y481777D01*
X995457Y481943D01*
X994873Y481860D01*
X994373Y481610D01*
X994040Y481027D01*
X993873Y480527D01*
Y480027D01*
X994040Y479527D01*
X994457Y479027D01*
X994957Y478693D01*
X995540Y478610D01*
X996123Y478777D01*
X996707Y479277D01*
G01X999723Y478610D02*
Y481943D01*
G01Y481277D02*
X1000140Y481610D01*
X1000557Y481860D01*
X1001140Y481943D01*
X1001557Y481860D01*
X1002057Y481610D01*
G01X1013590Y478610D02*
Y481943D01*
G01Y481360D02*
X1013257Y481693D01*
X1012757Y481860D01*
X1012173Y481943D01*
X1011590Y481777D01*
X1011090Y481443D01*
X1010757Y480943D01*
X1010590Y480277D01*
X1010757Y479610D01*
X1011090Y479110D01*
X1011590Y478777D01*
X1012173Y478610D01*
X1012757Y478693D01*
X1013257Y478943D01*
X1013590Y479277D01*
G01X1016273Y478610D02*
Y481943D01*
G01Y481110D02*
X1016607Y481527D01*
X1017107Y481860D01*
X1017773Y481943D01*
X1018357Y481860D01*
X1018857Y481527D01*
X1019107Y480943D01*
Y478610D01*
G01X1024790Y483610D02*
Y478610D01*
G01Y479360D02*
X1024457Y478943D01*
X1023957Y478693D01*
X1023373Y478610D01*
X1022707Y478777D01*
X1022207Y479193D01*
X1021873Y479693D01*
X1021790Y480277D01*
X1021873Y480860D01*
X1022207Y481360D01*
X1022707Y481777D01*
X1023373Y481943D01*
X1023957Y481860D01*
X1024373Y481693D01*
X1024790Y481360D01*
G01X1032990Y476943D02*
Y481943D01*
G01Y481193D02*
X1033407Y481610D01*
X1033823Y481860D01*
X1034490Y481943D01*
X1035073Y481860D01*
X1035657Y481443D01*
X1035907Y480860D01*
X1035990Y480277D01*
X1035907Y479693D01*
X1035657Y479110D01*
X1035157Y478777D01*
X1034490Y478610D01*
X1033907Y478693D01*
X1033323Y478943D01*
X1032990Y479277D01*
G01X1040090Y478610D02*
Y483610D01*
G01X1044273Y481943D02*
Y479610D01*
X1044607Y479027D01*
X1045107Y478693D01*
X1045690Y478610D01*
X1046273Y478693D01*
X1046773Y479027D01*
X1047107Y479610D01*
G01Y478610D02*
Y481943D01*
G01X1050123Y477360D02*
X1050707Y477027D01*
X1051373Y476943D01*
X1051957Y477027D01*
X1052457Y477443D01*
X1052790Y478027D01*
Y481943D01*
G01Y481277D02*
X1052457Y481610D01*
X1051957Y481860D01*
X1051373Y481943D01*
X1050707Y481777D01*
X1050290Y481443D01*
X1049957Y480860D01*
X1049790Y480277D01*
X1049873Y479777D01*
X1050207Y479193D01*
X1050707Y478777D01*
X1051373Y478610D01*
X1051873Y478693D01*
X1052457Y479027D01*
X1052790Y479360D01*
G01X1060407Y481943D02*
X1061407Y478610D01*
X1062490Y481943D01*
X1063573Y478610D01*
X1064573Y481943D01*
G01X1068090D02*
Y478610D01*
G01Y483277D02*
X1067923Y483360D01*
Y483527D01*
X1068090Y483610D01*
X1068257Y483527D01*
Y483360D01*
X1068090Y483277D01*
G01X1073690Y483610D02*
Y478610D01*
G01X1072523Y481943D02*
X1074857D01*
G01X1077873Y478610D02*
Y483610D01*
G01Y481193D02*
X1078290Y481610D01*
X1078707Y481860D01*
X1079373Y481943D01*
X1079873Y481860D01*
X1080457Y481527D01*
X1080707Y481027D01*
Y478610D01*
G01X1089323D02*
Y481943D01*
G01Y481277D02*
X1089740Y481610D01*
X1090157Y481860D01*
X1090740Y481943D01*
X1091157Y481860D01*
X1091657Y481610D01*
G01X1094840Y480860D02*
X1097507D01*
X1097257Y481443D01*
X1096840Y481777D01*
X1096257Y481943D01*
X1095673Y481860D01*
X1095173Y481610D01*
X1094840Y481027D01*
X1094673Y480527D01*
Y480027D01*
X1094840Y479527D01*
X1095257Y479027D01*
X1095757Y478693D01*
X1096340Y478610D01*
X1096923Y478777D01*
X1097507Y479277D01*
G01X1100440Y479193D02*
X1100857Y478860D01*
X1101440Y478610D01*
X1101940D01*
X1102440Y478777D01*
X1102773Y479027D01*
X1102940Y479360D01*
X1102857Y479860D01*
X1102523Y480110D01*
X1101023Y480610D01*
X1100690Y481193D01*
X1100857Y481610D01*
X1101190Y481860D01*
X1101690Y481943D01*
X1102190Y481860D01*
X1102690Y481610D01*
G01X1107290Y481943D02*
Y478610D01*
G01Y483277D02*
X1107123Y483360D01*
Y483527D01*
X1107290Y483610D01*
X1107457Y483527D01*
Y483360D01*
X1107290Y483277D01*
G01X1111473Y478610D02*
Y481943D01*
G01Y481110D02*
X1111807Y481527D01*
X1112307Y481860D01*
X1112973Y481943D01*
X1113557Y481860D01*
X1114057Y481527D01*
X1114307Y480943D01*
Y478610D01*
G01X925600Y693300D02*
Y454800D01*
G01X937100Y544300D02*
Y547633D01*
G01Y547050D02*
X936767Y547383D01*
X936267Y547550D01*
X935683Y547633D01*
X935100Y547467D01*
X934600Y547133D01*
X934267Y546633D01*
X934100Y545967D01*
X934267Y545300D01*
X934600Y544800D01*
X935100Y544467D01*
X935683Y544300D01*
X936267Y544383D01*
X936767Y544633D01*
X937100Y544967D01*
G01X939783Y544300D02*
Y547633D01*
G01Y546800D02*
X940117Y547217D01*
X940617Y547550D01*
X941283Y547633D01*
X941867Y547550D01*
X942367Y547217D01*
X942617Y546633D01*
Y544300D01*
G01X948300Y549300D02*
Y544300D01*
G01Y545050D02*
X947967Y544633D01*
X947467Y544383D01*
X946883Y544300D01*
X946217Y544467D01*
X945717Y544883D01*
X945383Y545383D01*
X945300Y545967D01*
X945383Y546550D01*
X945717Y547050D01*
X946217Y547467D01*
X946883Y547633D01*
X947467Y547550D01*
X947883Y547383D01*
X948300Y547050D01*
G01X956500Y544300D02*
Y549300D01*
G01Y546800D02*
X956917Y547300D01*
X957417Y547550D01*
X957917Y547633D01*
X958667Y547467D01*
X959167Y547133D01*
X959500Y546550D01*
Y545883D01*
X959333Y545217D01*
X959000Y544717D01*
X958417Y544383D01*
X957917Y544300D01*
X957417Y544383D01*
X956917Y544633D01*
X956500Y545050D01*
G01X963600Y544300D02*
X963100Y544383D01*
X962600Y544717D01*
X962267Y545300D01*
X962100Y545967D01*
X962267Y546633D01*
X962600Y547217D01*
X963100Y547550D01*
X963600Y547633D01*
X964100Y547550D01*
X964600Y547217D01*
X964933Y546633D01*
X965017Y545967D01*
X964933Y545300D01*
X964600Y544717D01*
X964100Y544383D01*
X963600Y544300D01*
G01X969200Y549300D02*
Y544300D01*
G01X968033Y547633D02*
X970367D01*
G01X974800Y549300D02*
Y544300D01*
G01X973633Y547633D02*
X975967D01*
G01X980400Y544300D02*
X979900Y544383D01*
X979400Y544717D01*
X979067Y545300D01*
X978900Y545967D01*
X979067Y546633D01*
X979400Y547217D01*
X979900Y547550D01*
X980400Y547633D01*
X980900Y547550D01*
X981400Y547217D01*
X981733Y546633D01*
X981817Y545967D01*
X981733Y545300D01*
X981400Y544717D01*
X980900Y544383D01*
X980400Y544300D01*
G01X983500D02*
Y547633D01*
G01Y546717D02*
X983750Y547133D01*
X984167Y547467D01*
X984750Y547633D01*
X985333Y547467D01*
X985750Y547133D01*
X986000Y546717D01*
Y544300D01*
G01Y546717D02*
X986250Y547133D01*
X986667Y547467D01*
X987250Y547633D01*
X987833Y547467D01*
X988250Y547133D01*
X988500Y546633D01*
Y544300D01*
G01X995950Y544883D02*
X996367Y544550D01*
X996950Y544300D01*
X997450D01*
X997950Y544467D01*
X998283Y544717D01*
X998450Y545050D01*
X998367Y545550D01*
X998033Y545800D01*
X996533Y546300D01*
X996200Y546883D01*
X996367Y547300D01*
X996700Y547550D01*
X997200Y547633D01*
X997700Y547550D01*
X998200Y547300D01*
G01X1002800Y547633D02*
Y544300D01*
G01Y548967D02*
X1002633Y549050D01*
Y549217D01*
X1002800Y549300D01*
X1002967Y549217D01*
Y549050D01*
X1002800Y548967D01*
G01X1009900Y549300D02*
Y544300D01*
G01Y545050D02*
X1009567Y544633D01*
X1009067Y544383D01*
X1008483Y544300D01*
X1007817Y544467D01*
X1007317Y544883D01*
X1006983Y545383D01*
X1006900Y545967D01*
X1006983Y546550D01*
X1007317Y547050D01*
X1007817Y547467D01*
X1008483Y547633D01*
X1009067Y547550D01*
X1009483Y547383D01*
X1009900Y547050D01*
G01X1012750Y546550D02*
X1015417D01*
X1015167Y547133D01*
X1014750Y547467D01*
X1014167Y547633D01*
X1013583Y547550D01*
X1013083Y547300D01*
X1012750Y546717D01*
X1012583Y546217D01*
Y545717D01*
X1012750Y545217D01*
X1013167Y544717D01*
X1013667Y544383D01*
X1014250Y544300D01*
X1014833Y544467D01*
X1015417Y544967D01*
G01X935100Y529300D02*
Y533550D01*
X935267Y533967D01*
X935600Y534217D01*
X936100Y534300D01*
X936600Y534133D01*
X936850Y533717D01*
G01X935850Y532300D02*
X934183D01*
G01X941200Y529300D02*
X940700Y529383D01*
X940200Y529717D01*
X939867Y530300D01*
X939700Y530967D01*
X939867Y531633D01*
X940200Y532217D01*
X940700Y532550D01*
X941200Y532633D01*
X941700Y532550D01*
X942200Y532217D01*
X942533Y531633D01*
X942617Y530967D01*
X942533Y530300D01*
X942200Y529717D01*
X941700Y529383D01*
X941200Y529300D01*
G01X946800D02*
Y534300D01*
G01X952400Y529300D02*
Y534300D01*
G01X958000Y529300D02*
X957500Y529383D01*
X957000Y529717D01*
X956667Y530300D01*
X956500Y530967D01*
X956667Y531633D01*
X957000Y532217D01*
X957500Y532550D01*
X958000Y532633D01*
X958500Y532550D01*
X959000Y532217D01*
X959333Y531633D01*
X959417Y530967D01*
X959333Y530300D01*
X959000Y529717D01*
X958500Y529383D01*
X958000Y529300D01*
G01X961517Y532633D02*
X962517Y529300D01*
X963600Y532633D01*
X964683Y529300D01*
X965683Y532633D01*
G01X975300Y531800D02*
X976967D01*
Y530300D01*
X976467Y529800D01*
X975883Y529467D01*
X975050Y529300D01*
X974217Y529467D01*
X973633Y529800D01*
X973133Y530300D01*
X972800Y530883D01*
X972633Y531550D01*
Y532133D01*
X972800Y532633D01*
X973133Y533217D01*
X973633Y533717D01*
X974133Y534050D01*
X974800Y534300D01*
X975383D01*
X976050Y534133D01*
X976550Y533800D01*
G01X979150Y531550D02*
X981817D01*
X981567Y532133D01*
X981150Y532467D01*
X980567Y532633D01*
X979983Y532550D01*
X979483Y532300D01*
X979150Y531717D01*
X978983Y531217D01*
Y530717D01*
X979150Y530217D01*
X979567Y529717D01*
X980067Y529383D01*
X980650Y529300D01*
X981233Y529467D01*
X981817Y529967D01*
G01X984833Y529300D02*
Y532633D01*
G01Y531967D02*
X985250Y532300D01*
X985667Y532550D01*
X986250Y532633D01*
X986667Y532550D01*
X987167Y532300D01*
G01X990100Y529300D02*
Y534300D01*
G01Y531800D02*
X990517Y532300D01*
X991017Y532550D01*
X991517Y532633D01*
X992267Y532467D01*
X992767Y532133D01*
X993100Y531550D01*
Y530883D01*
X992933Y530217D01*
X992600Y529717D01*
X992017Y529383D01*
X991517Y529300D01*
X991017Y529383D01*
X990517Y529633D01*
X990100Y530050D01*
G01X995950Y531550D02*
X998617D01*
X998367Y532133D01*
X997950Y532467D01*
X997367Y532633D01*
X996783Y532550D01*
X996283Y532300D01*
X995950Y531717D01*
X995783Y531217D01*
Y530717D01*
X995950Y530217D01*
X996367Y529717D01*
X996867Y529383D01*
X997450Y529300D01*
X998033Y529467D01*
X998617Y529967D01*
G01X1001633Y529300D02*
Y532633D01*
G01Y531967D02*
X1002050Y532300D01*
X1002467Y532550D01*
X1003050Y532633D01*
X1003467Y532550D01*
X1003967Y532300D01*
G01X935100Y508300D02*
Y512550D01*
X935267Y512967D01*
X935600Y513217D01*
X936100Y513300D01*
X936600Y513133D01*
X936850Y512717D01*
G01X935850Y511300D02*
X934183D01*
G01X941200Y508300D02*
X940700Y508383D01*
X940200Y508717D01*
X939867Y509300D01*
X939700Y509967D01*
X939867Y510633D01*
X940200Y511217D01*
X940700Y511550D01*
X941200Y511633D01*
X941700Y511550D01*
X942200Y511217D01*
X942533Y510633D01*
X942617Y509967D01*
X942533Y509300D01*
X942200Y508717D01*
X941700Y508383D01*
X941200Y508300D01*
G01X946800D02*
Y513300D01*
G01X952400Y508300D02*
Y513300D01*
G01X958000Y508300D02*
X957500Y508383D01*
X957000Y508717D01*
X956667Y509300D01*
X956500Y509967D01*
X956667Y510633D01*
X957000Y511217D01*
X957500Y511550D01*
X958000Y511633D01*
X958500Y511550D01*
X959000Y511217D01*
X959333Y510633D01*
X959417Y509967D01*
X959333Y509300D01*
X959000Y508717D01*
X958500Y508383D01*
X958000Y508300D01*
G01X961517Y511633D02*
X962517Y508300D01*
X963600Y511633D01*
X964683Y508300D01*
X965683Y511633D01*
G01X975300Y510800D02*
X976967D01*
Y509300D01*
X976467Y508800D01*
X975883Y508467D01*
X975050Y508300D01*
X974217Y508467D01*
X973633Y508800D01*
X973133Y509300D01*
X972800Y509883D01*
X972633Y510550D01*
Y511133D01*
X972800Y511633D01*
X973133Y512217D01*
X973633Y512717D01*
X974133Y513050D01*
X974800Y513300D01*
X975383D01*
X976050Y513133D01*
X976550Y512800D01*
G01X979150Y510550D02*
X981817D01*
X981567Y511133D01*
X981150Y511467D01*
X980567Y511633D01*
X979983Y511550D01*
X979483Y511300D01*
X979150Y510717D01*
X978983Y510217D01*
Y509717D01*
X979150Y509217D01*
X979567Y508717D01*
X980067Y508383D01*
X980650Y508300D01*
X981233Y508467D01*
X981817Y508967D01*
G01X984833Y508300D02*
Y511633D01*
G01Y510967D02*
X985250Y511300D01*
X985667Y511550D01*
X986250Y511633D01*
X986667Y511550D01*
X987167Y511300D01*
G01X990100Y508300D02*
Y513300D01*
G01Y510800D02*
X990517Y511300D01*
X991017Y511550D01*
X991517Y511633D01*
X992267Y511467D01*
X992767Y511133D01*
X993100Y510550D01*
Y509883D01*
X992933Y509217D01*
X992600Y508717D01*
X992017Y508383D01*
X991517Y508300D01*
X991017Y508383D01*
X990517Y508633D01*
X990100Y509050D01*
G01X995950Y510550D02*
X998617D01*
X998367Y511133D01*
X997950Y511467D01*
X997367Y511633D01*
X996783Y511550D01*
X996283Y511300D01*
X995950Y510717D01*
X995783Y510217D01*
Y509717D01*
X995950Y509217D01*
X996367Y508717D01*
X996867Y508383D01*
X997450Y508300D01*
X998033Y508467D01*
X998617Y508967D01*
G01X1001633Y508300D02*
Y511633D01*
G01Y510967D02*
X1002050Y511300D01*
X1002467Y511550D01*
X1003050Y511633D01*
X1003467Y511550D01*
X1003967Y511300D01*
G01X1015500Y508300D02*
Y511633D01*
G01Y511050D02*
X1015167Y511383D01*
X1014667Y511550D01*
X1014083Y511633D01*
X1013500Y511467D01*
X1013000Y511133D01*
X1012667Y510633D01*
X1012500Y509967D01*
X1012667Y509300D01*
X1013000Y508800D01*
X1013500Y508467D01*
X1014083Y508300D01*
X1014667Y508383D01*
X1015167Y508633D01*
X1015500Y508967D01*
G01X1018183Y508300D02*
Y511633D01*
G01Y510800D02*
X1018517Y511217D01*
X1019017Y511550D01*
X1019683Y511633D01*
X1020267Y511550D01*
X1020767Y511217D01*
X1021017Y510633D01*
Y508300D01*
G01X1026700Y513300D02*
Y508300D01*
G01Y509050D02*
X1026367Y508633D01*
X1025867Y508383D01*
X1025283Y508300D01*
X1024617Y508467D01*
X1024117Y508883D01*
X1023783Y509383D01*
X1023700Y509967D01*
X1023783Y510550D01*
X1024117Y511050D01*
X1024617Y511467D01*
X1025283Y511633D01*
X1025867Y511550D01*
X1026283Y511383D01*
X1026700Y511050D01*
G01X1034900Y506633D02*
Y511633D01*
G01Y510883D02*
X1035317Y511300D01*
X1035733Y511550D01*
X1036400Y511633D01*
X1036983Y511550D01*
X1037567Y511133D01*
X1037817Y510550D01*
X1037900Y509967D01*
X1037817Y509383D01*
X1037567Y508800D01*
X1037067Y508467D01*
X1036400Y508300D01*
X1035817Y508383D01*
X1035233Y508633D01*
X1034900Y508967D01*
G01X1042000Y508300D02*
Y513300D01*
G01X1046183Y511633D02*
Y509300D01*
X1046517Y508717D01*
X1047017Y508383D01*
X1047600Y508300D01*
X1048183Y508383D01*
X1048683Y508717D01*
X1049017Y509300D01*
G01Y508300D02*
Y511633D01*
G01X1052033Y507050D02*
X1052617Y506717D01*
X1053283Y506633D01*
X1053867Y506717D01*
X1054367Y507133D01*
X1054700Y507717D01*
Y511633D01*
G01Y510967D02*
X1054367Y511300D01*
X1053867Y511550D01*
X1053283Y511633D01*
X1052617Y511467D01*
X1052200Y511133D01*
X1051867Y510550D01*
X1051700Y509967D01*
X1051783Y509467D01*
X1052117Y508883D01*
X1052617Y508467D01*
X1053283Y508300D01*
X1053783Y508383D01*
X1054367Y508717D01*
X1054700Y509050D01*
G01X1062317Y511633D02*
X1063317Y508300D01*
X1064400Y511633D01*
X1065483Y508300D01*
X1066483Y511633D01*
G01X1070000D02*
Y508300D01*
G01Y512967D02*
X1069833Y513050D01*
Y513217D01*
X1070000Y513300D01*
X1070167Y513217D01*
Y513050D01*
X1070000Y512967D01*
G01X1075600Y513300D02*
Y508300D01*
G01X1074433Y511633D02*
X1076767D01*
G01X1079783Y508300D02*
Y513300D01*
G01Y510883D02*
X1080200Y511300D01*
X1080617Y511550D01*
X1081283Y511633D01*
X1081783Y511550D01*
X1082367Y511217D01*
X1082617Y510717D01*
Y508300D01*
G01X1091233D02*
Y511633D01*
G01Y510967D02*
X1091650Y511300D01*
X1092067Y511550D01*
X1092650Y511633D01*
X1093067Y511550D01*
X1093567Y511300D01*
G01X1096750Y510550D02*
X1099417D01*
X1099167Y511133D01*
X1098750Y511467D01*
X1098167Y511633D01*
X1097583Y511550D01*
X1097083Y511300D01*
X1096750Y510717D01*
X1096583Y510217D01*
Y509717D01*
X1096750Y509217D01*
X1097167Y508717D01*
X1097667Y508383D01*
X1098250Y508300D01*
X1098833Y508467D01*
X1099417Y508967D01*
G01X1102350Y508883D02*
X1102767Y508550D01*
X1103350Y508300D01*
X1103850D01*
X1104350Y508467D01*
X1104683Y508717D01*
X1104850Y509050D01*
X1104767Y509550D01*
X1104433Y509800D01*
X1102933Y510300D01*
X1102600Y510883D01*
X1102767Y511300D01*
X1103100Y511550D01*
X1103600Y511633D01*
X1104100Y511550D01*
X1104600Y511300D01*
G01X1109200Y511633D02*
Y508300D01*
G01Y512967D02*
X1109033Y513050D01*
Y513217D01*
X1109200Y513300D01*
X1109367Y513217D01*
Y513050D01*
X1109200Y512967D01*
G01X1113383Y508300D02*
Y511633D01*
G01Y510800D02*
X1113717Y511217D01*
X1114217Y511550D01*
X1114883Y511633D01*
X1115467Y511550D01*
X1115967Y511217D01*
X1116217Y510633D01*
Y508300D01*
G01X933517Y559633D02*
X934517Y556300D01*
X935600Y559633D01*
X936683Y556300D01*
X937683Y559633D01*
G01X941200D02*
Y556300D01*
G01Y560967D02*
X941033Y561050D01*
Y561217D01*
X941200Y561300D01*
X941367Y561217D01*
Y561050D01*
X941200Y560967D01*
G01X946800Y561300D02*
Y556300D01*
G01X945633Y559633D02*
X947967D01*
G01X950983Y556300D02*
Y561300D01*
G01Y558883D02*
X951400Y559300D01*
X951817Y559550D01*
X952483Y559633D01*
X952983Y559550D01*
X953567Y559217D01*
X953817Y558717D01*
Y556300D01*
G01X958000D02*
X957500Y556383D01*
X957000Y556717D01*
X956667Y557300D01*
X956500Y557967D01*
X956667Y558633D01*
X957000Y559217D01*
X957500Y559550D01*
X958000Y559633D01*
X958500Y559550D01*
X959000Y559217D01*
X959333Y558633D01*
X959417Y557967D01*
X959333Y557300D01*
X959000Y556717D01*
X958500Y556383D01*
X958000Y556300D01*
G01X962183Y559633D02*
Y557300D01*
X962517Y556717D01*
X963017Y556383D01*
X963600Y556300D01*
X964183Y556383D01*
X964683Y556717D01*
X965017Y557300D01*
G01Y556300D02*
Y559633D01*
G01X969200Y561300D02*
Y556300D01*
G01X968033Y559633D02*
X970367D01*
G01X979150Y556883D02*
X979567Y556550D01*
X980150Y556300D01*
X980650D01*
X981150Y556467D01*
X981483Y556717D01*
X981650Y557050D01*
X981567Y557550D01*
X981233Y557800D01*
X979733Y558300D01*
X979400Y558883D01*
X979567Y559300D01*
X979900Y559550D01*
X980400Y559633D01*
X980900Y559550D01*
X981400Y559300D01*
G01X986000Y556300D02*
X985500Y556383D01*
X985000Y556717D01*
X984667Y557300D01*
X984500Y557967D01*
X984667Y558633D01*
X985000Y559217D01*
X985500Y559550D01*
X986000Y559633D01*
X986500Y559550D01*
X987000Y559217D01*
X987333Y558633D01*
X987417Y557967D01*
X987333Y557300D01*
X987000Y556717D01*
X986500Y556383D01*
X986000Y556300D01*
G01X991600D02*
Y561300D01*
G01X998700D02*
Y556300D01*
G01Y557050D02*
X998367Y556633D01*
X997867Y556383D01*
X997283Y556300D01*
X996617Y556467D01*
X996117Y556883D01*
X995783Y557383D01*
X995700Y557967D01*
X995783Y558550D01*
X996117Y559050D01*
X996617Y559467D01*
X997283Y559633D01*
X997867Y559550D01*
X998283Y559383D01*
X998700Y559050D01*
G01X1001550Y558550D02*
X1004217D01*
X1003967Y559133D01*
X1003550Y559467D01*
X1002967Y559633D01*
X1002383Y559550D01*
X1001883Y559300D01*
X1001550Y558717D01*
X1001383Y558217D01*
Y557717D01*
X1001550Y557217D01*
X1001967Y556717D01*
X1002467Y556383D01*
X1003050Y556300D01*
X1003633Y556467D01*
X1004217Y556967D01*
G01X1007233Y556300D02*
Y559633D01*
G01Y558967D02*
X1007650Y559300D01*
X1008067Y559550D01*
X1008650Y559633D01*
X1009067Y559550D01*
X1009567Y559300D01*
G01X1017100Y556300D02*
Y559633D01*
G01Y558717D02*
X1017350Y559133D01*
X1017767Y559467D01*
X1018350Y559633D01*
X1018933Y559467D01*
X1019350Y559133D01*
X1019600Y558717D01*
Y556300D01*
G01Y558717D02*
X1019850Y559133D01*
X1020267Y559467D01*
X1020850Y559633D01*
X1021433Y559467D01*
X1021850Y559133D01*
X1022100Y558633D01*
Y556300D01*
G01X1026700D02*
Y559633D01*
G01Y559050D02*
X1026367Y559383D01*
X1025867Y559550D01*
X1025283Y559633D01*
X1024700Y559467D01*
X1024200Y559133D01*
X1023867Y558633D01*
X1023700Y557967D01*
X1023867Y557300D01*
X1024200Y556800D01*
X1024700Y556467D01*
X1025283Y556300D01*
X1025867Y556383D01*
X1026367Y556633D01*
X1026700Y556967D01*
G01X1029550Y556883D02*
X1029967Y556550D01*
X1030550Y556300D01*
X1031050D01*
X1031550Y556467D01*
X1031883Y556717D01*
X1032050Y557050D01*
X1031967Y557550D01*
X1031633Y557800D01*
X1030133Y558300D01*
X1029800Y558883D01*
X1029967Y559300D01*
X1030300Y559550D01*
X1030800Y559633D01*
X1031300Y559550D01*
X1031800Y559300D01*
G01X1034983Y556300D02*
Y561300D01*
G01X1037650Y559633D02*
X1034983Y557717D01*
G01X1036067Y558467D02*
X1037817Y556300D01*
G01X1046100Y554633D02*
Y559633D01*
G01Y558883D02*
X1046517Y559300D01*
X1046933Y559550D01*
X1047600Y559633D01*
X1048183Y559550D01*
X1048767Y559133D01*
X1049017Y558550D01*
X1049100Y557967D01*
X1049017Y557383D01*
X1048767Y556800D01*
X1048267Y556467D01*
X1047600Y556300D01*
X1047017Y556383D01*
X1046433Y556633D01*
X1046100Y556967D01*
G01X1054700Y556300D02*
Y559633D01*
G01Y559050D02*
X1054367Y559383D01*
X1053867Y559550D01*
X1053283Y559633D01*
X1052700Y559467D01*
X1052200Y559133D01*
X1051867Y558633D01*
X1051700Y557967D01*
X1051867Y557300D01*
X1052200Y556800D01*
X1052700Y556467D01*
X1053283Y556300D01*
X1053867Y556383D01*
X1054367Y556633D01*
X1054700Y556967D01*
G01X1060300Y561300D02*
Y556300D01*
G01Y557050D02*
X1059967Y556633D01*
X1059467Y556383D01*
X1058883Y556300D01*
X1058217Y556467D01*
X1057717Y556883D01*
X1057383Y557383D01*
X1057300Y557967D01*
X1057383Y558550D01*
X1057717Y559050D01*
X1058217Y559467D01*
X1058883Y559633D01*
X1059467Y559550D01*
X1059883Y559383D01*
X1060300Y559050D01*
G01X1070000Y556300D02*
X1069500Y556383D01*
X1069000Y556717D01*
X1068667Y557300D01*
X1068500Y557967D01*
X1068667Y558633D01*
X1069000Y559217D01*
X1069500Y559550D01*
X1070000Y559633D01*
X1070500Y559550D01*
X1071000Y559217D01*
X1071333Y558633D01*
X1071417Y557967D01*
X1071333Y557300D01*
X1071000Y556717D01*
X1070500Y556383D01*
X1070000Y556300D01*
G01X1074183D02*
Y559633D01*
G01Y558800D02*
X1074517Y559217D01*
X1075017Y559550D01*
X1075683Y559633D01*
X1076267Y559550D01*
X1076767Y559217D01*
X1077017Y558633D01*
Y556300D01*
G01X1086800Y561300D02*
Y556300D01*
G01X1085633Y559633D02*
X1087967D01*
G01X1092400Y556300D02*
X1091900Y556383D01*
X1091400Y556717D01*
X1091067Y557300D01*
X1090900Y557967D01*
X1091067Y558633D01*
X1091400Y559217D01*
X1091900Y559550D01*
X1092400Y559633D01*
X1092900Y559550D01*
X1093400Y559217D01*
X1093733Y558633D01*
X1093817Y557967D01*
X1093733Y557300D01*
X1093400Y556717D01*
X1092900Y556383D01*
X1092400Y556300D01*
G01X1096500Y554633D02*
Y559633D01*
G01Y558883D02*
X1096917Y559300D01*
X1097333Y559550D01*
X1098000Y559633D01*
X1098583Y559550D01*
X1099167Y559133D01*
X1099417Y558550D01*
X1099500Y557967D01*
X1099417Y557383D01*
X1099167Y556800D01*
X1098667Y556467D01*
X1098000Y556300D01*
X1097417Y556383D01*
X1096833Y556633D01*
X1096500Y556967D01*
G01X943350Y631383D02*
X943767Y631050D01*
X944350Y630800D01*
X944850D01*
X945350Y630967D01*
X945683Y631217D01*
X945850Y631550D01*
X945767Y632050D01*
X945433Y632300D01*
X943933Y632800D01*
X943600Y633383D01*
X943767Y633800D01*
X944100Y634050D01*
X944600Y634133D01*
X945100Y634050D01*
X945600Y633800D01*
G01X950200Y630800D02*
X949700Y630883D01*
X949200Y631217D01*
X948867Y631800D01*
X948700Y632467D01*
X948867Y633133D01*
X949200Y633717D01*
X949700Y634050D01*
X950200Y634133D01*
X950700Y634050D01*
X951200Y633717D01*
X951533Y633133D01*
X951617Y632467D01*
X951533Y631800D01*
X951200Y631217D01*
X950700Y630883D01*
X950200Y630800D01*
G01X955800D02*
Y635800D01*
G01X962900D02*
Y630800D01*
G01Y631550D02*
X962567Y631133D01*
X962067Y630883D01*
X961483Y630800D01*
X960817Y630967D01*
X960317Y631383D01*
X959983Y631883D01*
X959900Y632467D01*
X959983Y633050D01*
X960317Y633550D01*
X960817Y633967D01*
X961483Y634133D01*
X962067Y634050D01*
X962483Y633883D01*
X962900Y633550D01*
G01X965750Y633050D02*
X968417D01*
X968167Y633633D01*
X967750Y633967D01*
X967167Y634133D01*
X966583Y634050D01*
X966083Y633800D01*
X965750Y633217D01*
X965583Y632717D01*
Y632217D01*
X965750Y631717D01*
X966167Y631217D01*
X966667Y630883D01*
X967250Y630800D01*
X967833Y630967D01*
X968417Y631467D01*
G01X971433Y630800D02*
Y634133D01*
G01Y633467D02*
X971850Y633800D01*
X972267Y634050D01*
X972850Y634133D01*
X973267Y634050D01*
X973767Y633800D01*
G01X981300Y630800D02*
Y634133D01*
G01Y633217D02*
X981550Y633633D01*
X981967Y633967D01*
X982550Y634133D01*
X983133Y633967D01*
X983550Y633633D01*
X983800Y633217D01*
Y630800D01*
G01Y633217D02*
X984050Y633633D01*
X984467Y633967D01*
X985050Y634133D01*
X985633Y633967D01*
X986050Y633633D01*
X986300Y633133D01*
Y630800D01*
G01X990900D02*
Y634133D01*
G01Y633550D02*
X990567Y633883D01*
X990067Y634050D01*
X989483Y634133D01*
X988900Y633967D01*
X988400Y633633D01*
X988067Y633133D01*
X987900Y632467D01*
X988067Y631800D01*
X988400Y631300D01*
X988900Y630967D01*
X989483Y630800D01*
X990067Y630883D01*
X990567Y631133D01*
X990900Y631467D01*
G01X993750Y631383D02*
X994167Y631050D01*
X994750Y630800D01*
X995250D01*
X995750Y630967D01*
X996083Y631217D01*
X996250Y631550D01*
X996167Y632050D01*
X995833Y632300D01*
X994333Y632800D01*
X994000Y633383D01*
X994167Y633800D01*
X994500Y634050D01*
X995000Y634133D01*
X995500Y634050D01*
X996000Y633800D01*
G01X999183Y630800D02*
Y635800D01*
G01X1001850Y634133D02*
X999183Y632217D01*
G01X1000267Y632967D02*
X1002017Y630800D01*
G01X1010300Y629133D02*
Y634133D01*
G01Y633383D02*
X1010717Y633800D01*
X1011133Y634050D01*
X1011800Y634133D01*
X1012383Y634050D01*
X1012967Y633633D01*
X1013217Y633050D01*
X1013300Y632467D01*
X1013217Y631883D01*
X1012967Y631300D01*
X1012467Y630967D01*
X1011800Y630800D01*
X1011217Y630883D01*
X1010633Y631133D01*
X1010300Y631467D01*
G01X1018900Y630800D02*
Y634133D01*
G01Y633550D02*
X1018567Y633883D01*
X1018067Y634050D01*
X1017483Y634133D01*
X1016900Y633967D01*
X1016400Y633633D01*
X1016067Y633133D01*
X1015900Y632467D01*
X1016067Y631800D01*
X1016400Y631300D01*
X1016900Y630967D01*
X1017483Y630800D01*
X1018067Y630883D01*
X1018567Y631133D01*
X1018900Y631467D01*
G01X1024500Y635800D02*
Y630800D01*
G01Y631550D02*
X1024167Y631133D01*
X1023667Y630883D01*
X1023083Y630800D01*
X1022417Y630967D01*
X1021917Y631383D01*
X1021583Y631883D01*
X1021500Y632467D01*
X1021583Y633050D01*
X1021917Y633550D01*
X1022417Y633967D01*
X1023083Y634133D01*
X1023667Y634050D01*
X1024083Y633883D01*
X1024500Y633550D01*
G01X935600Y657800D02*
Y662800D01*
X934600Y661800D01*
G01Y657800D02*
X936600D01*
G01X941200Y657633D02*
X941033Y657717D01*
Y657883D01*
X941200Y657967D01*
X941367Y657883D01*
Y657717D01*
X941200Y657633D01*
G01X946800Y657800D02*
X946133Y657883D01*
X945550Y658217D01*
X945050Y658717D01*
X944717Y659300D01*
X944550Y659967D01*
Y660633D01*
X944717Y661300D01*
X945050Y661883D01*
X945550Y662383D01*
X946133Y662717D01*
X946800Y662800D01*
X947467Y662717D01*
X948050Y662383D01*
X948550Y661883D01*
X948883Y661300D01*
X949050Y660633D01*
Y659967D01*
X948883Y659300D01*
X948550Y658717D01*
X948050Y658217D01*
X947467Y657883D01*
X946800Y657800D01*
G01X950983D02*
Y661133D01*
G01Y660300D02*
X951317Y660717D01*
X951817Y661050D01*
X952483Y661133D01*
X953067Y661050D01*
X953567Y660717D01*
X953817Y660133D01*
Y657800D01*
G01X956750Y660050D02*
X959417D01*
X959167Y660633D01*
X958750Y660967D01*
X958167Y661133D01*
X957583Y661050D01*
X957083Y660800D01*
X956750Y660217D01*
X956583Y659717D01*
Y659217D01*
X956750Y658717D01*
X957167Y658217D01*
X957667Y657883D01*
X958250Y657800D01*
X958833Y657967D01*
X959417Y658467D01*
G01X967950Y658383D02*
X968367Y658050D01*
X968950Y657800D01*
X969450D01*
X969950Y657967D01*
X970283Y658217D01*
X970450Y658550D01*
X970367Y659050D01*
X970033Y659300D01*
X968533Y659800D01*
X968200Y660383D01*
X968367Y660800D01*
X968700Y661050D01*
X969200Y661133D01*
X969700Y661050D01*
X970200Y660800D01*
G01X974800Y661133D02*
Y657800D01*
G01Y662467D02*
X974633Y662550D01*
Y662717D01*
X974800Y662800D01*
X974967Y662717D01*
Y662550D01*
X974800Y662467D01*
G01X981900Y662800D02*
Y657800D01*
G01Y658550D02*
X981567Y658133D01*
X981067Y657883D01*
X980483Y657800D01*
X979817Y657967D01*
X979317Y658383D01*
X978983Y658883D01*
X978900Y659467D01*
X978983Y660050D01*
X979317Y660550D01*
X979817Y660967D01*
X980483Y661133D01*
X981067Y661050D01*
X981483Y660883D01*
X981900Y660550D01*
G01X984750Y660050D02*
X987417D01*
X987167Y660633D01*
X986750Y660967D01*
X986167Y661133D01*
X985583Y661050D01*
X985083Y660800D01*
X984750Y660217D01*
X984583Y659717D01*
Y659217D01*
X984750Y658717D01*
X985167Y658217D01*
X985667Y657883D01*
X986250Y657800D01*
X986833Y657967D01*
X987417Y658467D01*
G01X995117Y661133D02*
X996117Y657800D01*
X997200Y661133D01*
X998283Y657800D01*
X999283Y661133D01*
G01X1002800D02*
Y657800D01*
G01Y662467D02*
X1002633Y662550D01*
Y662717D01*
X1002800Y662800D01*
X1002967Y662717D01*
Y662550D01*
X1002800Y662467D01*
G01X1008400Y662800D02*
Y657800D01*
G01X1007233Y661133D02*
X1009567D01*
G01X1012583Y657800D02*
Y662800D01*
G01Y660383D02*
X1013000Y660800D01*
X1013417Y661050D01*
X1014083Y661133D01*
X1014583Y661050D01*
X1015167Y660717D01*
X1015417Y660217D01*
Y657800D01*
G01X1023950Y658383D02*
X1024367Y658050D01*
X1024950Y657800D01*
X1025450D01*
X1025950Y657967D01*
X1026283Y658217D01*
X1026450Y658550D01*
X1026367Y659050D01*
X1026033Y659300D01*
X1024533Y659800D01*
X1024200Y660383D01*
X1024367Y660800D01*
X1024700Y661050D01*
X1025200Y661133D01*
X1025700Y661050D01*
X1026200Y660800D01*
G01X1030800Y657800D02*
X1030300Y657883D01*
X1029800Y658217D01*
X1029467Y658800D01*
X1029300Y659467D01*
X1029467Y660133D01*
X1029800Y660717D01*
X1030300Y661050D01*
X1030800Y661133D01*
X1031300Y661050D01*
X1031800Y660717D01*
X1032133Y660133D01*
X1032217Y659467D01*
X1032133Y658800D01*
X1031800Y658217D01*
X1031300Y657883D01*
X1030800Y657800D01*
G01X1036400D02*
Y662800D01*
G01X1043500D02*
Y657800D01*
G01Y658550D02*
X1043167Y658133D01*
X1042667Y657883D01*
X1042083Y657800D01*
X1041417Y657967D01*
X1040917Y658383D01*
X1040583Y658883D01*
X1040500Y659467D01*
X1040583Y660050D01*
X1040917Y660550D01*
X1041417Y660967D01*
X1042083Y661133D01*
X1042667Y661050D01*
X1043083Y660883D01*
X1043500Y660550D01*
G01X1046350Y660050D02*
X1049017D01*
X1048767Y660633D01*
X1048350Y660967D01*
X1047767Y661133D01*
X1047183Y661050D01*
X1046683Y660800D01*
X1046350Y660217D01*
X1046183Y659717D01*
Y659217D01*
X1046350Y658717D01*
X1046767Y658217D01*
X1047267Y657883D01*
X1047850Y657800D01*
X1048433Y657967D01*
X1049017Y658467D01*
G01X1052033Y657800D02*
Y661133D01*
G01Y660467D02*
X1052450Y660800D01*
X1052867Y661050D01*
X1053450Y661133D01*
X1053867Y661050D01*
X1054367Y660800D01*
G01X1061900Y657800D02*
Y661133D01*
G01Y660217D02*
X1062150Y660633D01*
X1062567Y660967D01*
X1063150Y661133D01*
X1063733Y660967D01*
X1064150Y660633D01*
X1064400Y660217D01*
Y657800D01*
G01Y660217D02*
X1064650Y660633D01*
X1065067Y660967D01*
X1065650Y661133D01*
X1066233Y660967D01*
X1066650Y660633D01*
X1066900Y660133D01*
Y657800D01*
G01X1071500D02*
Y661133D01*
G01Y660550D02*
X1071167Y660883D01*
X1070667Y661050D01*
X1070083Y661133D01*
X1069500Y660967D01*
X1069000Y660633D01*
X1068667Y660133D01*
X1068500Y659467D01*
X1068667Y658800D01*
X1069000Y658300D01*
X1069500Y657967D01*
X1070083Y657800D01*
X1070667Y657883D01*
X1071167Y658133D01*
X1071500Y658467D01*
G01X1074350Y658383D02*
X1074767Y658050D01*
X1075350Y657800D01*
X1075850D01*
X1076350Y657967D01*
X1076683Y658217D01*
X1076850Y658550D01*
X1076767Y659050D01*
X1076433Y659300D01*
X1074933Y659800D01*
X1074600Y660383D01*
X1074767Y660800D01*
X1075100Y661050D01*
X1075600Y661133D01*
X1076100Y661050D01*
X1076600Y660800D01*
G01X1079783Y657800D02*
Y662800D01*
G01X1082450Y661133D02*
X1079783Y659217D01*
G01X1080867Y659967D02*
X1082617Y657800D01*
G01X1090900Y656133D02*
Y661133D01*
G01Y660383D02*
X1091317Y660800D01*
X1091733Y661050D01*
X1092400Y661133D01*
X1092983Y661050D01*
X1093567Y660633D01*
X1093817Y660050D01*
X1093900Y659467D01*
X1093817Y658883D01*
X1093567Y658300D01*
X1093067Y657967D01*
X1092400Y657800D01*
X1091817Y657883D01*
X1091233Y658133D01*
X1090900Y658467D01*
G01X1099500Y657800D02*
Y661133D01*
G01Y660550D02*
X1099167Y660883D01*
X1098667Y661050D01*
X1098083Y661133D01*
X1097500Y660967D01*
X1097000Y660633D01*
X1096667Y660133D01*
X1096500Y659467D01*
X1096667Y658800D01*
X1097000Y658300D01*
X1097500Y657967D01*
X1098083Y657800D01*
X1098667Y657883D01*
X1099167Y658133D01*
X1099500Y658467D01*
G01X1105100Y662800D02*
Y657800D01*
G01Y658550D02*
X1104767Y658133D01*
X1104267Y657883D01*
X1103683Y657800D01*
X1103017Y657967D01*
X1102517Y658383D01*
X1102183Y658883D01*
X1102100Y659467D01*
X1102183Y660050D01*
X1102517Y660550D01*
X1103017Y660967D01*
X1103683Y661133D01*
X1104267Y661050D01*
X1104683Y660883D01*
X1105100Y660550D01*
G01X908100Y763300D02*
Y758300D01*
G01X906933Y761633D02*
X909267D01*
G01X912283Y758300D02*
Y763300D01*
G01Y760883D02*
X912700Y761300D01*
X913117Y761550D01*
X913783Y761633D01*
X914283Y761550D01*
X914867Y761217D01*
X915117Y760717D01*
Y758300D01*
G01X919300Y761633D02*
Y758300D01*
G01Y762967D02*
X919133Y763050D01*
Y763217D01*
X919300Y763300D01*
X919467Y763217D01*
Y763050D01*
X919300Y762967D01*
G01X926233Y761217D02*
X925650Y761550D01*
X925150Y761633D01*
X924483Y761467D01*
X923983Y761133D01*
X923650Y760550D01*
X923567Y759967D01*
X923650Y759383D01*
X923983Y758883D01*
X924483Y758467D01*
X925150Y758300D01*
X925733Y758467D01*
X926233Y758800D01*
G01X929083Y758300D02*
Y763300D01*
G01X931750Y761633D02*
X929083Y759717D01*
G01X930167Y760467D02*
X931917Y758300D01*
G01X934683D02*
Y761633D01*
G01Y760800D02*
X935017Y761217D01*
X935517Y761550D01*
X936183Y761633D01*
X936767Y761550D01*
X937267Y761217D01*
X937517Y760633D01*
Y758300D01*
G01X940450Y760550D02*
X943117D01*
X942867Y761133D01*
X942450Y761467D01*
X941867Y761633D01*
X941283Y761550D01*
X940783Y761300D01*
X940450Y760717D01*
X940283Y760217D01*
Y759717D01*
X940450Y759217D01*
X940867Y758717D01*
X941367Y758383D01*
X941950Y758300D01*
X942533Y758467D01*
X943117Y758967D01*
G01X946050Y758883D02*
X946467Y758550D01*
X947050Y758300D01*
X947550D01*
X948050Y758467D01*
X948383Y758717D01*
X948550Y759050D01*
X948467Y759550D01*
X948133Y759800D01*
X946633Y760300D01*
X946300Y760883D01*
X946467Y761300D01*
X946800Y761550D01*
X947300Y761633D01*
X947800Y761550D01*
X948300Y761300D01*
G01X951650Y758883D02*
X952067Y758550D01*
X952650Y758300D01*
X953150D01*
X953650Y758467D01*
X953983Y758717D01*
X954150Y759050D01*
X954067Y759550D01*
X953733Y759800D01*
X952233Y760300D01*
X951900Y760883D01*
X952067Y761300D01*
X952400Y761550D01*
X952900Y761633D01*
X953400Y761550D01*
X953900Y761300D01*
G01X922600Y775300D02*
Y780300D01*
G01Y777800D02*
X923017Y778300D01*
X923517Y778550D01*
X924017Y778633D01*
X924767Y778467D01*
X925267Y778133D01*
X925600Y777550D01*
Y776883D01*
X925433Y776217D01*
X925100Y775717D01*
X924517Y775383D01*
X924017Y775300D01*
X923517Y775383D01*
X923017Y775633D01*
X922600Y776050D01*
G01X929700Y775300D02*
X929200Y775383D01*
X928700Y775717D01*
X928367Y776300D01*
X928200Y776967D01*
X928367Y777633D01*
X928700Y778217D01*
X929200Y778550D01*
X929700Y778633D01*
X930200Y778550D01*
X930700Y778217D01*
X931033Y777633D01*
X931117Y776967D01*
X931033Y776300D01*
X930700Y775717D01*
X930200Y775383D01*
X929700Y775300D01*
G01X936800D02*
Y778633D01*
G01Y778050D02*
X936467Y778383D01*
X935967Y778550D01*
X935383Y778633D01*
X934800Y778467D01*
X934300Y778133D01*
X933967Y777633D01*
X933800Y776967D01*
X933967Y776300D01*
X934300Y775800D01*
X934800Y775467D01*
X935383Y775300D01*
X935967Y775383D01*
X936467Y775633D01*
X936800Y775967D01*
G01X939733Y775300D02*
Y778633D01*
G01Y777967D02*
X940150Y778300D01*
X940567Y778550D01*
X941150Y778633D01*
X941567Y778550D01*
X942067Y778300D01*
G01X948000Y780300D02*
Y775300D01*
G01Y776050D02*
X947667Y775633D01*
X947167Y775383D01*
X946583Y775300D01*
X945917Y775467D01*
X945417Y775883D01*
X945083Y776383D01*
X945000Y776967D01*
X945083Y777550D01*
X945417Y778050D01*
X945917Y778467D01*
X946583Y778633D01*
X947167Y778550D01*
X947583Y778383D01*
X948000Y778050D01*
G01X912100Y884300D02*
Y879300D01*
G01X910183Y884300D02*
X914017D01*
G01X915617Y882633D02*
X916617Y879300D01*
X917700Y882633D01*
X918783Y879300D01*
X919783Y882633D01*
G01X923300D02*
Y879300D01*
G01Y883967D02*
X923133Y884050D01*
Y884217D01*
X923300Y884300D01*
X923467Y884217D01*
Y884050D01*
X923300Y883967D01*
G01X927650Y879883D02*
X928067Y879550D01*
X928650Y879300D01*
X929150D01*
X929650Y879467D01*
X929983Y879717D01*
X930150Y880050D01*
X930067Y880550D01*
X929733Y880800D01*
X928233Y881300D01*
X927900Y881883D01*
X928067Y882300D01*
X928400Y882550D01*
X928900Y882633D01*
X929400Y882550D01*
X929900Y882300D01*
G01X934500Y884300D02*
Y879300D01*
G01X933333Y882633D02*
X935667D01*
G01X947200Y879300D02*
Y882633D01*
G01Y882050D02*
X946867Y882383D01*
X946367Y882550D01*
X945783Y882633D01*
X945200Y882467D01*
X944700Y882133D01*
X944367Y881633D01*
X944200Y880967D01*
X944367Y880300D01*
X944700Y879800D01*
X945200Y879467D01*
X945783Y879300D01*
X946367Y879383D01*
X946867Y879633D01*
X947200Y879967D01*
G01X949883Y879300D02*
Y882633D01*
G01Y881800D02*
X950217Y882217D01*
X950717Y882550D01*
X951383Y882633D01*
X951967Y882550D01*
X952467Y882217D01*
X952717Y881633D01*
Y879300D01*
G01X958400Y884300D02*
Y879300D01*
G01Y880050D02*
X958067Y879633D01*
X957567Y879383D01*
X956983Y879300D01*
X956317Y879467D01*
X955817Y879883D01*
X955483Y880383D01*
X955400Y880967D01*
X955483Y881550D01*
X955817Y882050D01*
X956317Y882467D01*
X956983Y882633D01*
X957567Y882550D01*
X957983Y882383D01*
X958400Y882050D01*
G01X966600Y879300D02*
Y884300D01*
G01Y881800D02*
X967017Y882300D01*
X967517Y882550D01*
X968017Y882633D01*
X968767Y882467D01*
X969267Y882133D01*
X969600Y881550D01*
Y880883D01*
X969433Y880217D01*
X969100Y879717D01*
X968517Y879383D01*
X968017Y879300D01*
X967517Y879383D01*
X967017Y879633D01*
X966600Y880050D01*
G01X973700Y879300D02*
X973200Y879383D01*
X972700Y879717D01*
X972367Y880300D01*
X972200Y880967D01*
X972367Y881633D01*
X972700Y882217D01*
X973200Y882550D01*
X973700Y882633D01*
X974200Y882550D01*
X974700Y882217D01*
X975033Y881633D01*
X975117Y880967D01*
X975033Y880300D01*
X974700Y879717D01*
X974200Y879383D01*
X973700Y879300D01*
G01X977217Y882633D02*
X978217Y879300D01*
X979300Y882633D01*
X980383Y879300D01*
X981383Y882633D01*
G01X901600Y939410D02*
Y870910D01*
G01X910433Y915300D02*
Y920300D01*
X912517D01*
X913183Y920050D01*
X913600Y919717D01*
X913767Y919050D01*
X913600Y918383D01*
X913100Y917967D01*
X912517Y917717D01*
X910433D01*
G01X912517D02*
X913767Y915300D01*
G01X917700D02*
X917200Y915383D01*
X916700Y915717D01*
X916367Y916300D01*
X916200Y916967D01*
X916367Y917633D01*
X916700Y918217D01*
X917200Y918550D01*
X917700Y918633D01*
X918200Y918550D01*
X918700Y918217D01*
X919033Y917633D01*
X919117Y916967D01*
X919033Y916300D01*
X918700Y915717D01*
X918200Y915383D01*
X917700Y915300D01*
G01X921883Y918633D02*
Y916300D01*
X922217Y915717D01*
X922717Y915383D01*
X923300Y915300D01*
X923883Y915383D01*
X924383Y915717D01*
X924717Y916300D01*
G01Y915300D02*
Y918633D01*
G01X928900Y920300D02*
Y915300D01*
G01X927733Y918633D02*
X930067D01*
G01X934500D02*
Y915300D01*
G01Y919967D02*
X934333Y920050D01*
Y920217D01*
X934500Y920300D01*
X934667Y920217D01*
Y920050D01*
X934500Y919967D01*
G01X938683Y915300D02*
Y918633D01*
G01Y917800D02*
X939017Y918217D01*
X939517Y918550D01*
X940183Y918633D01*
X940767Y918550D01*
X941267Y918217D01*
X941517Y917633D01*
Y915300D01*
G01X944533Y914050D02*
X945117Y913717D01*
X945783Y913633D01*
X946367Y913717D01*
X946867Y914133D01*
X947200Y914717D01*
Y918633D01*
G01Y917967D02*
X946867Y918300D01*
X946367Y918550D01*
X945783Y918633D01*
X945117Y918467D01*
X944700Y918133D01*
X944367Y917550D01*
X944200Y916967D01*
X944283Y916467D01*
X944617Y915883D01*
X945117Y915467D01*
X945783Y915300D01*
X946283Y915383D01*
X946867Y915717D01*
X947200Y916050D01*
G01X956900Y920300D02*
Y915300D01*
G01X955733Y918633D02*
X958067D01*
G01X962500Y915300D02*
X962000Y915383D01*
X961500Y915717D01*
X961167Y916300D01*
X961000Y916967D01*
X961167Y917633D01*
X961500Y918217D01*
X962000Y918550D01*
X962500Y918633D01*
X963000Y918550D01*
X963500Y918217D01*
X963833Y917633D01*
X963917Y916967D01*
X963833Y916300D01*
X963500Y915717D01*
X963000Y915383D01*
X962500Y915300D01*
G01X968100D02*
Y920300D01*
G01X972450Y917550D02*
X975117D01*
X974867Y918133D01*
X974450Y918467D01*
X973867Y918633D01*
X973283Y918550D01*
X972783Y918300D01*
X972450Y917717D01*
X972283Y917217D01*
Y916717D01*
X972450Y916217D01*
X972867Y915717D01*
X973367Y915383D01*
X973950Y915300D01*
X974533Y915467D01*
X975117Y915967D01*
G01X978133Y915300D02*
Y918633D01*
G01Y917967D02*
X978550Y918300D01*
X978967Y918550D01*
X979550Y918633D01*
X979967Y918550D01*
X980467Y918300D01*
G01X986400Y915300D02*
Y918633D01*
G01Y918050D02*
X986067Y918383D01*
X985567Y918550D01*
X984983Y918633D01*
X984400Y918467D01*
X983900Y918133D01*
X983567Y917633D01*
X983400Y916967D01*
X983567Y916300D01*
X983900Y915800D01*
X984400Y915467D01*
X984983Y915300D01*
X985567Y915383D01*
X986067Y915633D01*
X986400Y915967D01*
G01X989083Y915300D02*
Y918633D01*
G01Y917800D02*
X989417Y918217D01*
X989917Y918550D01*
X990583Y918633D01*
X991167Y918550D01*
X991667Y918217D01*
X991917Y917633D01*
Y915300D01*
G01X997433Y918217D02*
X996850Y918550D01*
X996350Y918633D01*
X995683Y918467D01*
X995183Y918133D01*
X994850Y917550D01*
X994767Y916967D01*
X994850Y916383D01*
X995183Y915883D01*
X995683Y915467D01*
X996350Y915300D01*
X996933Y915467D01*
X997433Y915800D01*
G01X1000450Y917550D02*
X1003117D01*
X1002867Y918133D01*
X1002450Y918467D01*
X1001867Y918633D01*
X1001283Y918550D01*
X1000783Y918300D01*
X1000450Y917717D01*
X1000283Y917217D01*
Y916717D01*
X1000450Y916217D01*
X1000867Y915717D01*
X1001367Y915383D01*
X1001950Y915300D01*
X1002533Y915467D01*
X1003117Y915967D01*
G01X901600Y894300D02*
X1456600D01*
G01X981850Y240800D02*
Y245800D01*
G01X985350D02*
Y240800D01*
G01Y243300D02*
X981850D01*
G01X989200Y240800D02*
X988533Y240883D01*
X987950Y241217D01*
X987450Y241717D01*
X987117Y242300D01*
X986950Y242967D01*
Y243633D01*
X987117Y244300D01*
X987450Y244883D01*
X987950Y245383D01*
X988533Y245717D01*
X989200Y245800D01*
X989867Y245717D01*
X990450Y245383D01*
X990950Y244883D01*
X991283Y244300D01*
X991450Y243633D01*
Y242967D01*
X991283Y242300D01*
X990950Y241717D01*
X990450Y241217D01*
X989867Y240883D01*
X989200Y240800D01*
G01X993133Y245800D02*
Y240800D01*
X996467D01*
G01X1002067D02*
X998733D01*
Y245800D01*
X1002067D01*
G01X1000733Y243383D02*
X998733D01*
G01X1025900Y240800D02*
Y244133D01*
G01Y243217D02*
X1026150Y243633D01*
X1026567Y243967D01*
X1027150Y244133D01*
X1027733Y243967D01*
X1028150Y243633D01*
X1028400Y243217D01*
Y240800D01*
G01Y243217D02*
X1028650Y243633D01*
X1029067Y243967D01*
X1029650Y244133D01*
X1030233Y243967D01*
X1030650Y243633D01*
X1030900Y243133D01*
Y240800D01*
G01X1034000Y244133D02*
Y240800D01*
G01Y245467D02*
X1033833Y245550D01*
Y245717D01*
X1034000Y245800D01*
X1034167Y245717D01*
Y245550D01*
X1034000Y245467D01*
G01X1039600Y240800D02*
Y245800D01*
G01X1043950Y241383D02*
X1044367Y241050D01*
X1044950Y240800D01*
X1045450D01*
X1045950Y240967D01*
X1046283Y241217D01*
X1046450Y241550D01*
X1046367Y242050D01*
X1046033Y242300D01*
X1044533Y242800D01*
X1044200Y243383D01*
X1044367Y243800D01*
X1044700Y244050D01*
X1045200Y244133D01*
X1045700Y244050D01*
X1046200Y243800D01*
G01X1050383Y239133D02*
X1049550Y239967D01*
X1049133Y240800D01*
Y244133D01*
X1049550Y244967D01*
X1050383Y245800D01*
G01X1054733Y240800D02*
Y245800D01*
X1056733D01*
X1057400Y245550D01*
X1057900Y244967D01*
X1058067Y244300D01*
X1057900Y243633D01*
X1057483Y243133D01*
X1056733Y242883D01*
X1054733D01*
G01X1062000Y245800D02*
Y240800D01*
G01X1060083Y245800D02*
X1063917D01*
G01X1065850Y240800D02*
Y245800D01*
G01X1069350D02*
Y240800D01*
G01Y243300D02*
X1065850D01*
G01X1073617Y239133D02*
X1074450Y239967D01*
X1074867Y240800D01*
Y244133D01*
X1074450Y244967D01*
X1073617Y245800D01*
G01X981767Y396967D02*
X982100Y397217D01*
X982350Y397633D01*
X982517Y398217D01*
X982350Y398717D01*
X982017Y399050D01*
X981433Y399300D01*
X979183D01*
Y394300D01*
X981933D01*
X982517Y394633D01*
X982850Y395133D01*
X983017Y395717D01*
X982850Y396300D01*
X982350Y396800D01*
X981767Y396967D01*
X979183D01*
G01X984617Y394300D02*
X986700Y399300D01*
X988783Y394300D01*
G01X988033Y396050D02*
X985367D01*
G01X994133Y398883D02*
X993633Y399133D01*
X993050Y399300D01*
X992383D01*
X991633Y399050D01*
X991050Y398633D01*
X990633Y398133D01*
X990300Y397300D01*
X990217Y396550D01*
X990383Y395800D01*
X990633Y395300D01*
X991133Y394800D01*
X991717Y394467D01*
X992300Y394300D01*
X992883D01*
X993467Y394467D01*
X993967Y394717D01*
X994383Y395050D01*
G01X996067Y394300D02*
Y399300D01*
G01X999233D02*
X996067Y396217D01*
G01X999733Y394300D02*
X997483Y397633D01*
G01X1007267Y394300D02*
Y399300D01*
X1008933D01*
X1009600Y399050D01*
X1010100Y398717D01*
X1010517Y398217D01*
X1010850Y397633D01*
X1010933Y396800D01*
X1010850Y395967D01*
X1010517Y395383D01*
X1010100Y394883D01*
X1009600Y394550D01*
X1008933Y394300D01*
X1007267D01*
G01X1013033D02*
Y399300D01*
X1015117D01*
X1015783Y399050D01*
X1016200Y398717D01*
X1016367Y398050D01*
X1016200Y397383D01*
X1015700Y396967D01*
X1015117Y396717D01*
X1013033D01*
G01X1015117D02*
X1016367Y394300D01*
G01X1019300Y399300D02*
X1021300D01*
G01X1020300D02*
Y394300D01*
G01X1019300D02*
X1021300D01*
G01X1024233Y399300D02*
Y394300D01*
X1027567D01*
G01X1029833Y399300D02*
Y394300D01*
X1033167D01*
G01X1057000D02*
Y397633D01*
G01Y396717D02*
X1057250Y397133D01*
X1057667Y397467D01*
X1058250Y397633D01*
X1058833Y397467D01*
X1059250Y397133D01*
X1059500Y396717D01*
Y394300D01*
G01Y396717D02*
X1059750Y397133D01*
X1060167Y397467D01*
X1060750Y397633D01*
X1061333Y397467D01*
X1061750Y397133D01*
X1062000Y396633D01*
Y394300D01*
G01X1065100Y397633D02*
Y394300D01*
G01Y398967D02*
X1064933Y399050D01*
Y399217D01*
X1065100Y399300D01*
X1065267Y399217D01*
Y399050D01*
X1065100Y398967D01*
G01X1070700Y394300D02*
Y399300D01*
G01X1075050Y394883D02*
X1075467Y394550D01*
X1076050Y394300D01*
X1076550D01*
X1077050Y394467D01*
X1077383Y394717D01*
X1077550Y395050D01*
X1077467Y395550D01*
X1077133Y395800D01*
X1075633Y396300D01*
X1075300Y396883D01*
X1075467Y397300D01*
X1075800Y397550D01*
X1076300Y397633D01*
X1076800Y397550D01*
X1077300Y397300D01*
G01X1081483Y392633D02*
X1080650Y393467D01*
X1080233Y394300D01*
Y397633D01*
X1080650Y398467D01*
X1081483Y399300D01*
G01X1085583Y394300D02*
Y399300D01*
X1089417Y394300D01*
Y399300D01*
G01X1091433Y394300D02*
Y399300D01*
X1093433D01*
X1094100Y399050D01*
X1094600Y398467D01*
X1094767Y397800D01*
X1094600Y397133D01*
X1094183Y396633D01*
X1093433Y396383D01*
X1091433D01*
G01X1098700Y399300D02*
Y394300D01*
G01X1096783Y399300D02*
X1100617D01*
G01X1102550Y394300D02*
Y399300D01*
G01X1106050D02*
Y394300D01*
G01Y396800D02*
X1102550D01*
G01X1110317Y392633D02*
X1111150Y393467D01*
X1111567Y394300D01*
Y397633D01*
X1111150Y398467D01*
X1110317Y399300D01*
G01X943517Y652133D02*
X944517Y648800D01*
X945600Y652133D01*
X946683Y648800D01*
X947683Y652133D01*
G01X949783Y648800D02*
Y653800D01*
G01Y651383D02*
X950200Y651800D01*
X950617Y652050D01*
X951283Y652133D01*
X951783Y652050D01*
X952367Y651717D01*
X952617Y651217D01*
Y648800D01*
G01X956800Y652133D02*
Y648800D01*
G01Y653467D02*
X956633Y653550D01*
Y653717D01*
X956800Y653800D01*
X956967Y653717D01*
Y653550D01*
X956800Y653467D01*
G01X963733Y651717D02*
X963150Y652050D01*
X962650Y652133D01*
X961983Y651967D01*
X961483Y651633D01*
X961150Y651050D01*
X961067Y650467D01*
X961150Y649883D01*
X961483Y649383D01*
X961983Y648967D01*
X962650Y648800D01*
X963233Y648967D01*
X963733Y649300D01*
G01X966583Y648800D02*
Y653800D01*
G01Y651383D02*
X967000Y651800D01*
X967417Y652050D01*
X968083Y652133D01*
X968583Y652050D01*
X969167Y651717D01*
X969417Y651217D01*
Y648800D01*
G01X977950Y649383D02*
X978367Y649050D01*
X978950Y648800D01*
X979450D01*
X979950Y648967D01*
X980283Y649217D01*
X980450Y649550D01*
X980367Y650050D01*
X980033Y650300D01*
X978533Y650800D01*
X978200Y651383D01*
X978367Y651800D01*
X978700Y652050D01*
X979200Y652133D01*
X979700Y652050D01*
X980200Y651800D01*
G01X984800Y652133D02*
Y648800D01*
G01Y653467D02*
X984633Y653550D01*
Y653717D01*
X984800Y653800D01*
X984967Y653717D01*
Y653550D01*
X984800Y653467D01*
G01X989150Y652133D02*
X991650D01*
X989150Y648800D01*
X991650D01*
G01X994750Y651050D02*
X997417D01*
X997167Y651633D01*
X996750Y651967D01*
X996167Y652133D01*
X995583Y652050D01*
X995083Y651800D01*
X994750Y651217D01*
X994583Y650717D01*
Y650217D01*
X994750Y649717D01*
X995167Y649217D01*
X995667Y648883D01*
X996250Y648800D01*
X996833Y648967D01*
X997417Y649467D01*
G01X1007200Y652133D02*
Y648800D01*
G01Y653467D02*
X1007033Y653550D01*
Y653717D01*
X1007200Y653800D01*
X1007367Y653717D01*
Y653550D01*
X1007200Y653467D01*
G01X1011550Y649383D02*
X1011967Y649050D01*
X1012550Y648800D01*
X1013050D01*
X1013550Y648967D01*
X1013883Y649217D01*
X1014050Y649550D01*
X1013967Y650050D01*
X1013633Y650300D01*
X1012133Y650800D01*
X1011800Y651383D01*
X1011967Y651800D01*
X1012300Y652050D01*
X1012800Y652133D01*
X1013300Y652050D01*
X1013800Y651800D01*
G01X1022500Y648800D02*
Y653800D01*
G01Y651300D02*
X1022917Y651800D01*
X1023417Y652050D01*
X1023917Y652133D01*
X1024667Y651967D01*
X1025167Y651633D01*
X1025500Y651050D01*
Y650383D01*
X1025333Y649717D01*
X1025000Y649217D01*
X1024417Y648883D01*
X1023917Y648800D01*
X1023417Y648883D01*
X1022917Y649133D01*
X1022500Y649550D01*
G01X1029600Y652133D02*
Y648800D01*
G01Y653467D02*
X1029433Y653550D01*
Y653717D01*
X1029600Y653800D01*
X1029767Y653717D01*
Y653550D01*
X1029600Y653467D01*
G01X1034033Y647550D02*
X1034617Y647217D01*
X1035283Y647133D01*
X1035867Y647217D01*
X1036367Y647633D01*
X1036700Y648217D01*
Y652133D01*
G01Y651467D02*
X1036367Y651800D01*
X1035867Y652050D01*
X1035283Y652133D01*
X1034617Y651967D01*
X1034200Y651633D01*
X1033867Y651050D01*
X1033700Y650467D01*
X1033783Y649967D01*
X1034117Y649383D01*
X1034617Y648967D01*
X1035283Y648800D01*
X1035783Y648883D01*
X1036367Y649217D01*
X1036700Y649550D01*
G01X1039633Y647550D02*
X1040217Y647217D01*
X1040883Y647133D01*
X1041467Y647217D01*
X1041967Y647633D01*
X1042300Y648217D01*
Y652133D01*
G01Y651467D02*
X1041967Y651800D01*
X1041467Y652050D01*
X1040883Y652133D01*
X1040217Y651967D01*
X1039800Y651633D01*
X1039467Y651050D01*
X1039300Y650467D01*
X1039383Y649967D01*
X1039717Y649383D01*
X1040217Y648967D01*
X1040883Y648800D01*
X1041383Y648883D01*
X1041967Y649217D01*
X1042300Y649550D01*
G01X1045150Y651050D02*
X1047817D01*
X1047567Y651633D01*
X1047150Y651967D01*
X1046567Y652133D01*
X1045983Y652050D01*
X1045483Y651800D01*
X1045150Y651217D01*
X1044983Y650717D01*
Y650217D01*
X1045150Y649717D01*
X1045567Y649217D01*
X1046067Y648883D01*
X1046650Y648800D01*
X1047233Y648967D01*
X1047817Y649467D01*
G01X1050833Y648800D02*
Y652133D01*
G01Y651467D02*
X1051250Y651800D01*
X1051667Y652050D01*
X1052250Y652133D01*
X1052667Y652050D01*
X1053167Y651800D01*
G01X1063200Y653800D02*
Y648800D01*
G01X1062033Y652133D02*
X1064367D01*
G01X1067383Y648800D02*
Y653800D01*
G01Y651383D02*
X1067800Y651800D01*
X1068217Y652050D01*
X1068883Y652133D01*
X1069383Y652050D01*
X1069967Y651717D01*
X1070217Y651217D01*
Y648800D01*
G01X1075900D02*
Y652133D01*
G01Y651550D02*
X1075567Y651883D01*
X1075067Y652050D01*
X1074483Y652133D01*
X1073900Y651967D01*
X1073400Y651633D01*
X1073067Y651133D01*
X1072900Y650467D01*
X1073067Y649800D01*
X1073400Y649300D01*
X1073900Y648967D01*
X1074483Y648800D01*
X1075067Y648883D01*
X1075567Y649133D01*
X1075900Y649467D01*
G01X1078583Y648800D02*
Y652133D01*
G01Y651300D02*
X1078917Y651717D01*
X1079417Y652050D01*
X1080083Y652133D01*
X1080667Y652050D01*
X1081167Y651717D01*
X1081417Y651133D01*
Y648800D01*
G01X1092700D02*
Y652133D01*
G01Y651550D02*
X1092367Y651883D01*
X1091867Y652050D01*
X1091283Y652133D01*
X1090700Y651967D01*
X1090200Y651633D01*
X1089867Y651133D01*
X1089700Y650467D01*
X1089867Y649800D01*
X1090200Y649300D01*
X1090700Y648967D01*
X1091283Y648800D01*
X1091867Y648883D01*
X1092367Y649133D01*
X1092700Y649467D01*
G01X1095383Y648800D02*
Y652133D01*
G01Y651300D02*
X1095717Y651717D01*
X1096217Y652050D01*
X1096883Y652133D01*
X1097467Y652050D01*
X1097967Y651717D01*
X1098217Y651133D01*
Y648800D01*
G01X1100983D02*
Y652133D01*
G01Y651300D02*
X1101317Y651717D01*
X1101817Y652050D01*
X1102483Y652133D01*
X1103067Y652050D01*
X1103567Y651717D01*
X1103817Y651133D01*
Y648800D01*
G01X1106583Y652133D02*
Y649800D01*
X1106917Y649217D01*
X1107417Y648883D01*
X1108000Y648800D01*
X1108583Y648883D01*
X1109083Y649217D01*
X1109417Y649800D01*
G01Y648800D02*
Y652133D01*
G01X1115100Y648800D02*
Y652133D01*
G01Y651550D02*
X1114767Y651883D01*
X1114267Y652050D01*
X1113683Y652133D01*
X1113100Y651967D01*
X1112600Y651633D01*
X1112267Y651133D01*
X1112100Y650467D01*
X1112267Y649800D01*
X1112600Y649300D01*
X1113100Y648967D01*
X1113683Y648800D01*
X1114267Y648883D01*
X1114767Y649133D01*
X1115100Y649467D01*
G01X1119200Y648800D02*
Y653800D01*
G01X944933Y639800D02*
Y643133D01*
G01Y642467D02*
X945350Y642800D01*
X945767Y643050D01*
X946350Y643133D01*
X946767Y643050D01*
X947267Y642800D01*
G01X951700Y643133D02*
Y639800D01*
G01Y644467D02*
X951533Y644550D01*
Y644717D01*
X951700Y644800D01*
X951867Y644717D01*
Y644550D01*
X951700Y644467D01*
G01X955883Y639800D02*
Y643133D01*
G01Y642300D02*
X956217Y642717D01*
X956717Y643050D01*
X957383Y643133D01*
X957967Y643050D01*
X958467Y642717D01*
X958717Y642133D01*
Y639800D01*
G01X961733Y638550D02*
X962317Y638217D01*
X962983Y638133D01*
X963567Y638217D01*
X964067Y638633D01*
X964400Y639217D01*
Y643133D01*
G01Y642467D02*
X964067Y642800D01*
X963567Y643050D01*
X962983Y643133D01*
X962317Y642967D01*
X961900Y642633D01*
X961567Y642050D01*
X961400Y641467D01*
X961483Y640967D01*
X961817Y640383D01*
X962317Y639967D01*
X962983Y639800D01*
X963483Y639883D01*
X964067Y640217D01*
X964400Y640550D01*
G01X972850Y640383D02*
X973267Y640050D01*
X973850Y639800D01*
X974350D01*
X974850Y639967D01*
X975183Y640217D01*
X975350Y640550D01*
X975267Y641050D01*
X974933Y641300D01*
X973433Y641800D01*
X973100Y642383D01*
X973267Y642800D01*
X973600Y643050D01*
X974100Y643133D01*
X974600Y643050D01*
X975100Y642800D01*
G01X979700Y643133D02*
Y639800D01*
G01Y644467D02*
X979533Y644550D01*
Y644717D01*
X979700Y644800D01*
X979867Y644717D01*
Y644550D01*
X979700Y644467D01*
G01X984050Y643133D02*
X986550D01*
X984050Y639800D01*
X986550D01*
G01X989650Y642050D02*
X992317D01*
X992067Y642633D01*
X991650Y642967D01*
X991067Y643133D01*
X990483Y643050D01*
X989983Y642800D01*
X989650Y642217D01*
X989483Y641717D01*
Y641217D01*
X989650Y640717D01*
X990067Y640217D01*
X990567Y639883D01*
X991150Y639800D01*
X991733Y639967D01*
X992317Y640467D01*
G01X1001933Y638883D02*
X1002267Y639967D01*
G01X991600Y680300D02*
X993267D01*
Y678800D01*
X992767Y678300D01*
X992183Y677967D01*
X991350Y677800D01*
X990517Y677967D01*
X989933Y678300D01*
X989433Y678800D01*
X989100Y679383D01*
X988933Y680050D01*
Y680633D01*
X989100Y681133D01*
X989433Y681717D01*
X989933Y682217D01*
X990433Y682550D01*
X991100Y682800D01*
X991683D01*
X992350Y682633D01*
X992850Y682300D01*
G01X995450Y680050D02*
X998117D01*
X997867Y680633D01*
X997450Y680967D01*
X996867Y681133D01*
X996283Y681050D01*
X995783Y680800D01*
X995450Y680217D01*
X995283Y679717D01*
Y679217D01*
X995450Y678717D01*
X995867Y678217D01*
X996367Y677883D01*
X996950Y677800D01*
X997533Y677967D01*
X998117Y678467D01*
G01X1001133Y677800D02*
Y681133D01*
G01Y680467D02*
X1001550Y680800D01*
X1001967Y681050D01*
X1002550Y681133D01*
X1002967Y681050D01*
X1003467Y680800D01*
G01X1006400Y677800D02*
Y682800D01*
G01Y680300D02*
X1006817Y680800D01*
X1007317Y681050D01*
X1007817Y681133D01*
X1008567Y680967D01*
X1009067Y680633D01*
X1009400Y680050D01*
Y679383D01*
X1009233Y678717D01*
X1008900Y678217D01*
X1008317Y677883D01*
X1007817Y677800D01*
X1007317Y677883D01*
X1006817Y678133D01*
X1006400Y678550D01*
G01X1012250Y680050D02*
X1014917D01*
X1014667Y680633D01*
X1014250Y680967D01*
X1013667Y681133D01*
X1013083Y681050D01*
X1012583Y680800D01*
X1012250Y680217D01*
X1012083Y679717D01*
Y679217D01*
X1012250Y678717D01*
X1012667Y678217D01*
X1013167Y677883D01*
X1013750Y677800D01*
X1014333Y677967D01*
X1014917Y678467D01*
G01X1017933Y677800D02*
Y681133D01*
G01Y680467D02*
X1018350Y680800D01*
X1018767Y681050D01*
X1019350Y681133D01*
X1019767Y681050D01*
X1020267Y680800D01*
G01X1031800Y682800D02*
Y677800D01*
G01Y678550D02*
X1031467Y678133D01*
X1030967Y677883D01*
X1030383Y677800D01*
X1029717Y677967D01*
X1029217Y678383D01*
X1028883Y678883D01*
X1028800Y679467D01*
X1028883Y680050D01*
X1029217Y680550D01*
X1029717Y680967D01*
X1030383Y681133D01*
X1030967Y681050D01*
X1031383Y680883D01*
X1031800Y680550D01*
G01X1034650Y680050D02*
X1037317D01*
X1037067Y680633D01*
X1036650Y680967D01*
X1036067Y681133D01*
X1035483Y681050D01*
X1034983Y680800D01*
X1034650Y680217D01*
X1034483Y679717D01*
Y679217D01*
X1034650Y678717D01*
X1035067Y678217D01*
X1035567Y677883D01*
X1036150Y677800D01*
X1036733Y677967D01*
X1037317Y678467D01*
G01X1040250Y678383D02*
X1040667Y678050D01*
X1041250Y677800D01*
X1041750D01*
X1042250Y677967D01*
X1042583Y678217D01*
X1042750Y678550D01*
X1042667Y679050D01*
X1042333Y679300D01*
X1040833Y679800D01*
X1040500Y680383D01*
X1040667Y680800D01*
X1041000Y681050D01*
X1041500Y681133D01*
X1042000Y681050D01*
X1042500Y680800D01*
G01X1047100Y681133D02*
Y677800D01*
G01Y682467D02*
X1046933Y682550D01*
Y682717D01*
X1047100Y682800D01*
X1047267Y682717D01*
Y682550D01*
X1047100Y682467D01*
G01X1051533Y676550D02*
X1052117Y676217D01*
X1052783Y676133D01*
X1053367Y676217D01*
X1053867Y676633D01*
X1054200Y677217D01*
Y681133D01*
G01Y680467D02*
X1053867Y680800D01*
X1053367Y681050D01*
X1052783Y681133D01*
X1052117Y680967D01*
X1051700Y680633D01*
X1051367Y680050D01*
X1051200Y679467D01*
X1051283Y678967D01*
X1051617Y678383D01*
X1052117Y677967D01*
X1052783Y677800D01*
X1053283Y677883D01*
X1053867Y678217D01*
X1054200Y678550D01*
G01X1056883Y677800D02*
Y681133D01*
G01Y680300D02*
X1057217Y680717D01*
X1057717Y681050D01*
X1058383Y681133D01*
X1058967Y681050D01*
X1059467Y680717D01*
X1059717Y680133D01*
Y677800D01*
G01X956683Y823300D02*
Y828300D01*
G01Y825883D02*
X957100Y826300D01*
X957517Y826550D01*
X958183Y826633D01*
X958683Y826550D01*
X959267Y826217D01*
X959517Y825717D01*
Y823300D01*
G01X965200D02*
Y826633D01*
G01Y826050D02*
X964867Y826383D01*
X964367Y826550D01*
X963783Y826633D01*
X963200Y826467D01*
X962700Y826133D01*
X962367Y825633D01*
X962200Y824967D01*
X962367Y824300D01*
X962700Y823800D01*
X963200Y823467D01*
X963783Y823300D01*
X964367Y823383D01*
X964867Y823633D01*
X965200Y823967D01*
G01X969300Y823300D02*
Y828300D01*
G01X974400Y823300D02*
Y827550D01*
X974567Y827967D01*
X974900Y828217D01*
X975400Y828300D01*
X975900Y828133D01*
X976150Y827717D01*
G01X975150Y826300D02*
X973483D01*
G01X984600Y821633D02*
Y826633D01*
G01Y825883D02*
X985017Y826300D01*
X985433Y826550D01*
X986100Y826633D01*
X986683Y826550D01*
X987267Y826133D01*
X987517Y825550D01*
X987600Y824967D01*
X987517Y824383D01*
X987267Y823800D01*
X986767Y823467D01*
X986100Y823300D01*
X985517Y823383D01*
X984933Y823633D01*
X984600Y823967D01*
G01X991700Y823300D02*
Y828300D01*
G01X995883Y826633D02*
Y824300D01*
X996217Y823717D01*
X996717Y823383D01*
X997300Y823300D01*
X997883Y823383D01*
X998383Y823717D01*
X998717Y824300D01*
G01Y823300D02*
Y826633D01*
G01X1001733Y822050D02*
X1002317Y821717D01*
X1002983Y821633D01*
X1003567Y821717D01*
X1004067Y822133D01*
X1004400Y822717D01*
Y826633D01*
G01Y825967D02*
X1004067Y826300D01*
X1003567Y826550D01*
X1002983Y826633D01*
X1002317Y826467D01*
X1001900Y826133D01*
X1001567Y825550D01*
X1001400Y824967D01*
X1001483Y824467D01*
X1001817Y823883D01*
X1002317Y823467D01*
X1002983Y823300D01*
X1003483Y823383D01*
X1004067Y823717D01*
X1004400Y824050D01*
G01X1007333Y822050D02*
X1007917Y821717D01*
X1008583Y821633D01*
X1009167Y821717D01*
X1009667Y822133D01*
X1010000Y822717D01*
Y826633D01*
G01Y825967D02*
X1009667Y826300D01*
X1009167Y826550D01*
X1008583Y826633D01*
X1007917Y826467D01*
X1007500Y826133D01*
X1007167Y825550D01*
X1007000Y824967D01*
X1007083Y824467D01*
X1007417Y823883D01*
X1007917Y823467D01*
X1008583Y823300D01*
X1009083Y823383D01*
X1009667Y823717D01*
X1010000Y824050D01*
G01X1014100Y826633D02*
Y823300D01*
G01Y827967D02*
X1013933Y828050D01*
Y828217D01*
X1014100Y828300D01*
X1014267Y828217D01*
Y828050D01*
X1014100Y827967D01*
G01X1018283Y823300D02*
Y826633D01*
G01Y825800D02*
X1018617Y826217D01*
X1019117Y826550D01*
X1019783Y826633D01*
X1020367Y826550D01*
X1020867Y826217D01*
X1021117Y825633D01*
Y823300D01*
G01X1024133Y822050D02*
X1024717Y821717D01*
X1025383Y821633D01*
X1025967Y821717D01*
X1026467Y822133D01*
X1026800Y822717D01*
Y826633D01*
G01Y825967D02*
X1026467Y826300D01*
X1025967Y826550D01*
X1025383Y826633D01*
X1024717Y826467D01*
X1024300Y826133D01*
X1023967Y825550D01*
X1023800Y824967D01*
X1023883Y824467D01*
X1024217Y823883D01*
X1024717Y823467D01*
X1025383Y823300D01*
X1025883Y823383D01*
X1026467Y823717D01*
X1026800Y824050D01*
G01X1022600Y156300D02*
Y161300D01*
X1019517Y157717D01*
X1023683D01*
G01X1025367Y157050D02*
X1025867Y156633D01*
X1026450Y156383D01*
X1027200Y156300D01*
X1027950Y156467D01*
X1028533Y156800D01*
X1028950Y157383D01*
X1029033Y158050D01*
X1028867Y158717D01*
X1028450Y159133D01*
X1027867Y159467D01*
X1027283Y159550D01*
X1026700Y159467D01*
X1025950Y159133D01*
X1026200Y161300D01*
X1028450D01*
G01X1022850Y272883D02*
X1023267Y272550D01*
X1023850Y272300D01*
X1024350D01*
X1024850Y272467D01*
X1025183Y272717D01*
X1025350Y273050D01*
X1025267Y273550D01*
X1024933Y273800D01*
X1023433Y274300D01*
X1023100Y274883D01*
X1023267Y275300D01*
X1023600Y275550D01*
X1024100Y275633D01*
X1024600Y275550D01*
X1025100Y275300D01*
G01X1029700Y277300D02*
Y272300D01*
G01X1028533Y275633D02*
X1030867D01*
G01X1033883D02*
Y273300D01*
X1034217Y272717D01*
X1034717Y272383D01*
X1035300Y272300D01*
X1035883Y272383D01*
X1036383Y272717D01*
X1036717Y273300D01*
G01Y272300D02*
Y275633D01*
G01X1039400Y272300D02*
Y277300D01*
G01Y274800D02*
X1039817Y275300D01*
X1040317Y275550D01*
X1040817Y275633D01*
X1041567Y275467D01*
X1042067Y275133D01*
X1042400Y274550D01*
Y273883D01*
X1042233Y273217D01*
X1041900Y272717D01*
X1041317Y272383D01*
X1040817Y272300D01*
X1040317Y272383D01*
X1039817Y272633D01*
X1039400Y273050D01*
G01X1052100Y272300D02*
Y277300D01*
G01X1056450Y274550D02*
X1059117D01*
X1058867Y275133D01*
X1058450Y275467D01*
X1057867Y275633D01*
X1057283Y275550D01*
X1056783Y275300D01*
X1056450Y274717D01*
X1056283Y274217D01*
Y273717D01*
X1056450Y273217D01*
X1056867Y272717D01*
X1057367Y272383D01*
X1057950Y272300D01*
X1058533Y272467D01*
X1059117Y272967D01*
G01X1061883Y272300D02*
Y275633D01*
G01Y274800D02*
X1062217Y275217D01*
X1062717Y275550D01*
X1063383Y275633D01*
X1063967Y275550D01*
X1064467Y275217D01*
X1064717Y274633D01*
Y272300D01*
G01X1067733Y271050D02*
X1068317Y270717D01*
X1068983Y270633D01*
X1069567Y270717D01*
X1070067Y271133D01*
X1070400Y271717D01*
Y275633D01*
G01Y274967D02*
X1070067Y275300D01*
X1069567Y275550D01*
X1068983Y275633D01*
X1068317Y275467D01*
X1067900Y275133D01*
X1067567Y274550D01*
X1067400Y273967D01*
X1067483Y273467D01*
X1067817Y272883D01*
X1068317Y272467D01*
X1068983Y272300D01*
X1069483Y272383D01*
X1070067Y272717D01*
X1070400Y273050D01*
G01X1074500Y277300D02*
Y272300D01*
G01X1073333Y275633D02*
X1075667D01*
G01X1078683Y272300D02*
Y277300D01*
G01Y274883D02*
X1079100Y275300D01*
X1079517Y275550D01*
X1080183Y275633D01*
X1080683Y275550D01*
X1081267Y275217D01*
X1081517Y274717D01*
Y272300D01*
G01X1084617Y273217D02*
X1086783D01*
G01Y274717D02*
X1084617D01*
G01X1089717Y274383D02*
X1090300Y274967D01*
X1090800Y275300D01*
X1091467Y275467D01*
X1092050Y275300D01*
X1092467Y274967D01*
X1092800Y274467D01*
X1092883Y273883D01*
X1092800Y273383D01*
X1092467Y272883D01*
X1091967Y272467D01*
X1091383Y272300D01*
X1090717Y272467D01*
X1090133Y272967D01*
X1089800Y273717D01*
X1089717Y274550D01*
X1089883Y275633D01*
X1090133Y276217D01*
X1090550Y276800D01*
X1091133Y277217D01*
X1091717Y277300D01*
X1092300Y277133D01*
X1092717Y276717D01*
G01X1095983Y273967D02*
X1097983D01*
G01X1096900Y275050D02*
Y272883D01*
G01X1101000Y272133D02*
X1104000Y277300D01*
G01X1107017Y273967D02*
X1109183D01*
G01X1111867Y273050D02*
X1112367Y272633D01*
X1112950Y272383D01*
X1113700Y272300D01*
X1114450Y272467D01*
X1115033Y272800D01*
X1115450Y273383D01*
X1115533Y274050D01*
X1115367Y274717D01*
X1114950Y275133D01*
X1114367Y275467D01*
X1113783Y275550D01*
X1113200Y275467D01*
X1112450Y275133D01*
X1112700Y277300D01*
X1114950D01*
G01X1116800Y272300D02*
Y275633D01*
G01Y274717D02*
X1117050Y275133D01*
X1117467Y275467D01*
X1118050Y275633D01*
X1118633Y275467D01*
X1119050Y275133D01*
X1119300Y274717D01*
Y272300D01*
G01Y274717D02*
X1119550Y275133D01*
X1119967Y275467D01*
X1120550Y275633D01*
X1121133Y275467D01*
X1121550Y275133D01*
X1121800Y274633D01*
Y272300D01*
G01X1124900Y275633D02*
Y272300D01*
G01Y276967D02*
X1124733Y277050D01*
Y277217D01*
X1124900Y277300D01*
X1125067Y277217D01*
Y277050D01*
X1124900Y276967D01*
G01X1130500Y272300D02*
Y277300D01*
G01X1014433Y303300D02*
Y298300D01*
X1017767D01*
G01X1020283D02*
Y301633D01*
G01Y300800D02*
X1020617Y301217D01*
X1021117Y301550D01*
X1021783Y301633D01*
X1022367Y301550D01*
X1022867Y301217D01*
X1023117Y300633D01*
Y298300D01*
G01X1016433Y344300D02*
Y339300D01*
X1019767D01*
G01X1022450Y342633D02*
X1024950Y339300D01*
G01Y342633D02*
X1022450Y339300D01*
G01X1002867Y437873D02*
X1006533Y441540D01*
G01X1004700Y442207D02*
Y437207D01*
G01X1006533Y437873D02*
X1002867Y441540D01*
G01X1002200Y439707D02*
X1007200D01*
G01X1009883Y436373D02*
X1009050Y437207D01*
X1008633Y438040D01*
Y441373D01*
X1009050Y442207D01*
X1009883Y443040D01*
G01X1014067Y438790D02*
X1014567Y438373D01*
X1015150Y438123D01*
X1015900Y438040D01*
X1016650Y438207D01*
X1017233Y438540D01*
X1017650Y439123D01*
X1017733Y439790D01*
X1017567Y440457D01*
X1017150Y440873D01*
X1016567Y441207D01*
X1015983Y441290D01*
X1015400Y441207D01*
X1014650Y440873D01*
X1014900Y443040D01*
X1017150D01*
G01X1021500Y437873D02*
X1021333Y437957D01*
Y438123D01*
X1021500Y438207D01*
X1021667Y438123D01*
Y437957D01*
X1021500Y437873D01*
G01X1027100Y438040D02*
Y443040D01*
X1026100Y442040D01*
G01Y438040D02*
X1028100D01*
G01X1033117Y436373D02*
X1033950Y437207D01*
X1034367Y438040D01*
Y441373D01*
X1033950Y442207D01*
X1033117Y443040D01*
G01X1007600Y644800D02*
Y639800D01*
G01X1006433Y643133D02*
X1008767D01*
G01X1011783Y639800D02*
Y644800D01*
G01Y642383D02*
X1012200Y642800D01*
X1012617Y643050D01*
X1013283Y643133D01*
X1013783Y643050D01*
X1014367Y642717D01*
X1014617Y642217D01*
Y639800D01*
G01X1017550Y642050D02*
X1020217D01*
X1019967Y642633D01*
X1019550Y642967D01*
X1018967Y643133D01*
X1018383Y643050D01*
X1017883Y642800D01*
X1017550Y642217D01*
X1017383Y641717D01*
Y641217D01*
X1017550Y640717D01*
X1017967Y640217D01*
X1018467Y639883D01*
X1019050Y639800D01*
X1019633Y639967D01*
X1020217Y640467D01*
G01X1030000Y639800D02*
X1029500Y639883D01*
X1029000Y640217D01*
X1028667Y640800D01*
X1028500Y641467D01*
X1028667Y642133D01*
X1029000Y642717D01*
X1029500Y643050D01*
X1030000Y643133D01*
X1030500Y643050D01*
X1031000Y642717D01*
X1031333Y642133D01*
X1031417Y641467D01*
X1031333Y640800D01*
X1031000Y640217D01*
X1030500Y639883D01*
X1030000Y639800D01*
G01X1035600Y644800D02*
Y639800D01*
G01X1034433Y643133D02*
X1036767D01*
G01X1039783Y639800D02*
Y644800D01*
G01Y642383D02*
X1040200Y642800D01*
X1040617Y643050D01*
X1041283Y643133D01*
X1041783Y643050D01*
X1042367Y642717D01*
X1042617Y642217D01*
Y639800D01*
G01X1045550Y642050D02*
X1048217D01*
X1047967Y642633D01*
X1047550Y642967D01*
X1046967Y643133D01*
X1046383Y643050D01*
X1045883Y642800D01*
X1045550Y642217D01*
X1045383Y641717D01*
Y641217D01*
X1045550Y640717D01*
X1045967Y640217D01*
X1046467Y639883D01*
X1047050Y639800D01*
X1047633Y639967D01*
X1048217Y640467D01*
G01X1051233Y639800D02*
Y643133D01*
G01Y642467D02*
X1051650Y642800D01*
X1052067Y643050D01*
X1052650Y643133D01*
X1053067Y643050D01*
X1053567Y642800D01*
G01X1062350Y640383D02*
X1062767Y640050D01*
X1063350Y639800D01*
X1063850D01*
X1064350Y639967D01*
X1064683Y640217D01*
X1064850Y640550D01*
X1064767Y641050D01*
X1064433Y641300D01*
X1062933Y641800D01*
X1062600Y642383D01*
X1062767Y642800D01*
X1063100Y643050D01*
X1063600Y643133D01*
X1064100Y643050D01*
X1064600Y642800D01*
G01X1069200Y643133D02*
Y639800D01*
G01Y644467D02*
X1069033Y644550D01*
Y644717D01*
X1069200Y644800D01*
X1069367Y644717D01*
Y644550D01*
X1069200Y644467D01*
G01X1076300Y644800D02*
Y639800D01*
G01Y640550D02*
X1075967Y640133D01*
X1075467Y639883D01*
X1074883Y639800D01*
X1074217Y639967D01*
X1073717Y640383D01*
X1073383Y640883D01*
X1073300Y641467D01*
X1073383Y642050D01*
X1073717Y642550D01*
X1074217Y642967D01*
X1074883Y643133D01*
X1075467Y643050D01*
X1075883Y642883D01*
X1076300Y642550D01*
G01X1079150Y642050D02*
X1081817D01*
X1081567Y642633D01*
X1081150Y642967D01*
X1080567Y643133D01*
X1079983Y643050D01*
X1079483Y642800D01*
X1079150Y642217D01*
X1078983Y641717D01*
Y641217D01*
X1079150Y640717D01*
X1079567Y640217D01*
X1080067Y639883D01*
X1080650Y639800D01*
X1081233Y639967D01*
X1081817Y640467D01*
G01X1089517Y643133D02*
X1090517Y639800D01*
X1091600Y643133D01*
X1092683Y639800D01*
X1093683Y643133D01*
G01X1097200D02*
Y639800D01*
G01Y644467D02*
X1097033Y644550D01*
Y644717D01*
X1097200Y644800D01*
X1097367Y644717D01*
Y644550D01*
X1097200Y644467D01*
G01X1102800Y644800D02*
Y639800D01*
G01X1101633Y643133D02*
X1103967D01*
G01X1106983Y639800D02*
Y644800D01*
G01Y642383D02*
X1107400Y642800D01*
X1107817Y643050D01*
X1108483Y643133D01*
X1108983Y643050D01*
X1109567Y642717D01*
X1109817Y642217D01*
Y639800D01*
G01X1114000D02*
X1113500Y639883D01*
X1113000Y640217D01*
X1112667Y640800D01*
X1112500Y641467D01*
X1112667Y642133D01*
X1113000Y642717D01*
X1113500Y643050D01*
X1114000Y643133D01*
X1114500Y643050D01*
X1115000Y642717D01*
X1115333Y642133D01*
X1115417Y641467D01*
X1115333Y640800D01*
X1115000Y640217D01*
X1114500Y639883D01*
X1114000Y639800D01*
G01X1118183Y643133D02*
Y640800D01*
X1118517Y640217D01*
X1119017Y639883D01*
X1119600Y639800D01*
X1120183Y639883D01*
X1120683Y640217D01*
X1121017Y640800D01*
G01Y639800D02*
Y643133D01*
G01X1125200Y644800D02*
Y639800D01*
G01X1124033Y643133D02*
X1126367D01*
G01X1042183Y111883D02*
X1042767Y111467D01*
X1043433Y111300D01*
X1044100Y111467D01*
X1044683Y111967D01*
X1045100Y112717D01*
X1045267Y113467D01*
Y114383D01*
X1045100Y115133D01*
X1044683Y115800D01*
X1044183Y116133D01*
X1043600Y116300D01*
X1042933Y116133D01*
X1042433Y115800D01*
X1042100Y115300D01*
X1041933Y114633D01*
X1042100Y114050D01*
X1042517Y113467D01*
X1043017Y113133D01*
X1043600Y113050D01*
X1044267Y113217D01*
X1044767Y113633D01*
X1045267Y114383D01*
G01X1047617Y113383D02*
X1048200Y113967D01*
X1048700Y114300D01*
X1049367Y114467D01*
X1049950Y114300D01*
X1050367Y113967D01*
X1050700Y113467D01*
X1050783Y112883D01*
X1050700Y112383D01*
X1050367Y111883D01*
X1049867Y111467D01*
X1049283Y111300D01*
X1048617Y111467D01*
X1048033Y111967D01*
X1047700Y112717D01*
X1047617Y113550D01*
X1047783Y114633D01*
X1048033Y115217D01*
X1048450Y115800D01*
X1049033Y116217D01*
X1049617Y116300D01*
X1050200Y116133D01*
X1050617Y115717D01*
G01X1042600Y823300D02*
Y827550D01*
X1042767Y827967D01*
X1043100Y828217D01*
X1043600Y828300D01*
X1044100Y828133D01*
X1044350Y827717D01*
G01X1043350Y826300D02*
X1041683D01*
G01X1047283Y826633D02*
Y824300D01*
X1047617Y823717D01*
X1048117Y823383D01*
X1048700Y823300D01*
X1049283Y823383D01*
X1049783Y823717D01*
X1050117Y824300D01*
G01Y823300D02*
Y826633D01*
G01X1054300Y823300D02*
Y828300D01*
G01X1059900Y823300D02*
Y828300D01*
G01X1069600Y821633D02*
Y826633D01*
G01Y825883D02*
X1070017Y826300D01*
X1070433Y826550D01*
X1071100Y826633D01*
X1071683Y826550D01*
X1072267Y826133D01*
X1072517Y825550D01*
X1072600Y824967D01*
X1072517Y824383D01*
X1072267Y823800D01*
X1071767Y823467D01*
X1071100Y823300D01*
X1070517Y823383D01*
X1069933Y823633D01*
X1069600Y823967D01*
G01X1076700Y823300D02*
Y828300D01*
G01X1080883Y826633D02*
Y824300D01*
X1081217Y823717D01*
X1081717Y823383D01*
X1082300Y823300D01*
X1082883Y823383D01*
X1083383Y823717D01*
X1083717Y824300D01*
G01Y823300D02*
Y826633D01*
G01X1086733Y822050D02*
X1087317Y821717D01*
X1087983Y821633D01*
X1088567Y821717D01*
X1089067Y822133D01*
X1089400Y822717D01*
Y826633D01*
G01Y825967D02*
X1089067Y826300D01*
X1088567Y826550D01*
X1087983Y826633D01*
X1087317Y826467D01*
X1086900Y826133D01*
X1086567Y825550D01*
X1086400Y824967D01*
X1086483Y824467D01*
X1086817Y823883D01*
X1087317Y823467D01*
X1087983Y823300D01*
X1088483Y823383D01*
X1089067Y823717D01*
X1089400Y824050D01*
G01X1092333Y822050D02*
X1092917Y821717D01*
X1093583Y821633D01*
X1094167Y821717D01*
X1094667Y822133D01*
X1095000Y822717D01*
Y826633D01*
G01Y825967D02*
X1094667Y826300D01*
X1094167Y826550D01*
X1093583Y826633D01*
X1092917Y826467D01*
X1092500Y826133D01*
X1092167Y825550D01*
X1092000Y824967D01*
X1092083Y824467D01*
X1092417Y823883D01*
X1092917Y823467D01*
X1093583Y823300D01*
X1094083Y823383D01*
X1094667Y823717D01*
X1095000Y824050D01*
G01X1099100Y826633D02*
Y823300D01*
G01Y827967D02*
X1098933Y828050D01*
Y828217D01*
X1099100Y828300D01*
X1099267Y828217D01*
Y828050D01*
X1099100Y827967D01*
G01X1103283Y823300D02*
Y826633D01*
G01Y825800D02*
X1103617Y826217D01*
X1104117Y826550D01*
X1104783Y826633D01*
X1105367Y826550D01*
X1105867Y826217D01*
X1106117Y825633D01*
Y823300D01*
G01X1109133Y822050D02*
X1109717Y821717D01*
X1110383Y821633D01*
X1110967Y821717D01*
X1111467Y822133D01*
X1111800Y822717D01*
Y826633D01*
G01Y825967D02*
X1111467Y826300D01*
X1110967Y826550D01*
X1110383Y826633D01*
X1109717Y826467D01*
X1109300Y826133D01*
X1108967Y825550D01*
X1108800Y824967D01*
X1108883Y824467D01*
X1109217Y823883D01*
X1109717Y823467D01*
X1110383Y823300D01*
X1110883Y823383D01*
X1111467Y823717D01*
X1111800Y824050D01*
G01X1069600Y884780D02*
Y879780D01*
G01X1067683Y884780D02*
X1071517D01*
G01X1073117Y883113D02*
X1074117Y879780D01*
X1075200Y883113D01*
X1076283Y879780D01*
X1077283Y883113D01*
G01X1080800D02*
Y879780D01*
G01Y884447D02*
X1080633Y884530D01*
Y884697D01*
X1080800Y884780D01*
X1080967Y884697D01*
Y884530D01*
X1080800Y884447D01*
G01X1085150Y880363D02*
X1085567Y880030D01*
X1086150Y879780D01*
X1086650D01*
X1087150Y879947D01*
X1087483Y880197D01*
X1087650Y880530D01*
X1087567Y881030D01*
X1087233Y881280D01*
X1085733Y881780D01*
X1085400Y882363D01*
X1085567Y882780D01*
X1085900Y883030D01*
X1086400Y883113D01*
X1086900Y883030D01*
X1087400Y882780D01*
G01X1092000Y884780D02*
Y879780D01*
G01X1090833Y883113D02*
X1093167D01*
G01X1104700Y879780D02*
Y883113D01*
G01Y882530D02*
X1104367Y882863D01*
X1103867Y883030D01*
X1103283Y883113D01*
X1102700Y882947D01*
X1102200Y882613D01*
X1101867Y882113D01*
X1101700Y881447D01*
X1101867Y880780D01*
X1102200Y880280D01*
X1102700Y879947D01*
X1103283Y879780D01*
X1103867Y879863D01*
X1104367Y880113D01*
X1104700Y880447D01*
G01X1107383Y879780D02*
Y883113D01*
G01Y882280D02*
X1107717Y882697D01*
X1108217Y883030D01*
X1108883Y883113D01*
X1109467Y883030D01*
X1109967Y882697D01*
X1110217Y882113D01*
Y879780D01*
G01X1115900Y884780D02*
Y879780D01*
G01Y880530D02*
X1115567Y880113D01*
X1115067Y879863D01*
X1114483Y879780D01*
X1113817Y879947D01*
X1113317Y880363D01*
X1112983Y880863D01*
X1112900Y881447D01*
X1112983Y882030D01*
X1113317Y882530D01*
X1113817Y882947D01*
X1114483Y883113D01*
X1115067Y883030D01*
X1115483Y882863D01*
X1115900Y882530D01*
G01X1124100Y879780D02*
Y884780D01*
G01Y882280D02*
X1124517Y882780D01*
X1125017Y883030D01*
X1125517Y883113D01*
X1126267Y882947D01*
X1126767Y882613D01*
X1127100Y882030D01*
Y881363D01*
X1126933Y880697D01*
X1126600Y880197D01*
X1126017Y879863D01*
X1125517Y879780D01*
X1125017Y879863D01*
X1124517Y880113D01*
X1124100Y880530D01*
G01X1131200Y879780D02*
X1130700Y879863D01*
X1130200Y880197D01*
X1129867Y880780D01*
X1129700Y881447D01*
X1129867Y882113D01*
X1130200Y882697D01*
X1130700Y883030D01*
X1131200Y883113D01*
X1131700Y883030D01*
X1132200Y882697D01*
X1132533Y882113D01*
X1132617Y881447D01*
X1132533Y880780D01*
X1132200Y880197D01*
X1131700Y879863D01*
X1131200Y879780D01*
G01X1134717Y883113D02*
X1135717Y879780D01*
X1136800Y883113D01*
X1137883Y879780D01*
X1138883Y883113D01*
G01X1061600Y939410D02*
Y870910D01*
G01X1071100Y900300D02*
X1072767D01*
Y898800D01*
X1072267Y898300D01*
X1071683Y897967D01*
X1070850Y897800D01*
X1070017Y897967D01*
X1069433Y898300D01*
X1068933Y898800D01*
X1068600Y899383D01*
X1068433Y900050D01*
Y900633D01*
X1068600Y901133D01*
X1068933Y901717D01*
X1069433Y902217D01*
X1069933Y902550D01*
X1070600Y902800D01*
X1071183D01*
X1071850Y902633D01*
X1072350Y902300D01*
G01X1074700Y897633D02*
X1077700Y902800D01*
G01X1080217Y897800D02*
Y902800D01*
X1083383D01*
G01X1082217Y900383D02*
X1080217D01*
G01X1091250Y898467D02*
X1091917Y898050D01*
X1092667Y897800D01*
X1093333D01*
X1094000Y898050D01*
X1094500Y898467D01*
X1094750Y899050D01*
X1094583Y899633D01*
X1094167Y900133D01*
X1093417Y900467D01*
X1092417Y900633D01*
X1091833Y900967D01*
X1091583Y901550D01*
X1091750Y902133D01*
X1092167Y902550D01*
X1092750Y902800D01*
X1093333D01*
X1093917Y902633D01*
X1094417Y902217D01*
G01X1098600Y897800D02*
Y902800D01*
G01X1104200Y897800D02*
X1103700Y897883D01*
X1103200Y898217D01*
X1102867Y898800D01*
X1102700Y899467D01*
X1102867Y900133D01*
X1103200Y900717D01*
X1103700Y901050D01*
X1104200Y901133D01*
X1104700Y901050D01*
X1105200Y900717D01*
X1105533Y900133D01*
X1105617Y899467D01*
X1105533Y898800D01*
X1105200Y898217D01*
X1104700Y897883D01*
X1104200Y897800D01*
G01X1109800Y902800D02*
Y897800D01*
G01X1108633Y901133D02*
X1110967D01*
G01X1069350Y915050D02*
X1072017D01*
X1071767Y915633D01*
X1071350Y915967D01*
X1070767Y916133D01*
X1070183Y916050D01*
X1069683Y915800D01*
X1069350Y915217D01*
X1069183Y914717D01*
Y914217D01*
X1069350Y913717D01*
X1069767Y913217D01*
X1070267Y912883D01*
X1070850Y912800D01*
X1071433Y912967D01*
X1072017Y913467D01*
G01X1077700Y917800D02*
Y912800D01*
G01Y913550D02*
X1077367Y913133D01*
X1076867Y912883D01*
X1076283Y912800D01*
X1075617Y912967D01*
X1075117Y913383D01*
X1074783Y913883D01*
X1074700Y914467D01*
X1074783Y915050D01*
X1075117Y915550D01*
X1075617Y915967D01*
X1076283Y916133D01*
X1076867Y916050D01*
X1077283Y915883D01*
X1077700Y915550D01*
G01X1080633Y911550D02*
X1081217Y911217D01*
X1081883Y911133D01*
X1082467Y911217D01*
X1082967Y911633D01*
X1083300Y912217D01*
Y916133D01*
G01Y915467D02*
X1082967Y915800D01*
X1082467Y916050D01*
X1081883Y916133D01*
X1081217Y915967D01*
X1080800Y915633D01*
X1080467Y915050D01*
X1080300Y914467D01*
X1080383Y913967D01*
X1080717Y913383D01*
X1081217Y912967D01*
X1081883Y912800D01*
X1082383Y912883D01*
X1082967Y913217D01*
X1083300Y913550D01*
G01X1086150Y915050D02*
X1088817D01*
X1088567Y915633D01*
X1088150Y915967D01*
X1087567Y916133D01*
X1086983Y916050D01*
X1086483Y915800D01*
X1086150Y915217D01*
X1085983Y914717D01*
Y914217D01*
X1086150Y913717D01*
X1086567Y913217D01*
X1087067Y912883D01*
X1087650Y912800D01*
X1088233Y912967D01*
X1088817Y913467D01*
G01X1098600Y917800D02*
Y912800D01*
G01X1097433Y916133D02*
X1099767D01*
G01X1104200Y912800D02*
X1103700Y912883D01*
X1103200Y913217D01*
X1102867Y913800D01*
X1102700Y914467D01*
X1102867Y915133D01*
X1103200Y915717D01*
X1103700Y916050D01*
X1104200Y916133D01*
X1104700Y916050D01*
X1105200Y915717D01*
X1105533Y915133D01*
X1105617Y914467D01*
X1105533Y913800D01*
X1105200Y913217D01*
X1104700Y912883D01*
X1104200Y912800D01*
G01X1113983D02*
Y917800D01*
G01Y915383D02*
X1114400Y915800D01*
X1114817Y916050D01*
X1115483Y916133D01*
X1115983Y916050D01*
X1116567Y915717D01*
X1116817Y915217D01*
Y912800D01*
G01X1121000D02*
X1120500Y912883D01*
X1120000Y913217D01*
X1119667Y913800D01*
X1119500Y914467D01*
X1119667Y915133D01*
X1120000Y915717D01*
X1120500Y916050D01*
X1121000Y916133D01*
X1121500Y916050D01*
X1122000Y915717D01*
X1122333Y915133D01*
X1122417Y914467D01*
X1122333Y913800D01*
X1122000Y913217D01*
X1121500Y912883D01*
X1121000Y912800D01*
G01X1126600D02*
Y917800D01*
G01X1130950Y915050D02*
X1133617D01*
X1133367Y915633D01*
X1132950Y915967D01*
X1132367Y916133D01*
X1131783Y916050D01*
X1131283Y915800D01*
X1130950Y915217D01*
X1130783Y914717D01*
Y914217D01*
X1130950Y913717D01*
X1131367Y913217D01*
X1131867Y912883D01*
X1132450Y912800D01*
X1133033Y912967D01*
X1133617Y913467D01*
G01X1069350Y931550D02*
X1072017D01*
X1071767Y932133D01*
X1071350Y932467D01*
X1070767Y932633D01*
X1070183Y932550D01*
X1069683Y932300D01*
X1069350Y931717D01*
X1069183Y931217D01*
Y930717D01*
X1069350Y930217D01*
X1069767Y929717D01*
X1070267Y929383D01*
X1070850Y929300D01*
X1071433Y929467D01*
X1072017Y929967D01*
G01X1077700Y934300D02*
Y929300D01*
G01Y930050D02*
X1077367Y929633D01*
X1076867Y929383D01*
X1076283Y929300D01*
X1075617Y929467D01*
X1075117Y929883D01*
X1074783Y930383D01*
X1074700Y930967D01*
X1074783Y931550D01*
X1075117Y932050D01*
X1075617Y932467D01*
X1076283Y932633D01*
X1076867Y932550D01*
X1077283Y932383D01*
X1077700Y932050D01*
G01X1080633Y928050D02*
X1081217Y927717D01*
X1081883Y927633D01*
X1082467Y927717D01*
X1082967Y928133D01*
X1083300Y928717D01*
Y932633D01*
G01Y931967D02*
X1082967Y932300D01*
X1082467Y932550D01*
X1081883Y932633D01*
X1081217Y932467D01*
X1080800Y932133D01*
X1080467Y931550D01*
X1080300Y930967D01*
X1080383Y930467D01*
X1080717Y929883D01*
X1081217Y929467D01*
X1081883Y929300D01*
X1082383Y929383D01*
X1082967Y929717D01*
X1083300Y930050D01*
G01X1086150Y931550D02*
X1088817D01*
X1088567Y932133D01*
X1088150Y932467D01*
X1087567Y932633D01*
X1086983Y932550D01*
X1086483Y932300D01*
X1086150Y931717D01*
X1085983Y931217D01*
Y930717D01*
X1086150Y930217D01*
X1086567Y929717D01*
X1087067Y929383D01*
X1087650Y929300D01*
X1088233Y929467D01*
X1088817Y929967D01*
G01X1098600Y934300D02*
Y929300D01*
G01X1097433Y932633D02*
X1099767D01*
G01X1104200Y929300D02*
X1103700Y929383D01*
X1103200Y929717D01*
X1102867Y930300D01*
X1102700Y930967D01*
X1102867Y931633D01*
X1103200Y932217D01*
X1103700Y932550D01*
X1104200Y932633D01*
X1104700Y932550D01*
X1105200Y932217D01*
X1105533Y931633D01*
X1105617Y930967D01*
X1105533Y930300D01*
X1105200Y929717D01*
X1104700Y929383D01*
X1104200Y929300D01*
G01X1114150Y931550D02*
X1116817D01*
X1116567Y932133D01*
X1116150Y932467D01*
X1115567Y932633D01*
X1114983Y932550D01*
X1114483Y932300D01*
X1114150Y931717D01*
X1113983Y931217D01*
Y930717D01*
X1114150Y930217D01*
X1114567Y929717D01*
X1115067Y929383D01*
X1115650Y929300D01*
X1116233Y929467D01*
X1116817Y929967D01*
G01X1122500Y934300D02*
Y929300D01*
G01Y930050D02*
X1122167Y929633D01*
X1121667Y929383D01*
X1121083Y929300D01*
X1120417Y929467D01*
X1119917Y929883D01*
X1119583Y930383D01*
X1119500Y930967D01*
X1119583Y931550D01*
X1119917Y932050D01*
X1120417Y932467D01*
X1121083Y932633D01*
X1121667Y932550D01*
X1122083Y932383D01*
X1122500Y932050D01*
G01X1125433Y928050D02*
X1126017Y927717D01*
X1126683Y927633D01*
X1127267Y927717D01*
X1127767Y928133D01*
X1128100Y928717D01*
Y932633D01*
G01Y931967D02*
X1127767Y932300D01*
X1127267Y932550D01*
X1126683Y932633D01*
X1126017Y932467D01*
X1125600Y932133D01*
X1125267Y931550D01*
X1125100Y930967D01*
X1125183Y930467D01*
X1125517Y929883D01*
X1126017Y929467D01*
X1126683Y929300D01*
X1127183Y929383D01*
X1127767Y929717D01*
X1128100Y930050D01*
G01X1130950Y931550D02*
X1133617D01*
X1133367Y932133D01*
X1132950Y932467D01*
X1132367Y932633D01*
X1131783Y932550D01*
X1131283Y932300D01*
X1130950Y931717D01*
X1130783Y931217D01*
Y930717D01*
X1130950Y930217D01*
X1131367Y929717D01*
X1131867Y929383D01*
X1132450Y929300D01*
X1133033Y929467D01*
X1133617Y929967D01*
G01X1062100Y908300D02*
X1456600D01*
G01X1062100Y923300D02*
X1456600D01*
G01X1109267Y94300D02*
Y99300D01*
X1110933D01*
X1111600Y99050D01*
X1112100Y98717D01*
X1112517Y98217D01*
X1112850Y97633D01*
X1112933Y96800D01*
X1112850Y95967D01*
X1112517Y95383D01*
X1112100Y94883D01*
X1111600Y94550D01*
X1110933Y94300D01*
X1109267D01*
G01X1116700D02*
Y99300D01*
X1115700Y98300D01*
G01Y94300D02*
X1117700D01*
G01X1120717Y96383D02*
X1121300Y96967D01*
X1121800Y97300D01*
X1122467Y97467D01*
X1123050Y97300D01*
X1123467Y96967D01*
X1123800Y96467D01*
X1123883Y95883D01*
X1123800Y95383D01*
X1123467Y94883D01*
X1122967Y94467D01*
X1122383Y94300D01*
X1121717Y94467D01*
X1121133Y94967D01*
X1120800Y95717D01*
X1120717Y96550D01*
X1120883Y97633D01*
X1121133Y98217D01*
X1121550Y98800D01*
X1122133Y99217D01*
X1122717Y99300D01*
X1123300Y99133D01*
X1123717Y98717D01*
G01X1127900Y94133D02*
X1127733Y94217D01*
Y94383D01*
X1127900Y94467D01*
X1128067Y94383D01*
Y94217D01*
X1127900Y94133D01*
G01Y96383D02*
X1127733Y96467D01*
Y96633D01*
X1127900Y96717D01*
X1128067Y96633D01*
Y96467D01*
X1127900Y96383D01*
G01X1131667Y94300D02*
Y99300D01*
X1133333D01*
X1134000Y99050D01*
X1134500Y98717D01*
X1134917Y98217D01*
X1135250Y97633D01*
X1135333Y96800D01*
X1135250Y95967D01*
X1134917Y95383D01*
X1134500Y94883D01*
X1134000Y94550D01*
X1133333Y94300D01*
X1131667D01*
G01X1139100Y97633D02*
Y94300D01*
G01Y98967D02*
X1138933Y99050D01*
Y99217D01*
X1139100Y99300D01*
X1139267Y99217D01*
Y99050D01*
X1139100Y98967D01*
G01X1146200Y94300D02*
Y97633D01*
G01Y97050D02*
X1145867Y97383D01*
X1145367Y97550D01*
X1144783Y97633D01*
X1144200Y97467D01*
X1143700Y97133D01*
X1143367Y96633D01*
X1143200Y95967D01*
X1143367Y95300D01*
X1143700Y94800D01*
X1144200Y94467D01*
X1144783Y94300D01*
X1145367Y94383D01*
X1145867Y94633D01*
X1146200Y94967D01*
G01X1147800Y94300D02*
Y97633D01*
G01Y96717D02*
X1148050Y97133D01*
X1148467Y97467D01*
X1149050Y97633D01*
X1149633Y97467D01*
X1150050Y97133D01*
X1150300Y96717D01*
Y94300D01*
G01Y96717D02*
X1150550Y97133D01*
X1150967Y97467D01*
X1151550Y97633D01*
X1152133Y97467D01*
X1152550Y97133D01*
X1152800Y96633D01*
Y94300D01*
G01X1154650Y96550D02*
X1157317D01*
X1157067Y97133D01*
X1156650Y97467D01*
X1156067Y97633D01*
X1155483Y97550D01*
X1154983Y97300D01*
X1154650Y96717D01*
X1154483Y96217D01*
Y95717D01*
X1154650Y95217D01*
X1155067Y94717D01*
X1155567Y94383D01*
X1156150Y94300D01*
X1156733Y94467D01*
X1157317Y94967D01*
G01X1161500Y99300D02*
Y94300D01*
G01X1160333Y97633D02*
X1162667D01*
G01X1165850Y96550D02*
X1168517D01*
X1168267Y97133D01*
X1167850Y97467D01*
X1167267Y97633D01*
X1166683Y97550D01*
X1166183Y97300D01*
X1165850Y96717D01*
X1165683Y96217D01*
Y95717D01*
X1165850Y95217D01*
X1166267Y94717D01*
X1166767Y94383D01*
X1167350Y94300D01*
X1167933Y94467D01*
X1168517Y94967D01*
G01X1171533Y94300D02*
Y97633D01*
G01Y96967D02*
X1171950Y97300D01*
X1172367Y97550D01*
X1172950Y97633D01*
X1173367Y97550D01*
X1173867Y97300D01*
G01X1183900Y94300D02*
Y99300D01*
X1182900Y98300D01*
G01Y94300D02*
X1184900D01*
G01X1187917Y96383D02*
X1188500Y96967D01*
X1189000Y97300D01*
X1189667Y97467D01*
X1190250Y97300D01*
X1190667Y96967D01*
X1191000Y96467D01*
X1191083Y95883D01*
X1191000Y95383D01*
X1190667Y94883D01*
X1190167Y94467D01*
X1189583Y94300D01*
X1188917Y94467D01*
X1188333Y94967D01*
X1188000Y95717D01*
X1187917Y96550D01*
X1188083Y97633D01*
X1188333Y98217D01*
X1188750Y98800D01*
X1189333Y99217D01*
X1189917Y99300D01*
X1190500Y99133D01*
X1190917Y98717D01*
G01X1192600Y94300D02*
Y97633D01*
G01Y96717D02*
X1192850Y97133D01*
X1193267Y97467D01*
X1193850Y97633D01*
X1194433Y97467D01*
X1194850Y97133D01*
X1195100Y96717D01*
Y94300D01*
G01Y96717D02*
X1195350Y97133D01*
X1195767Y97467D01*
X1196350Y97633D01*
X1196933Y97467D01*
X1197350Y97133D01*
X1197600Y96633D01*
Y94300D01*
G01X1200700Y97633D02*
Y94300D01*
G01Y98967D02*
X1200533Y99050D01*
Y99217D01*
X1200700Y99300D01*
X1200867Y99217D01*
Y99050D01*
X1200700Y98967D01*
G01X1206300Y94300D02*
Y99300D01*
G01X1094267Y105300D02*
X1090933D01*
Y110300D01*
X1094267D01*
G01X1092933Y107883D02*
X1090933D01*
G01X1096950Y108633D02*
X1099450Y105300D01*
G01Y108633D02*
X1096950Y105300D01*
G01X1103800Y105133D02*
X1103633Y105217D01*
Y105383D01*
X1103800Y105467D01*
X1103967Y105383D01*
Y105217D01*
X1103800Y105133D01*
G01X1107650Y105300D02*
Y110300D01*
G01X1111150D02*
Y105300D01*
G01Y107800D02*
X1107650D01*
G01X1113333Y105300D02*
Y110300D01*
X1115417D01*
X1116083Y110050D01*
X1116500Y109717D01*
X1116667Y109050D01*
X1116500Y108383D01*
X1116000Y107967D01*
X1115417Y107717D01*
X1113333D01*
G01X1115417D02*
X1116667Y105300D01*
G01X1122267D02*
X1118933D01*
Y110300D01*
X1122267D01*
G01X1120933Y107883D02*
X1118933D01*
G01X1127200Y105300D02*
Y110300D01*
X1124117Y106717D01*
X1128283D01*
G01X1129967Y106050D02*
X1130467Y105633D01*
X1131050Y105383D01*
X1131800Y105300D01*
X1132550Y105467D01*
X1133133Y105800D01*
X1133550Y106383D01*
X1133633Y107050D01*
X1133467Y107717D01*
X1133050Y108133D01*
X1132467Y108467D01*
X1131883Y108550D01*
X1131300Y108467D01*
X1130550Y108133D01*
X1130800Y110300D01*
X1133050D01*
G01X1135650Y105300D02*
X1139150Y110300D01*
G01X1135650D02*
X1139150Y105300D01*
G01X1141583Y105883D02*
X1142167Y105467D01*
X1142833Y105300D01*
X1143500Y105467D01*
X1144083Y105967D01*
X1144500Y106717D01*
X1144667Y107467D01*
Y108383D01*
X1144500Y109133D01*
X1144083Y109800D01*
X1143583Y110133D01*
X1143000Y110300D01*
X1142333Y110133D01*
X1141833Y109800D01*
X1141500Y109300D01*
X1141333Y108633D01*
X1141500Y108050D01*
X1141917Y107467D01*
X1142417Y107133D01*
X1143000Y107050D01*
X1143667Y107217D01*
X1144167Y107633D01*
X1144667Y108383D01*
G01X1147017Y107383D02*
X1147600Y107967D01*
X1148100Y108300D01*
X1148767Y108467D01*
X1149350Y108300D01*
X1149767Y107967D01*
X1150100Y107467D01*
X1150183Y106883D01*
X1150100Y106383D01*
X1149767Y105883D01*
X1149267Y105467D01*
X1148683Y105300D01*
X1148017Y105467D01*
X1147433Y105967D01*
X1147100Y106717D01*
X1147017Y107550D01*
X1147183Y108633D01*
X1147433Y109217D01*
X1147850Y109800D01*
X1148433Y110217D01*
X1149017Y110300D01*
X1149600Y110133D01*
X1150017Y109717D01*
G01X1153783Y103633D02*
X1152950Y104467D01*
X1152533Y105300D01*
Y108633D01*
X1152950Y109467D01*
X1153783Y110300D01*
G01X1157967Y105300D02*
Y110300D01*
X1159633D01*
X1160300Y110050D01*
X1160800Y109717D01*
X1161217Y109217D01*
X1161550Y108633D01*
X1161633Y107800D01*
X1161550Y106967D01*
X1161217Y106383D01*
X1160800Y105883D01*
X1160300Y105550D01*
X1159633Y105300D01*
X1157967D01*
G01X1165400D02*
Y110300D01*
X1164400Y109300D01*
G01Y105300D02*
X1166400D01*
G01X1169417Y107383D02*
X1170000Y107967D01*
X1170500Y108300D01*
X1171167Y108467D01*
X1171750Y108300D01*
X1172167Y107967D01*
X1172500Y107467D01*
X1172583Y106883D01*
X1172500Y106383D01*
X1172167Y105883D01*
X1171667Y105467D01*
X1171083Y105300D01*
X1170417Y105467D01*
X1169833Y105967D01*
X1169500Y106717D01*
X1169417Y107550D01*
X1169583Y108633D01*
X1169833Y109217D01*
X1170250Y109800D01*
X1170833Y110217D01*
X1171417Y110300D01*
X1172000Y110133D01*
X1172417Y109717D01*
G01X1174850Y105300D02*
X1178350Y110300D01*
G01X1174850D02*
X1178350Y105300D01*
G01X1183200D02*
Y110300D01*
X1180117Y106717D01*
X1184283D01*
G01X1188217Y103633D02*
X1189050Y104467D01*
X1189467Y105300D01*
Y108633D01*
X1189050Y109467D01*
X1188217Y110300D01*
G01X1090933Y154300D02*
Y159300D01*
X1093017D01*
X1093683Y159050D01*
X1094100Y158717D01*
X1094267Y158050D01*
X1094100Y157383D01*
X1093600Y156967D01*
X1093017Y156717D01*
X1090933D01*
G01X1093017D02*
X1094267Y154300D01*
G01X1099867D02*
X1096533D01*
Y159300D01*
X1099867D01*
G01X1098533Y156883D02*
X1096533D01*
G01X1105633Y158883D02*
X1105133Y159133D01*
X1104550Y159300D01*
X1103883D01*
X1103133Y159050D01*
X1102550Y158633D01*
X1102133Y158133D01*
X1101800Y157300D01*
X1101717Y156550D01*
X1101883Y155800D01*
X1102133Y155300D01*
X1102633Y154800D01*
X1103217Y154467D01*
X1103800Y154300D01*
X1104383D01*
X1104967Y154467D01*
X1105467Y154717D01*
X1105883Y155050D01*
G01X1109400Y159300D02*
Y154300D01*
G01X1107483Y159300D02*
X1111317D01*
G01X1112917Y154300D02*
X1115000Y159300D01*
X1117083Y154300D01*
G01X1116333Y156050D02*
X1113667D01*
G01X1118683Y154300D02*
Y159300D01*
X1122517Y154300D01*
Y159300D01*
G01X1126700Y156800D02*
X1128367D01*
Y155300D01*
X1127867Y154800D01*
X1127283Y154467D01*
X1126450Y154300D01*
X1125617Y154467D01*
X1125033Y154800D01*
X1124533Y155300D01*
X1124200Y155883D01*
X1124033Y156550D01*
Y157133D01*
X1124200Y157633D01*
X1124533Y158217D01*
X1125033Y158717D01*
X1125533Y159050D01*
X1126200Y159300D01*
X1126783D01*
X1127450Y159133D01*
X1127950Y158800D01*
G01X1130133Y159300D02*
Y154300D01*
X1133467D01*
G01X1139067D02*
X1135733D01*
Y159300D01*
X1139067D01*
G01X1137733Y156883D02*
X1135733D01*
G01X1146767Y154300D02*
Y159300D01*
X1148433D01*
X1149100Y159050D01*
X1149600Y158717D01*
X1150017Y158217D01*
X1150350Y157633D01*
X1150433Y156800D01*
X1150350Y155967D01*
X1150017Y155383D01*
X1149600Y154883D01*
X1149100Y154550D01*
X1148433Y154300D01*
X1146767D01*
G01X1152533D02*
Y159300D01*
X1154617D01*
X1155283Y159050D01*
X1155700Y158717D01*
X1155867Y158050D01*
X1155700Y157383D01*
X1155200Y156967D01*
X1154617Y156717D01*
X1152533D01*
G01X1154617D02*
X1155867Y154300D01*
G01X1158800Y159300D02*
X1160800D01*
G01X1159800D02*
Y154300D01*
G01X1158800D02*
X1160800D01*
G01X1163733Y159300D02*
Y154300D01*
X1167067D01*
G01X1169333Y159300D02*
Y154300D01*
X1172667D01*
G01X1180450D02*
Y159300D01*
G01X1183950D02*
Y154300D01*
G01Y156800D02*
X1180450D01*
G01X1187800Y154300D02*
X1187133Y154383D01*
X1186550Y154717D01*
X1186050Y155217D01*
X1185717Y155800D01*
X1185550Y156467D01*
Y157133D01*
X1185717Y157800D01*
X1186050Y158383D01*
X1186550Y158883D01*
X1187133Y159217D01*
X1187800Y159300D01*
X1188467Y159217D01*
X1189050Y158883D01*
X1189550Y158383D01*
X1189883Y157800D01*
X1190050Y157133D01*
Y156467D01*
X1189883Y155800D01*
X1189550Y155217D01*
X1189050Y154717D01*
X1188467Y154383D01*
X1187800Y154300D01*
G01X1191733Y159300D02*
Y154300D01*
X1195067D01*
G01X1200667D02*
X1197333D01*
Y159300D01*
X1200667D01*
G01X1199333Y156883D02*
X1197333D01*
G01X1208367Y154300D02*
Y159300D01*
X1210033D01*
X1210700Y159050D01*
X1211200Y158717D01*
X1211617Y158217D01*
X1211950Y157633D01*
X1212033Y156800D01*
X1211950Y155967D01*
X1211617Y155383D01*
X1211200Y154883D01*
X1210700Y154550D01*
X1210033Y154300D01*
X1208367D01*
G01X1217467D02*
X1214133D01*
Y159300D01*
X1217467D01*
G01X1216133Y156883D02*
X1214133D01*
G01X1219817Y154300D02*
Y159300D01*
X1222983D01*
G01X1221817Y156883D02*
X1219817D01*
G01X1226000Y159300D02*
X1228000D01*
G01X1227000D02*
Y154300D01*
G01X1226000D02*
X1228000D01*
G01X1230683D02*
Y159300D01*
X1234517Y154300D01*
Y159300D01*
G01X1239867Y154300D02*
X1236533D01*
Y159300D01*
X1239867D01*
G01X1238533Y156883D02*
X1236533D01*
G01X1135017Y472467D02*
X1135517Y472967D01*
X1136100Y473217D01*
X1136767Y473300D01*
X1137600Y473133D01*
X1138183Y472717D01*
X1138350Y472217D01*
X1138267Y471717D01*
X1137933Y471300D01*
X1136267Y470467D01*
X1135517Y469883D01*
X1135017Y469050D01*
X1134850Y468300D01*
X1138350D01*
G01X1142200Y468133D02*
X1142033Y468217D01*
Y468383D01*
X1142200Y468467D01*
X1142367Y468383D01*
Y468217D01*
X1142200Y468133D01*
G01X1145717Y473300D02*
X1147800Y468300D01*
X1149883Y473300D01*
G01X1153400Y471633D02*
Y468300D01*
G01Y472967D02*
X1153233Y473050D01*
Y473217D01*
X1153400Y473300D01*
X1153567Y473217D01*
Y473050D01*
X1153400Y472967D01*
G01X1160500Y468300D02*
Y471633D01*
G01Y471050D02*
X1160167Y471383D01*
X1159667Y471550D01*
X1159083Y471633D01*
X1158500Y471467D01*
X1158000Y471133D01*
X1157667Y470633D01*
X1157500Y469967D01*
X1157667Y469300D01*
X1158000Y468800D01*
X1158500Y468467D01*
X1159083Y468300D01*
X1159667Y468383D01*
X1160167Y468633D01*
X1160500Y468967D01*
G01X1168950Y468883D02*
X1169367Y468550D01*
X1169950Y468300D01*
X1170450D01*
X1170950Y468467D01*
X1171283Y468717D01*
X1171450Y469050D01*
X1171367Y469550D01*
X1171033Y469800D01*
X1169533Y470300D01*
X1169200Y470883D01*
X1169367Y471300D01*
X1169700Y471550D01*
X1170200Y471633D01*
X1170700Y471550D01*
X1171200Y471300D01*
G01X1174383Y468300D02*
Y473300D01*
G01Y470883D02*
X1174800Y471300D01*
X1175217Y471550D01*
X1175883Y471633D01*
X1176383Y471550D01*
X1176967Y471217D01*
X1177217Y470717D01*
Y468300D01*
G01X1181400D02*
X1180900Y468383D01*
X1180400Y468717D01*
X1180067Y469300D01*
X1179900Y469967D01*
X1180067Y470633D01*
X1180400Y471217D01*
X1180900Y471550D01*
X1181400Y471633D01*
X1181900Y471550D01*
X1182400Y471217D01*
X1182733Y470633D01*
X1182817Y469967D01*
X1182733Y469300D01*
X1182400Y468717D01*
X1181900Y468383D01*
X1181400Y468300D01*
G01X1185583Y471633D02*
Y469300D01*
X1185917Y468717D01*
X1186417Y468383D01*
X1187000Y468300D01*
X1187583Y468383D01*
X1188083Y468717D01*
X1188417Y469300D01*
G01Y468300D02*
Y471633D01*
G01X1192600Y468300D02*
Y473300D01*
G01X1199700D02*
Y468300D01*
G01Y469050D02*
X1199367Y468633D01*
X1198867Y468383D01*
X1198283Y468300D01*
X1197617Y468467D01*
X1197117Y468883D01*
X1196783Y469383D01*
X1196700Y469967D01*
X1196783Y470550D01*
X1197117Y471050D01*
X1197617Y471467D01*
X1198283Y471633D01*
X1198867Y471550D01*
X1199283Y471383D01*
X1199700Y471050D01*
G01X1207900Y468300D02*
Y473300D01*
G01Y470800D02*
X1208317Y471300D01*
X1208817Y471550D01*
X1209317Y471633D01*
X1210067Y471467D01*
X1210567Y471133D01*
X1210900Y470550D01*
Y469883D01*
X1210733Y469217D01*
X1210400Y468717D01*
X1209817Y468383D01*
X1209317Y468300D01*
X1208817Y468383D01*
X1208317Y468633D01*
X1207900Y469050D01*
G01X1213750Y470550D02*
X1216417D01*
X1216167Y471133D01*
X1215750Y471467D01*
X1215167Y471633D01*
X1214583Y471550D01*
X1214083Y471300D01*
X1213750Y470717D01*
X1213583Y470217D01*
Y469717D01*
X1213750Y469217D01*
X1214167Y468717D01*
X1214667Y468383D01*
X1215250Y468300D01*
X1215833Y468467D01*
X1216417Y468967D01*
G01X1224700Y466633D02*
Y471633D01*
G01Y470883D02*
X1225117Y471300D01*
X1225533Y471550D01*
X1226200Y471633D01*
X1226783Y471550D01*
X1227367Y471133D01*
X1227617Y470550D01*
X1227700Y469967D01*
X1227617Y469383D01*
X1227367Y468800D01*
X1226867Y468467D01*
X1226200Y468300D01*
X1225617Y468383D01*
X1225033Y468633D01*
X1224700Y468967D01*
G01X1231800Y468300D02*
Y473300D01*
G01X1235983Y471633D02*
Y469300D01*
X1236317Y468717D01*
X1236817Y468383D01*
X1237400Y468300D01*
X1237983Y468383D01*
X1238483Y468717D01*
X1238817Y469300D01*
G01Y468300D02*
Y471633D01*
G01X1241833Y467050D02*
X1242417Y466717D01*
X1243083Y466633D01*
X1243667Y466717D01*
X1244167Y467133D01*
X1244500Y467717D01*
Y471633D01*
G01Y470967D02*
X1244167Y471300D01*
X1243667Y471550D01*
X1243083Y471633D01*
X1242417Y471467D01*
X1242000Y471133D01*
X1241667Y470550D01*
X1241500Y469967D01*
X1241583Y469467D01*
X1241917Y468883D01*
X1242417Y468467D01*
X1243083Y468300D01*
X1243583Y468383D01*
X1244167Y468717D01*
X1244500Y469050D01*
G01X1247433Y467050D02*
X1248017Y466717D01*
X1248683Y466633D01*
X1249267Y466717D01*
X1249767Y467133D01*
X1250100Y467717D01*
Y471633D01*
G01Y470967D02*
X1249767Y471300D01*
X1249267Y471550D01*
X1248683Y471633D01*
X1248017Y471467D01*
X1247600Y471133D01*
X1247267Y470550D01*
X1247100Y469967D01*
X1247183Y469467D01*
X1247517Y468883D01*
X1248017Y468467D01*
X1248683Y468300D01*
X1249183Y468383D01*
X1249767Y468717D01*
X1250100Y469050D01*
G01X1252950Y470550D02*
X1255617D01*
X1255367Y471133D01*
X1254950Y471467D01*
X1254367Y471633D01*
X1253783Y471550D01*
X1253283Y471300D01*
X1252950Y470717D01*
X1252783Y470217D01*
Y469717D01*
X1252950Y469217D01*
X1253367Y468717D01*
X1253867Y468383D01*
X1254450Y468300D01*
X1255033Y468467D01*
X1255617Y468967D01*
G01X1261300Y473300D02*
Y468300D01*
G01Y469050D02*
X1260967Y468633D01*
X1260467Y468383D01*
X1259883Y468300D01*
X1259217Y468467D01*
X1258717Y468883D01*
X1258383Y469383D01*
X1258300Y469967D01*
X1258383Y470550D01*
X1258717Y471050D01*
X1259217Y471467D01*
X1259883Y471633D01*
X1260467Y471550D01*
X1260883Y471383D01*
X1261300Y471050D01*
G01X1268917Y471633D02*
X1269917Y468300D01*
X1271000Y471633D01*
X1272083Y468300D01*
X1273083Y471633D01*
G01X1276600D02*
Y468300D01*
G01Y472967D02*
X1276433Y473050D01*
Y473217D01*
X1276600Y473300D01*
X1276767Y473217D01*
Y473050D01*
X1276600Y472967D01*
G01X1282200Y473300D02*
Y468300D01*
G01X1281033Y471633D02*
X1283367D01*
G01X1286383Y468300D02*
Y473300D01*
G01Y470883D02*
X1286800Y471300D01*
X1287217Y471550D01*
X1287883Y471633D01*
X1288383Y471550D01*
X1288967Y471217D01*
X1289217Y470717D01*
Y468300D01*
G01X1297333D02*
X1300667Y469967D01*
X1297333Y471633D01*
G01X1303183Y468883D02*
X1303767Y468467D01*
X1304433Y468300D01*
X1305100Y468467D01*
X1305683Y468967D01*
X1306100Y469717D01*
X1306267Y470467D01*
Y471383D01*
X1306100Y472133D01*
X1305683Y472800D01*
X1305183Y473133D01*
X1304600Y473300D01*
X1303933Y473133D01*
X1303433Y472800D01*
X1303100Y472300D01*
X1302933Y471633D01*
X1303100Y471050D01*
X1303517Y470467D01*
X1304017Y470133D01*
X1304600Y470050D01*
X1305267Y470217D01*
X1305767Y470633D01*
X1306267Y471383D01*
G01X1310200Y473300D02*
X1309533Y473133D01*
X1309033Y472717D01*
X1308700Y472217D01*
X1308450Y471550D01*
X1308367Y470800D01*
X1308450Y470050D01*
X1308700Y469383D01*
X1309033Y468883D01*
X1309533Y468467D01*
X1310200Y468300D01*
X1310867Y468467D01*
X1311367Y468883D01*
X1311700Y469383D01*
X1311950Y470050D01*
X1312033Y470800D01*
X1311950Y471550D01*
X1311700Y472217D01*
X1311367Y472717D01*
X1310867Y473133D01*
X1310200Y473300D01*
G01X1314300Y468133D02*
X1317300Y473300D01*
G01X1314300D02*
X1313800Y473133D01*
X1313550Y472883D01*
X1313383Y472383D01*
X1313550Y471883D01*
X1313800Y471633D01*
X1314300Y471467D01*
X1314800Y471633D01*
X1315050Y471883D01*
X1315217Y472383D01*
X1315050Y472883D01*
X1314800Y473133D01*
X1314300Y473300D01*
G01X1317300Y469967D02*
X1316800Y469800D01*
X1316550Y469550D01*
X1316383Y469050D01*
X1316550Y468550D01*
X1316800Y468300D01*
X1317300Y468133D01*
X1317800Y468300D01*
X1318050Y468550D01*
X1318217Y469050D01*
X1318050Y469550D01*
X1317800Y469800D01*
X1317300Y469967D01*
G01X1325833Y468300D02*
Y471633D01*
G01Y470967D02*
X1326250Y471300D01*
X1326667Y471550D01*
X1327250Y471633D01*
X1327667Y471550D01*
X1328167Y471300D01*
G01X1331350Y470550D02*
X1334017D01*
X1333767Y471133D01*
X1333350Y471467D01*
X1332767Y471633D01*
X1332183Y471550D01*
X1331683Y471300D01*
X1331350Y470717D01*
X1331183Y470217D01*
Y469717D01*
X1331350Y469217D01*
X1331767Y468717D01*
X1332267Y468383D01*
X1332850Y468300D01*
X1333433Y468467D01*
X1334017Y468967D01*
G01X1336950Y468883D02*
X1337367Y468550D01*
X1337950Y468300D01*
X1338450D01*
X1338950Y468467D01*
X1339283Y468717D01*
X1339450Y469050D01*
X1339367Y469550D01*
X1339033Y469800D01*
X1337533Y470300D01*
X1337200Y470883D01*
X1337367Y471300D01*
X1337700Y471550D01*
X1338200Y471633D01*
X1338700Y471550D01*
X1339200Y471300D01*
G01X1343800Y471633D02*
Y468300D01*
G01Y472967D02*
X1343633Y473050D01*
Y473217D01*
X1343800Y473300D01*
X1343967Y473217D01*
Y473050D01*
X1343800Y472967D01*
G01X1347983Y468300D02*
Y471633D01*
G01Y470800D02*
X1348317Y471217D01*
X1348817Y471550D01*
X1349483Y471633D01*
X1350067Y471550D01*
X1350567Y471217D01*
X1350817Y470633D01*
Y468300D01*
G01X1360017Y466800D02*
X1361183Y467967D01*
Y469133D01*
X1360017D01*
Y467967D01*
X1361183D01*
G01Y469967D02*
Y471133D01*
X1360017D01*
Y469967D01*
X1361183D01*
G01X1364367Y468300D02*
Y473300D01*
X1366033D01*
X1366700Y473050D01*
X1367200Y472717D01*
X1367617Y472217D01*
X1367950Y471633D01*
X1368033Y470800D01*
X1367950Y469967D01*
X1367617Y469383D01*
X1367200Y468883D01*
X1366700Y468550D01*
X1366033Y468300D01*
X1364367D01*
G01X1371800D02*
X1371300Y468383D01*
X1370800Y468717D01*
X1370467Y469300D01*
X1370300Y469967D01*
X1370467Y470633D01*
X1370800Y471217D01*
X1371300Y471550D01*
X1371800Y471633D01*
X1372300Y471550D01*
X1372800Y471217D01*
X1373133Y470633D01*
X1373217Y469967D01*
X1373133Y469300D01*
X1372800Y468717D01*
X1372300Y468383D01*
X1371800Y468300D01*
G01X1381583D02*
Y471633D01*
G01Y470800D02*
X1381917Y471217D01*
X1382417Y471550D01*
X1383083Y471633D01*
X1383667Y471550D01*
X1384167Y471217D01*
X1384417Y470633D01*
Y468300D01*
G01X1388600D02*
X1388100Y468383D01*
X1387600Y468717D01*
X1387267Y469300D01*
X1387100Y469967D01*
X1387267Y470633D01*
X1387600Y471217D01*
X1388100Y471550D01*
X1388600Y471633D01*
X1389100Y471550D01*
X1389600Y471217D01*
X1389933Y470633D01*
X1390017Y469967D01*
X1389933Y469300D01*
X1389600Y468717D01*
X1389100Y468383D01*
X1388600Y468300D01*
G01X1394200Y473300D02*
Y468300D01*
G01X1393033Y471633D02*
X1395367D01*
G01X1406900Y468300D02*
Y471633D01*
G01Y471050D02*
X1406567Y471383D01*
X1406067Y471550D01*
X1405483Y471633D01*
X1404900Y471467D01*
X1404400Y471133D01*
X1404067Y470633D01*
X1403900Y469967D01*
X1404067Y469300D01*
X1404400Y468800D01*
X1404900Y468467D01*
X1405483Y468300D01*
X1406067Y468383D01*
X1406567Y468633D01*
X1406900Y468967D01*
G01X1411000Y468300D02*
Y473300D01*
G01X1416600Y468300D02*
Y473300D01*
G01X1422200Y468300D02*
X1421700Y468383D01*
X1421200Y468717D01*
X1420867Y469300D01*
X1420700Y469967D01*
X1420867Y470633D01*
X1421200Y471217D01*
X1421700Y471550D01*
X1422200Y471633D01*
X1422700Y471550D01*
X1423200Y471217D01*
X1423533Y470633D01*
X1423617Y469967D01*
X1423533Y469300D01*
X1423200Y468717D01*
X1422700Y468383D01*
X1422200Y468300D01*
G01X1425717Y471633D02*
X1426717Y468300D01*
X1427800Y471633D01*
X1428883Y468300D01*
X1429883Y471633D01*
G01X1136600Y478800D02*
Y483800D01*
X1135600Y482800D01*
G01Y478800D02*
X1137600D01*
G01X1142200Y478633D02*
X1142033Y478717D01*
Y478883D01*
X1142200Y478967D01*
X1142367Y478883D01*
Y478717D01*
X1142200Y478633D01*
G01X1145967Y478800D02*
Y483800D01*
X1147633D01*
X1148300Y483550D01*
X1148800Y483217D01*
X1149217Y482717D01*
X1149550Y482133D01*
X1149633Y481300D01*
X1149550Y480467D01*
X1149217Y479883D01*
X1148800Y479383D01*
X1148300Y479050D01*
X1147633Y478800D01*
X1145967D01*
G01X1153400Y482133D02*
Y478800D01*
G01Y483467D02*
X1153233Y483550D01*
Y483717D01*
X1153400Y483800D01*
X1153567Y483717D01*
Y483550D01*
X1153400Y483467D01*
G01X1156500Y478800D02*
Y482133D01*
G01Y481217D02*
X1156750Y481633D01*
X1157167Y481967D01*
X1157750Y482133D01*
X1158333Y481967D01*
X1158750Y481633D01*
X1159000Y481217D01*
Y478800D01*
G01Y481217D02*
X1159250Y481633D01*
X1159667Y481967D01*
X1160250Y482133D01*
X1160833Y481967D01*
X1161250Y481633D01*
X1161500Y481133D01*
Y478800D01*
G01X1163100Y477133D02*
Y482133D01*
G01Y481383D02*
X1163517Y481800D01*
X1163933Y482050D01*
X1164600Y482133D01*
X1165183Y482050D01*
X1165767Y481633D01*
X1166017Y481050D01*
X1166100Y480467D01*
X1166017Y479883D01*
X1165767Y479300D01*
X1165267Y478967D01*
X1164600Y478800D01*
X1164017Y478883D01*
X1163433Y479133D01*
X1163100Y479467D01*
G01X1170200Y478800D02*
Y483800D01*
G01X1174550Y481050D02*
X1177217D01*
X1176967Y481633D01*
X1176550Y481967D01*
X1175967Y482133D01*
X1175383Y482050D01*
X1174883Y481800D01*
X1174550Y481217D01*
X1174383Y480717D01*
Y480217D01*
X1174550Y479717D01*
X1174967Y479217D01*
X1175467Y478883D01*
X1176050Y478800D01*
X1176633Y478967D01*
X1177217Y479467D01*
G01X1188667Y478800D02*
X1185333Y480467D01*
X1188667Y482133D01*
G01X1198200Y478800D02*
Y483800D01*
X1197200Y482800D01*
G01Y478800D02*
X1199200D01*
G01X1206900D02*
Y482133D01*
G01Y481217D02*
X1207150Y481633D01*
X1207567Y481967D01*
X1208150Y482133D01*
X1208733Y481967D01*
X1209150Y481633D01*
X1209400Y481217D01*
Y478800D01*
G01Y481217D02*
X1209650Y481633D01*
X1210067Y481967D01*
X1210650Y482133D01*
X1211233Y481967D01*
X1211650Y481633D01*
X1211900Y481133D01*
Y478800D01*
G01X1215000Y482133D02*
Y478800D01*
G01Y483467D02*
X1214833Y483550D01*
Y483717D01*
X1215000Y483800D01*
X1215167Y483717D01*
Y483550D01*
X1215000Y483467D01*
G01X1220600Y478800D02*
Y483800D01*
G01X1231217Y477300D02*
X1232383Y478467D01*
Y479633D01*
X1231217D01*
Y478467D01*
X1232383D01*
G01Y480467D02*
Y481633D01*
X1231217D01*
Y480467D01*
X1232383D01*
G01X1129600Y693300D02*
Y454800D01*
G01X1136600Y512800D02*
Y517800D01*
X1135600Y516800D01*
G01Y512800D02*
X1137600D01*
G01X1142200Y512633D02*
X1142033Y512717D01*
Y512883D01*
X1142200Y512967D01*
X1142367Y512883D01*
Y512717D01*
X1142200Y512633D01*
G01X1145717Y517800D02*
X1147800Y512800D01*
X1149883Y517800D01*
G01X1153400Y516133D02*
Y512800D01*
G01Y517467D02*
X1153233Y517550D01*
Y517717D01*
X1153400Y517800D01*
X1153567Y517717D01*
Y517550D01*
X1153400Y517467D01*
G01X1160500Y512800D02*
Y516133D01*
G01Y515550D02*
X1160167Y515883D01*
X1159667Y516050D01*
X1159083Y516133D01*
X1158500Y515967D01*
X1158000Y515633D01*
X1157667Y515133D01*
X1157500Y514467D01*
X1157667Y513800D01*
X1158000Y513300D01*
X1158500Y512967D01*
X1159083Y512800D01*
X1159667Y512883D01*
X1160167Y513133D01*
X1160500Y513467D01*
G01X1168950Y513383D02*
X1169367Y513050D01*
X1169950Y512800D01*
X1170450D01*
X1170950Y512967D01*
X1171283Y513217D01*
X1171450Y513550D01*
X1171367Y514050D01*
X1171033Y514300D01*
X1169533Y514800D01*
X1169200Y515383D01*
X1169367Y515800D01*
X1169700Y516050D01*
X1170200Y516133D01*
X1170700Y516050D01*
X1171200Y515800D01*
G01X1174383Y512800D02*
Y517800D01*
G01Y515383D02*
X1174800Y515800D01*
X1175217Y516050D01*
X1175883Y516133D01*
X1176383Y516050D01*
X1176967Y515717D01*
X1177217Y515217D01*
Y512800D01*
G01X1181400D02*
X1180900Y512883D01*
X1180400Y513217D01*
X1180067Y513800D01*
X1179900Y514467D01*
X1180067Y515133D01*
X1180400Y515717D01*
X1180900Y516050D01*
X1181400Y516133D01*
X1181900Y516050D01*
X1182400Y515717D01*
X1182733Y515133D01*
X1182817Y514467D01*
X1182733Y513800D01*
X1182400Y513217D01*
X1181900Y512883D01*
X1181400Y512800D01*
G01X1185583Y516133D02*
Y513800D01*
X1185917Y513217D01*
X1186417Y512883D01*
X1187000Y512800D01*
X1187583Y512883D01*
X1188083Y513217D01*
X1188417Y513800D01*
G01Y512800D02*
Y516133D01*
G01X1192600Y512800D02*
Y517800D01*
G01X1199700D02*
Y512800D01*
G01Y513550D02*
X1199367Y513133D01*
X1198867Y512883D01*
X1198283Y512800D01*
X1197617Y512967D01*
X1197117Y513383D01*
X1196783Y513883D01*
X1196700Y514467D01*
X1196783Y515050D01*
X1197117Y515550D01*
X1197617Y515967D01*
X1198283Y516133D01*
X1198867Y516050D01*
X1199283Y515883D01*
X1199700Y515550D01*
G01X1207900Y512800D02*
Y517800D01*
G01Y515300D02*
X1208317Y515800D01*
X1208817Y516050D01*
X1209317Y516133D01*
X1210067Y515967D01*
X1210567Y515633D01*
X1210900Y515050D01*
Y514383D01*
X1210733Y513717D01*
X1210400Y513217D01*
X1209817Y512883D01*
X1209317Y512800D01*
X1208817Y512883D01*
X1208317Y513133D01*
X1207900Y513550D01*
G01X1213750Y515050D02*
X1216417D01*
X1216167Y515633D01*
X1215750Y515967D01*
X1215167Y516133D01*
X1214583Y516050D01*
X1214083Y515800D01*
X1213750Y515217D01*
X1213583Y514717D01*
Y514217D01*
X1213750Y513717D01*
X1214167Y513217D01*
X1214667Y512883D01*
X1215250Y512800D01*
X1215833Y512967D01*
X1216417Y513467D01*
G01X1224700Y511133D02*
Y516133D01*
G01Y515383D02*
X1225117Y515800D01*
X1225533Y516050D01*
X1226200Y516133D01*
X1226783Y516050D01*
X1227367Y515633D01*
X1227617Y515050D01*
X1227700Y514467D01*
X1227617Y513883D01*
X1227367Y513300D01*
X1226867Y512967D01*
X1226200Y512800D01*
X1225617Y512883D01*
X1225033Y513133D01*
X1224700Y513467D01*
G01X1231800Y512800D02*
Y517800D01*
G01X1235983Y516133D02*
Y513800D01*
X1236317Y513217D01*
X1236817Y512883D01*
X1237400Y512800D01*
X1237983Y512883D01*
X1238483Y513217D01*
X1238817Y513800D01*
G01Y512800D02*
Y516133D01*
G01X1241833Y511550D02*
X1242417Y511217D01*
X1243083Y511133D01*
X1243667Y511217D01*
X1244167Y511633D01*
X1244500Y512217D01*
Y516133D01*
G01Y515467D02*
X1244167Y515800D01*
X1243667Y516050D01*
X1243083Y516133D01*
X1242417Y515967D01*
X1242000Y515633D01*
X1241667Y515050D01*
X1241500Y514467D01*
X1241583Y513967D01*
X1241917Y513383D01*
X1242417Y512967D01*
X1243083Y512800D01*
X1243583Y512883D01*
X1244167Y513217D01*
X1244500Y513550D01*
G01X1247433Y511550D02*
X1248017Y511217D01*
X1248683Y511133D01*
X1249267Y511217D01*
X1249767Y511633D01*
X1250100Y512217D01*
Y516133D01*
G01Y515467D02*
X1249767Y515800D01*
X1249267Y516050D01*
X1248683Y516133D01*
X1248017Y515967D01*
X1247600Y515633D01*
X1247267Y515050D01*
X1247100Y514467D01*
X1247183Y513967D01*
X1247517Y513383D01*
X1248017Y512967D01*
X1248683Y512800D01*
X1249183Y512883D01*
X1249767Y513217D01*
X1250100Y513550D01*
G01X1252950Y515050D02*
X1255617D01*
X1255367Y515633D01*
X1254950Y515967D01*
X1254367Y516133D01*
X1253783Y516050D01*
X1253283Y515800D01*
X1252950Y515217D01*
X1252783Y514717D01*
Y514217D01*
X1252950Y513717D01*
X1253367Y513217D01*
X1253867Y512883D01*
X1254450Y512800D01*
X1255033Y512967D01*
X1255617Y513467D01*
G01X1261300Y517800D02*
Y512800D01*
G01Y513550D02*
X1260967Y513133D01*
X1260467Y512883D01*
X1259883Y512800D01*
X1259217Y512967D01*
X1258717Y513383D01*
X1258383Y513883D01*
X1258300Y514467D01*
X1258383Y515050D01*
X1258717Y515550D01*
X1259217Y515967D01*
X1259883Y516133D01*
X1260467Y516050D01*
X1260883Y515883D01*
X1261300Y515550D01*
G01X1268917Y516133D02*
X1269917Y512800D01*
X1271000Y516133D01*
X1272083Y512800D01*
X1273083Y516133D01*
G01X1276600D02*
Y512800D01*
G01Y517467D02*
X1276433Y517550D01*
Y517717D01*
X1276600Y517800D01*
X1276767Y517717D01*
Y517550D01*
X1276600Y517467D01*
G01X1282200Y517800D02*
Y512800D01*
G01X1281033Y516133D02*
X1283367D01*
G01X1286383Y512800D02*
Y517800D01*
G01Y515383D02*
X1286800Y515800D01*
X1287217Y516050D01*
X1287883Y516133D01*
X1288383Y516050D01*
X1288967Y515717D01*
X1289217Y515217D01*
Y512800D01*
G01X1297333D02*
X1300667Y514467D01*
X1297333Y516133D01*
G01X1303183Y513383D02*
X1303767Y512967D01*
X1304433Y512800D01*
X1305100Y512967D01*
X1305683Y513467D01*
X1306100Y514217D01*
X1306267Y514967D01*
Y515883D01*
X1306100Y516633D01*
X1305683Y517300D01*
X1305183Y517633D01*
X1304600Y517800D01*
X1303933Y517633D01*
X1303433Y517300D01*
X1303100Y516800D01*
X1302933Y516133D01*
X1303100Y515550D01*
X1303517Y514967D01*
X1304017Y514633D01*
X1304600Y514550D01*
X1305267Y514717D01*
X1305767Y515133D01*
X1306267Y515883D01*
G01X1310200Y517800D02*
X1309533Y517633D01*
X1309033Y517217D01*
X1308700Y516717D01*
X1308450Y516050D01*
X1308367Y515300D01*
X1308450Y514550D01*
X1308700Y513883D01*
X1309033Y513383D01*
X1309533Y512967D01*
X1310200Y512800D01*
X1310867Y512967D01*
X1311367Y513383D01*
X1311700Y513883D01*
X1311950Y514550D01*
X1312033Y515300D01*
X1311950Y516050D01*
X1311700Y516717D01*
X1311367Y517217D01*
X1310867Y517633D01*
X1310200Y517800D01*
G01X1314300Y512633D02*
X1317300Y517800D01*
G01X1314300D02*
X1313800Y517633D01*
X1313550Y517383D01*
X1313383Y516883D01*
X1313550Y516383D01*
X1313800Y516133D01*
X1314300Y515967D01*
X1314800Y516133D01*
X1315050Y516383D01*
X1315217Y516883D01*
X1315050Y517383D01*
X1314800Y517633D01*
X1314300Y517800D01*
G01X1317300Y514467D02*
X1316800Y514300D01*
X1316550Y514050D01*
X1316383Y513550D01*
X1316550Y513050D01*
X1316800Y512800D01*
X1317300Y512633D01*
X1317800Y512800D01*
X1318050Y513050D01*
X1318217Y513550D01*
X1318050Y514050D01*
X1317800Y514300D01*
X1317300Y514467D01*
G01X1325833Y512800D02*
Y516133D01*
G01Y515467D02*
X1326250Y515800D01*
X1326667Y516050D01*
X1327250Y516133D01*
X1327667Y516050D01*
X1328167Y515800D01*
G01X1331350Y515050D02*
X1334017D01*
X1333767Y515633D01*
X1333350Y515967D01*
X1332767Y516133D01*
X1332183Y516050D01*
X1331683Y515800D01*
X1331350Y515217D01*
X1331183Y514717D01*
Y514217D01*
X1331350Y513717D01*
X1331767Y513217D01*
X1332267Y512883D01*
X1332850Y512800D01*
X1333433Y512967D01*
X1334017Y513467D01*
G01X1336950Y513383D02*
X1337367Y513050D01*
X1337950Y512800D01*
X1338450D01*
X1338950Y512967D01*
X1339283Y513217D01*
X1339450Y513550D01*
X1339367Y514050D01*
X1339033Y514300D01*
X1337533Y514800D01*
X1337200Y515383D01*
X1337367Y515800D01*
X1337700Y516050D01*
X1338200Y516133D01*
X1338700Y516050D01*
X1339200Y515800D01*
G01X1343800Y516133D02*
Y512800D01*
G01Y517467D02*
X1343633Y517550D01*
Y517717D01*
X1343800Y517800D01*
X1343967Y517717D01*
Y517550D01*
X1343800Y517467D01*
G01X1347983Y512800D02*
Y516133D01*
G01Y515300D02*
X1348317Y515717D01*
X1348817Y516050D01*
X1349483Y516133D01*
X1350067Y516050D01*
X1350567Y515717D01*
X1350817Y515133D01*
Y512800D01*
G01X1360017Y511300D02*
X1361183Y512467D01*
Y513633D01*
X1360017D01*
Y512467D01*
X1361183D01*
G01Y514467D02*
Y515633D01*
X1360017D01*
Y514467D01*
X1361183D01*
G01X1364367Y512800D02*
Y517800D01*
X1366033D01*
X1366700Y517550D01*
X1367200Y517217D01*
X1367617Y516717D01*
X1367950Y516133D01*
X1368033Y515300D01*
X1367950Y514467D01*
X1367617Y513883D01*
X1367200Y513383D01*
X1366700Y513050D01*
X1366033Y512800D01*
X1364367D01*
G01X1371800D02*
X1371300Y512883D01*
X1370800Y513217D01*
X1370467Y513800D01*
X1370300Y514467D01*
X1370467Y515133D01*
X1370800Y515717D01*
X1371300Y516050D01*
X1371800Y516133D01*
X1372300Y516050D01*
X1372800Y515717D01*
X1373133Y515133D01*
X1373217Y514467D01*
X1373133Y513800D01*
X1372800Y513217D01*
X1372300Y512883D01*
X1371800Y512800D01*
G01X1381583D02*
Y516133D01*
G01Y515300D02*
X1381917Y515717D01*
X1382417Y516050D01*
X1383083Y516133D01*
X1383667Y516050D01*
X1384167Y515717D01*
X1384417Y515133D01*
Y512800D01*
G01X1388600D02*
X1388100Y512883D01*
X1387600Y513217D01*
X1387267Y513800D01*
X1387100Y514467D01*
X1387267Y515133D01*
X1387600Y515717D01*
X1388100Y516050D01*
X1388600Y516133D01*
X1389100Y516050D01*
X1389600Y515717D01*
X1389933Y515133D01*
X1390017Y514467D01*
X1389933Y513800D01*
X1389600Y513217D01*
X1389100Y512883D01*
X1388600Y512800D01*
G01X1394200Y517800D02*
Y512800D01*
G01X1393033Y516133D02*
X1395367D01*
G01X1406900Y512800D02*
Y516133D01*
G01Y515550D02*
X1406567Y515883D01*
X1406067Y516050D01*
X1405483Y516133D01*
X1404900Y515967D01*
X1404400Y515633D01*
X1404067Y515133D01*
X1403900Y514467D01*
X1404067Y513800D01*
X1404400Y513300D01*
X1404900Y512967D01*
X1405483Y512800D01*
X1406067Y512883D01*
X1406567Y513133D01*
X1406900Y513467D01*
G01X1411000Y512800D02*
Y517800D01*
G01X1416600Y512800D02*
Y517800D01*
G01X1422200Y512800D02*
X1421700Y512883D01*
X1421200Y513217D01*
X1420867Y513800D01*
X1420700Y514467D01*
X1420867Y515133D01*
X1421200Y515717D01*
X1421700Y516050D01*
X1422200Y516133D01*
X1422700Y516050D01*
X1423200Y515717D01*
X1423533Y515133D01*
X1423617Y514467D01*
X1423533Y513800D01*
X1423200Y513217D01*
X1422700Y512883D01*
X1422200Y512800D01*
G01X1425717Y516133D02*
X1426717Y512800D01*
X1427800Y516133D01*
X1428883Y512800D01*
X1429883Y516133D01*
G01X1134017Y631467D02*
X1134517Y631967D01*
X1135100Y632217D01*
X1135767Y632300D01*
X1136600Y632133D01*
X1137183Y631717D01*
X1137350Y631217D01*
X1137267Y630717D01*
X1136933Y630300D01*
X1135267Y629467D01*
X1134517Y628883D01*
X1134017Y628050D01*
X1133850Y627300D01*
X1137350D01*
G01X1141200Y627133D02*
X1141033Y627217D01*
Y627383D01*
X1141200Y627467D01*
X1141367Y627383D01*
Y627217D01*
X1141200Y627133D01*
G01X1146800Y632300D02*
Y627300D01*
G01X1144883Y632300D02*
X1148717D01*
G01X1150983Y627300D02*
Y632300D01*
G01Y629883D02*
X1151400Y630300D01*
X1151817Y630550D01*
X1152483Y630633D01*
X1152983Y630550D01*
X1153567Y630217D01*
X1153817Y629717D01*
Y627300D01*
G01X1156750Y629550D02*
X1159417D01*
X1159167Y630133D01*
X1158750Y630467D01*
X1158167Y630633D01*
X1157583Y630550D01*
X1157083Y630300D01*
X1156750Y629717D01*
X1156583Y629217D01*
Y628717D01*
X1156750Y628217D01*
X1157167Y627717D01*
X1157667Y627383D01*
X1158250Y627300D01*
X1158833Y627467D01*
X1159417Y627967D01*
G01X1167950Y627883D02*
X1168367Y627550D01*
X1168950Y627300D01*
X1169450D01*
X1169950Y627467D01*
X1170283Y627717D01*
X1170450Y628050D01*
X1170367Y628550D01*
X1170033Y628800D01*
X1168533Y629300D01*
X1168200Y629883D01*
X1168367Y630300D01*
X1168700Y630550D01*
X1169200Y630633D01*
X1169700Y630550D01*
X1170200Y630300D01*
G01X1174800Y630633D02*
Y627300D01*
G01Y631967D02*
X1174633Y632050D01*
Y632217D01*
X1174800Y632300D01*
X1174967Y632217D01*
Y632050D01*
X1174800Y631967D01*
G01X1181900Y632300D02*
Y627300D01*
G01Y628050D02*
X1181567Y627633D01*
X1181067Y627383D01*
X1180483Y627300D01*
X1179817Y627467D01*
X1179317Y627883D01*
X1178983Y628383D01*
X1178900Y628967D01*
X1178983Y629550D01*
X1179317Y630050D01*
X1179817Y630467D01*
X1180483Y630633D01*
X1181067Y630550D01*
X1181483Y630383D01*
X1181900Y630050D01*
G01X1184750Y629550D02*
X1187417D01*
X1187167Y630133D01*
X1186750Y630467D01*
X1186167Y630633D01*
X1185583Y630550D01*
X1185083Y630300D01*
X1184750Y629717D01*
X1184583Y629217D01*
Y628717D01*
X1184750Y628217D01*
X1185167Y627717D01*
X1185667Y627383D01*
X1186250Y627300D01*
X1186833Y627467D01*
X1187417Y627967D01*
G01X1195117Y630633D02*
X1196117Y627300D01*
X1197200Y630633D01*
X1198283Y627300D01*
X1199283Y630633D01*
G01X1202800D02*
Y627300D01*
G01Y631967D02*
X1202633Y632050D01*
Y632217D01*
X1202800Y632300D01*
X1202967Y632217D01*
Y632050D01*
X1202800Y631967D01*
G01X1208400Y632300D02*
Y627300D01*
G01X1207233Y630633D02*
X1209567D01*
G01X1212583Y627300D02*
Y632300D01*
G01Y629883D02*
X1213000Y630300D01*
X1213417Y630550D01*
X1214083Y630633D01*
X1214583Y630550D01*
X1215167Y630217D01*
X1215417Y629717D01*
Y627300D01*
G01X1223950Y627883D02*
X1224367Y627550D01*
X1224950Y627300D01*
X1225450D01*
X1225950Y627467D01*
X1226283Y627717D01*
X1226450Y628050D01*
X1226367Y628550D01*
X1226033Y628800D01*
X1224533Y629300D01*
X1224200Y629883D01*
X1224367Y630300D01*
X1224700Y630550D01*
X1225200Y630633D01*
X1225700Y630550D01*
X1226200Y630300D01*
G01X1230800Y627300D02*
X1230300Y627383D01*
X1229800Y627717D01*
X1229467Y628300D01*
X1229300Y628967D01*
X1229467Y629633D01*
X1229800Y630217D01*
X1230300Y630550D01*
X1230800Y630633D01*
X1231300Y630550D01*
X1231800Y630217D01*
X1232133Y629633D01*
X1232217Y628967D01*
X1232133Y628300D01*
X1231800Y627717D01*
X1231300Y627383D01*
X1230800Y627300D01*
G01X1236400D02*
Y632300D01*
G01X1243500D02*
Y627300D01*
G01Y628050D02*
X1243167Y627633D01*
X1242667Y627383D01*
X1242083Y627300D01*
X1241417Y627467D01*
X1240917Y627883D01*
X1240583Y628383D01*
X1240500Y628967D01*
X1240583Y629550D01*
X1240917Y630050D01*
X1241417Y630467D01*
X1242083Y630633D01*
X1242667Y630550D01*
X1243083Y630383D01*
X1243500Y630050D01*
G01X1246350Y629550D02*
X1249017D01*
X1248767Y630133D01*
X1248350Y630467D01*
X1247767Y630633D01*
X1247183Y630550D01*
X1246683Y630300D01*
X1246350Y629717D01*
X1246183Y629217D01*
Y628717D01*
X1246350Y628217D01*
X1246767Y627717D01*
X1247267Y627383D01*
X1247850Y627300D01*
X1248433Y627467D01*
X1249017Y627967D01*
G01X1252033Y627300D02*
Y630633D01*
G01Y629967D02*
X1252450Y630300D01*
X1252867Y630550D01*
X1253450Y630633D01*
X1253867Y630550D01*
X1254367Y630300D01*
G01X1261900Y627300D02*
Y630633D01*
G01Y629717D02*
X1262150Y630133D01*
X1262567Y630467D01*
X1263150Y630633D01*
X1263733Y630467D01*
X1264150Y630133D01*
X1264400Y629717D01*
Y627300D01*
G01Y629717D02*
X1264650Y630133D01*
X1265067Y630467D01*
X1265650Y630633D01*
X1266233Y630467D01*
X1266650Y630133D01*
X1266900Y629633D01*
Y627300D01*
G01X1271500D02*
Y630633D01*
G01Y630050D02*
X1271167Y630383D01*
X1270667Y630550D01*
X1270083Y630633D01*
X1269500Y630467D01*
X1269000Y630133D01*
X1268667Y629633D01*
X1268500Y628967D01*
X1268667Y628300D01*
X1269000Y627800D01*
X1269500Y627467D01*
X1270083Y627300D01*
X1270667Y627383D01*
X1271167Y627633D01*
X1271500Y627967D01*
G01X1274350Y627883D02*
X1274767Y627550D01*
X1275350Y627300D01*
X1275850D01*
X1276350Y627467D01*
X1276683Y627717D01*
X1276850Y628050D01*
X1276767Y628550D01*
X1276433Y628800D01*
X1274933Y629300D01*
X1274600Y629883D01*
X1274767Y630300D01*
X1275100Y630550D01*
X1275600Y630633D01*
X1276100Y630550D01*
X1276600Y630300D01*
G01X1279783Y627300D02*
Y632300D01*
G01X1282450Y630633D02*
X1279783Y628717D01*
G01X1280867Y629467D02*
X1282617Y627300D01*
G01X1290900Y625633D02*
Y630633D01*
G01Y629883D02*
X1291317Y630300D01*
X1291733Y630550D01*
X1292400Y630633D01*
X1292983Y630550D01*
X1293567Y630133D01*
X1293817Y629550D01*
X1293900Y628967D01*
X1293817Y628383D01*
X1293567Y627800D01*
X1293067Y627467D01*
X1292400Y627300D01*
X1291817Y627383D01*
X1291233Y627633D01*
X1290900Y627967D01*
G01X1299500Y627300D02*
Y630633D01*
G01Y630050D02*
X1299167Y630383D01*
X1298667Y630550D01*
X1298083Y630633D01*
X1297500Y630467D01*
X1297000Y630133D01*
X1296667Y629633D01*
X1296500Y628967D01*
X1296667Y628300D01*
X1297000Y627800D01*
X1297500Y627467D01*
X1298083Y627300D01*
X1298667Y627383D01*
X1299167Y627633D01*
X1299500Y627967D01*
G01X1305100Y632300D02*
Y627300D01*
G01Y628050D02*
X1304767Y627633D01*
X1304267Y627383D01*
X1303683Y627300D01*
X1303017Y627467D01*
X1302517Y627883D01*
X1302183Y628383D01*
X1302100Y628967D01*
X1302183Y629550D01*
X1302517Y630050D01*
X1303017Y630467D01*
X1303683Y630633D01*
X1304267Y630550D01*
X1304683Y630383D01*
X1305100Y630050D01*
G01X1309033Y626383D02*
X1309367Y627467D01*
G01X1320400Y632300D02*
Y627300D01*
G01X1319233Y630633D02*
X1321567D01*
G01X1324583Y627300D02*
Y632300D01*
G01Y629883D02*
X1325000Y630300D01*
X1325417Y630550D01*
X1326083Y630633D01*
X1326583Y630550D01*
X1327167Y630217D01*
X1327417Y629717D01*
Y627300D01*
G01X1330350Y629550D02*
X1333017D01*
X1332767Y630133D01*
X1332350Y630467D01*
X1331767Y630633D01*
X1331183Y630550D01*
X1330683Y630300D01*
X1330350Y629717D01*
X1330183Y629217D01*
Y628717D01*
X1330350Y628217D01*
X1330767Y627717D01*
X1331267Y627383D01*
X1331850Y627300D01*
X1332433Y627467D01*
X1333017Y627967D01*
G01X1344300Y627300D02*
Y630633D01*
G01Y630050D02*
X1343967Y630383D01*
X1343467Y630550D01*
X1342883Y630633D01*
X1342300Y630467D01*
X1341800Y630133D01*
X1341467Y629633D01*
X1341300Y628967D01*
X1341467Y628300D01*
X1341800Y627800D01*
X1342300Y627467D01*
X1342883Y627300D01*
X1343467Y627383D01*
X1343967Y627633D01*
X1344300Y627967D01*
G01X1346983Y627300D02*
Y630633D01*
G01Y629800D02*
X1347317Y630217D01*
X1347817Y630550D01*
X1348483Y630633D01*
X1349067Y630550D01*
X1349567Y630217D01*
X1349817Y629633D01*
Y627300D01*
G01X1352583D02*
Y630633D01*
G01Y629800D02*
X1352917Y630217D01*
X1353417Y630550D01*
X1354083Y630633D01*
X1354667Y630550D01*
X1355167Y630217D01*
X1355417Y629633D01*
Y627300D01*
G01X1358183Y630633D02*
Y628300D01*
X1358517Y627717D01*
X1359017Y627383D01*
X1359600Y627300D01*
X1360183Y627383D01*
X1360683Y627717D01*
X1361017Y628300D01*
G01Y627300D02*
Y630633D01*
G01X1366700Y627300D02*
Y630633D01*
G01Y630050D02*
X1366367Y630383D01*
X1365867Y630550D01*
X1365283Y630633D01*
X1364700Y630467D01*
X1364200Y630133D01*
X1363867Y629633D01*
X1363700Y628967D01*
X1363867Y628300D01*
X1364200Y627800D01*
X1364700Y627467D01*
X1365283Y627300D01*
X1365867Y627383D01*
X1366367Y627633D01*
X1366700Y627967D01*
G01X1370800Y627300D02*
Y632300D01*
G01X1380833Y627300D02*
Y630633D01*
G01Y629967D02*
X1381250Y630300D01*
X1381667Y630550D01*
X1382250Y630633D01*
X1382667Y630550D01*
X1383167Y630300D01*
G01X1387600Y630633D02*
Y627300D01*
G01Y631967D02*
X1387433Y632050D01*
Y632217D01*
X1387600Y632300D01*
X1387767Y632217D01*
Y632050D01*
X1387600Y631967D01*
G01X1391783Y627300D02*
Y630633D01*
G01Y629800D02*
X1392117Y630217D01*
X1392617Y630550D01*
X1393283Y630633D01*
X1393867Y630550D01*
X1394367Y630217D01*
X1394617Y629633D01*
Y627300D01*
G01X1397633Y626050D02*
X1398217Y625717D01*
X1398883Y625633D01*
X1399467Y625717D01*
X1399967Y626133D01*
X1400300Y626717D01*
Y630633D01*
G01Y629967D02*
X1399967Y630300D01*
X1399467Y630550D01*
X1398883Y630633D01*
X1398217Y630467D01*
X1397800Y630133D01*
X1397467Y629550D01*
X1397300Y628967D01*
X1397383Y628467D01*
X1397717Y627883D01*
X1398217Y627467D01*
X1398883Y627300D01*
X1399383Y627383D01*
X1399967Y627717D01*
X1400300Y628050D01*
G01X1408750Y627883D02*
X1409167Y627550D01*
X1409750Y627300D01*
X1410250D01*
X1410750Y627467D01*
X1411083Y627717D01*
X1411250Y628050D01*
X1411167Y628550D01*
X1410833Y628800D01*
X1409333Y629300D01*
X1409000Y629883D01*
X1409167Y630300D01*
X1409500Y630550D01*
X1410000Y630633D01*
X1410500Y630550D01*
X1411000Y630300D01*
G01X1414183Y627300D02*
Y632300D01*
G01Y629883D02*
X1414600Y630300D01*
X1415017Y630550D01*
X1415683Y630633D01*
X1416183Y630550D01*
X1416767Y630217D01*
X1417017Y629717D01*
Y627300D01*
G01X1421200D02*
X1420700Y627383D01*
X1420200Y627717D01*
X1419867Y628300D01*
X1419700Y628967D01*
X1419867Y629633D01*
X1420200Y630217D01*
X1420700Y630550D01*
X1421200Y630633D01*
X1421700Y630550D01*
X1422200Y630217D01*
X1422533Y629633D01*
X1422617Y628967D01*
X1422533Y628300D01*
X1422200Y627717D01*
X1421700Y627383D01*
X1421200Y627300D01*
G01X1425383Y630633D02*
Y628300D01*
X1425717Y627717D01*
X1426217Y627383D01*
X1426800Y627300D01*
X1427383Y627383D01*
X1427883Y627717D01*
X1428217Y628300D01*
G01Y627300D02*
Y630633D01*
G01X1432400Y627300D02*
Y632300D01*
G01X1439500D02*
Y627300D01*
G01Y628050D02*
X1439167Y627633D01*
X1438667Y627383D01*
X1438083Y627300D01*
X1437417Y627467D01*
X1436917Y627883D01*
X1436583Y628383D01*
X1436500Y628967D01*
X1436583Y629550D01*
X1436917Y630050D01*
X1437417Y630467D01*
X1438083Y630633D01*
X1438667Y630550D01*
X1439083Y630383D01*
X1439500Y630050D01*
G01X1135600Y658300D02*
Y663300D01*
X1134600Y662300D01*
G01Y658300D02*
X1136600D01*
G01X1141200Y658133D02*
X1141033Y658217D01*
Y658383D01*
X1141200Y658467D01*
X1141367Y658383D01*
Y658217D01*
X1141200Y658133D01*
G01X1146800Y663300D02*
Y658300D01*
G01X1144883Y663300D02*
X1148717D01*
G01X1150983Y658300D02*
Y663300D01*
G01Y660883D02*
X1151400Y661300D01*
X1151817Y661550D01*
X1152483Y661633D01*
X1152983Y661550D01*
X1153567Y661217D01*
X1153817Y660717D01*
Y658300D01*
G01X1156750Y660550D02*
X1159417D01*
X1159167Y661133D01*
X1158750Y661467D01*
X1158167Y661633D01*
X1157583Y661550D01*
X1157083Y661300D01*
X1156750Y660717D01*
X1156583Y660217D01*
Y659717D01*
X1156750Y659217D01*
X1157167Y658717D01*
X1157667Y658383D01*
X1158250Y658300D01*
X1158833Y658467D01*
X1159417Y658967D01*
G01X1167950Y658883D02*
X1168367Y658550D01*
X1168950Y658300D01*
X1169450D01*
X1169950Y658467D01*
X1170283Y658717D01*
X1170450Y659050D01*
X1170367Y659550D01*
X1170033Y659800D01*
X1168533Y660300D01*
X1168200Y660883D01*
X1168367Y661300D01*
X1168700Y661550D01*
X1169200Y661633D01*
X1169700Y661550D01*
X1170200Y661300D01*
G01X1174800Y661633D02*
Y658300D01*
G01Y662967D02*
X1174633Y663050D01*
Y663217D01*
X1174800Y663300D01*
X1174967Y663217D01*
Y663050D01*
X1174800Y662967D01*
G01X1181900Y663300D02*
Y658300D01*
G01Y659050D02*
X1181567Y658633D01*
X1181067Y658383D01*
X1180483Y658300D01*
X1179817Y658467D01*
X1179317Y658883D01*
X1178983Y659383D01*
X1178900Y659967D01*
X1178983Y660550D01*
X1179317Y661050D01*
X1179817Y661467D01*
X1180483Y661633D01*
X1181067Y661550D01*
X1181483Y661383D01*
X1181900Y661050D01*
G01X1184750Y660550D02*
X1187417D01*
X1187167Y661133D01*
X1186750Y661467D01*
X1186167Y661633D01*
X1185583Y661550D01*
X1185083Y661300D01*
X1184750Y660717D01*
X1184583Y660217D01*
Y659717D01*
X1184750Y659217D01*
X1185167Y658717D01*
X1185667Y658383D01*
X1186250Y658300D01*
X1186833Y658467D01*
X1187417Y658967D01*
G01X1195117Y661633D02*
X1196117Y658300D01*
X1197200Y661633D01*
X1198283Y658300D01*
X1199283Y661633D01*
G01X1202800D02*
Y658300D01*
G01Y662967D02*
X1202633Y663050D01*
Y663217D01*
X1202800Y663300D01*
X1202967Y663217D01*
Y663050D01*
X1202800Y662967D01*
G01X1208400Y663300D02*
Y658300D01*
G01X1207233Y661633D02*
X1209567D01*
G01X1212583Y658300D02*
Y663300D01*
G01Y660883D02*
X1213000Y661300D01*
X1213417Y661550D01*
X1214083Y661633D01*
X1214583Y661550D01*
X1215167Y661217D01*
X1215417Y660717D01*
Y658300D01*
G01X1219600D02*
X1219100Y658383D01*
X1218600Y658717D01*
X1218267Y659300D01*
X1218100Y659967D01*
X1218267Y660633D01*
X1218600Y661217D01*
X1219100Y661550D01*
X1219600Y661633D01*
X1220100Y661550D01*
X1220600Y661217D01*
X1220933Y660633D01*
X1221017Y659967D01*
X1220933Y659300D01*
X1220600Y658717D01*
X1220100Y658383D01*
X1219600Y658300D01*
G01X1223783Y661633D02*
Y659300D01*
X1224117Y658717D01*
X1224617Y658383D01*
X1225200Y658300D01*
X1225783Y658383D01*
X1226283Y658717D01*
X1226617Y659300D01*
G01Y658300D02*
Y661633D01*
G01X1230800Y663300D02*
Y658300D01*
G01X1229633Y661633D02*
X1231967D01*
G01X1240750Y658883D02*
X1241167Y658550D01*
X1241750Y658300D01*
X1242250D01*
X1242750Y658467D01*
X1243083Y658717D01*
X1243250Y659050D01*
X1243167Y659550D01*
X1242833Y659800D01*
X1241333Y660300D01*
X1241000Y660883D01*
X1241167Y661300D01*
X1241500Y661550D01*
X1242000Y661633D01*
X1242500Y661550D01*
X1243000Y661300D01*
G01X1247600Y658300D02*
X1247100Y658383D01*
X1246600Y658717D01*
X1246267Y659300D01*
X1246100Y659967D01*
X1246267Y660633D01*
X1246600Y661217D01*
X1247100Y661550D01*
X1247600Y661633D01*
X1248100Y661550D01*
X1248600Y661217D01*
X1248933Y660633D01*
X1249017Y659967D01*
X1248933Y659300D01*
X1248600Y658717D01*
X1248100Y658383D01*
X1247600Y658300D01*
G01X1253200D02*
Y663300D01*
G01X1260300D02*
Y658300D01*
G01Y659050D02*
X1259967Y658633D01*
X1259467Y658383D01*
X1258883Y658300D01*
X1258217Y658467D01*
X1257717Y658883D01*
X1257383Y659383D01*
X1257300Y659967D01*
X1257383Y660550D01*
X1257717Y661050D01*
X1258217Y661467D01*
X1258883Y661633D01*
X1259467Y661550D01*
X1259883Y661383D01*
X1260300Y661050D01*
G01X1263150Y660550D02*
X1265817D01*
X1265567Y661133D01*
X1265150Y661467D01*
X1264567Y661633D01*
X1263983Y661550D01*
X1263483Y661300D01*
X1263150Y660717D01*
X1262983Y660217D01*
Y659717D01*
X1263150Y659217D01*
X1263567Y658717D01*
X1264067Y658383D01*
X1264650Y658300D01*
X1265233Y658467D01*
X1265817Y658967D01*
G01X1268833Y658300D02*
Y661633D01*
G01Y660967D02*
X1269250Y661300D01*
X1269667Y661550D01*
X1270250Y661633D01*
X1270667Y661550D01*
X1271167Y661300D01*
G01X1278700Y658300D02*
Y661633D01*
G01Y660717D02*
X1278950Y661133D01*
X1279367Y661467D01*
X1279950Y661633D01*
X1280533Y661467D01*
X1280950Y661133D01*
X1281200Y660717D01*
Y658300D01*
G01Y660717D02*
X1281450Y661133D01*
X1281867Y661467D01*
X1282450Y661633D01*
X1283033Y661467D01*
X1283450Y661133D01*
X1283700Y660633D01*
Y658300D01*
G01X1288300D02*
Y661633D01*
G01Y661050D02*
X1287967Y661383D01*
X1287467Y661550D01*
X1286883Y661633D01*
X1286300Y661467D01*
X1285800Y661133D01*
X1285467Y660633D01*
X1285300Y659967D01*
X1285467Y659300D01*
X1285800Y658800D01*
X1286300Y658467D01*
X1286883Y658300D01*
X1287467Y658383D01*
X1287967Y658633D01*
X1288300Y658967D01*
G01X1291150Y658883D02*
X1291567Y658550D01*
X1292150Y658300D01*
X1292650D01*
X1293150Y658467D01*
X1293483Y658717D01*
X1293650Y659050D01*
X1293567Y659550D01*
X1293233Y659800D01*
X1291733Y660300D01*
X1291400Y660883D01*
X1291567Y661300D01*
X1291900Y661550D01*
X1292400Y661633D01*
X1292900Y661550D01*
X1293400Y661300D01*
G01X1296583Y658300D02*
Y663300D01*
G01X1299250Y661633D02*
X1296583Y659717D01*
G01X1297667Y660467D02*
X1299417Y658300D01*
G01X1307700Y656633D02*
Y661633D01*
G01Y660883D02*
X1308117Y661300D01*
X1308533Y661550D01*
X1309200Y661633D01*
X1309783Y661550D01*
X1310367Y661133D01*
X1310617Y660550D01*
X1310700Y659967D01*
X1310617Y659383D01*
X1310367Y658800D01*
X1309867Y658467D01*
X1309200Y658300D01*
X1308617Y658383D01*
X1308033Y658633D01*
X1307700Y658967D01*
G01X1316300Y658300D02*
Y661633D01*
G01Y661050D02*
X1315967Y661383D01*
X1315467Y661550D01*
X1314883Y661633D01*
X1314300Y661467D01*
X1313800Y661133D01*
X1313467Y660633D01*
X1313300Y659967D01*
X1313467Y659300D01*
X1313800Y658800D01*
X1314300Y658467D01*
X1314883Y658300D01*
X1315467Y658383D01*
X1315967Y658633D01*
X1316300Y658967D01*
G01X1321900Y663300D02*
Y658300D01*
G01Y659050D02*
X1321567Y658633D01*
X1321067Y658383D01*
X1320483Y658300D01*
X1319817Y658467D01*
X1319317Y658883D01*
X1318983Y659383D01*
X1318900Y659967D01*
X1318983Y660550D01*
X1319317Y661050D01*
X1319817Y661467D01*
X1320483Y661633D01*
X1321067Y661550D01*
X1321483Y661383D01*
X1321900Y661050D01*
G01X1331433Y657383D02*
X1331767Y658467D01*
G01X1344300Y658300D02*
Y661633D01*
G01Y661050D02*
X1343967Y661383D01*
X1343467Y661550D01*
X1342883Y661633D01*
X1342300Y661467D01*
X1341800Y661133D01*
X1341467Y660633D01*
X1341300Y659967D01*
X1341467Y659300D01*
X1341800Y658800D01*
X1342300Y658467D01*
X1342883Y658300D01*
X1343467Y658383D01*
X1343967Y658633D01*
X1344300Y658967D01*
G01X1346983Y658300D02*
Y661633D01*
G01Y660800D02*
X1347317Y661217D01*
X1347817Y661550D01*
X1348483Y661633D01*
X1349067Y661550D01*
X1349567Y661217D01*
X1349817Y660633D01*
Y658300D01*
G01X1352583D02*
Y661633D01*
G01Y660800D02*
X1352917Y661217D01*
X1353417Y661550D01*
X1354083Y661633D01*
X1354667Y661550D01*
X1355167Y661217D01*
X1355417Y660633D01*
Y658300D01*
G01X1358183Y661633D02*
Y659300D01*
X1358517Y658717D01*
X1359017Y658383D01*
X1359600Y658300D01*
X1360183Y658383D01*
X1360683Y658717D01*
X1361017Y659300D01*
G01Y658300D02*
Y661633D01*
G01X1366700Y658300D02*
Y661633D01*
G01Y661050D02*
X1366367Y661383D01*
X1365867Y661550D01*
X1365283Y661633D01*
X1364700Y661467D01*
X1364200Y661133D01*
X1363867Y660633D01*
X1363700Y659967D01*
X1363867Y659300D01*
X1364200Y658800D01*
X1364700Y658467D01*
X1365283Y658300D01*
X1365867Y658383D01*
X1366367Y658633D01*
X1366700Y658967D01*
G01X1370800Y658300D02*
Y663300D01*
G01X1380833Y658300D02*
Y661633D01*
G01Y660967D02*
X1381250Y661300D01*
X1381667Y661550D01*
X1382250Y661633D01*
X1382667Y661550D01*
X1383167Y661300D01*
G01X1387600Y661633D02*
Y658300D01*
G01Y662967D02*
X1387433Y663050D01*
Y663217D01*
X1387600Y663300D01*
X1387767Y663217D01*
Y663050D01*
X1387600Y662967D01*
G01X1391783Y658300D02*
Y661633D01*
G01Y660800D02*
X1392117Y661217D01*
X1392617Y661550D01*
X1393283Y661633D01*
X1393867Y661550D01*
X1394367Y661217D01*
X1394617Y660633D01*
Y658300D01*
G01X1397633Y657050D02*
X1398217Y656717D01*
X1398883Y656633D01*
X1399467Y656717D01*
X1399967Y657133D01*
X1400300Y657717D01*
Y661633D01*
G01Y660967D02*
X1399967Y661300D01*
X1399467Y661550D01*
X1398883Y661633D01*
X1398217Y661467D01*
X1397800Y661133D01*
X1397467Y660550D01*
X1397300Y659967D01*
X1397383Y659467D01*
X1397717Y658883D01*
X1398217Y658467D01*
X1398883Y658300D01*
X1399383Y658383D01*
X1399967Y658717D01*
X1400300Y659050D01*
G01X1408583Y658300D02*
Y661633D01*
G01Y660800D02*
X1408917Y661217D01*
X1409417Y661550D01*
X1410083Y661633D01*
X1410667Y661550D01*
X1411167Y661217D01*
X1411417Y660633D01*
Y658300D01*
G01X1414350Y660550D02*
X1417017D01*
X1416767Y661133D01*
X1416350Y661467D01*
X1415767Y661633D01*
X1415183Y661550D01*
X1414683Y661300D01*
X1414350Y660717D01*
X1414183Y660217D01*
Y659717D01*
X1414350Y659217D01*
X1414767Y658717D01*
X1415267Y658383D01*
X1415850Y658300D01*
X1416433Y658467D01*
X1417017Y658967D01*
G01X1419950Y660550D02*
X1422617D01*
X1422367Y661133D01*
X1421950Y661467D01*
X1421367Y661633D01*
X1420783Y661550D01*
X1420283Y661300D01*
X1419950Y660717D01*
X1419783Y660217D01*
Y659717D01*
X1419950Y659217D01*
X1420367Y658717D01*
X1420867Y658383D01*
X1421450Y658300D01*
X1422033Y658467D01*
X1422617Y658967D01*
G01X1428300Y663300D02*
Y658300D01*
G01Y659050D02*
X1427967Y658633D01*
X1427467Y658383D01*
X1426883Y658300D01*
X1426217Y658467D01*
X1425717Y658883D01*
X1425383Y659383D01*
X1425300Y659967D01*
X1425383Y660550D01*
X1425717Y661050D01*
X1426217Y661467D01*
X1426883Y661633D01*
X1427467Y661550D01*
X1427883Y661383D01*
X1428300Y661050D01*
G01X1125683Y819300D02*
Y822633D01*
G01Y821800D02*
X1126017Y822217D01*
X1126517Y822550D01*
X1127183Y822633D01*
X1127767Y822550D01*
X1128267Y822217D01*
X1128517Y821633D01*
Y819300D01*
G01X1132700D02*
X1132200Y819383D01*
X1131700Y819717D01*
X1131367Y820300D01*
X1131200Y820967D01*
X1131367Y821633D01*
X1131700Y822217D01*
X1132200Y822550D01*
X1132700Y822633D01*
X1133200Y822550D01*
X1133700Y822217D01*
X1134033Y821633D01*
X1134117Y820967D01*
X1134033Y820300D01*
X1133700Y819717D01*
X1133200Y819383D01*
X1132700Y819300D01*
G01X1142400Y817633D02*
Y822633D01*
G01Y821883D02*
X1142817Y822300D01*
X1143233Y822550D01*
X1143900Y822633D01*
X1144483Y822550D01*
X1145067Y822133D01*
X1145317Y821550D01*
X1145400Y820967D01*
X1145317Y820383D01*
X1145067Y819800D01*
X1144567Y819467D01*
X1143900Y819300D01*
X1143317Y819383D01*
X1142733Y819633D01*
X1142400Y819967D01*
G01X1149500Y819300D02*
Y824300D01*
G01X1153683Y822633D02*
Y820300D01*
X1154017Y819717D01*
X1154517Y819383D01*
X1155100Y819300D01*
X1155683Y819383D01*
X1156183Y819717D01*
X1156517Y820300D01*
G01Y819300D02*
Y822633D01*
G01X1159533Y818050D02*
X1160117Y817717D01*
X1160783Y817633D01*
X1161367Y817717D01*
X1161867Y818133D01*
X1162200Y818717D01*
Y822633D01*
G01Y821967D02*
X1161867Y822300D01*
X1161367Y822550D01*
X1160783Y822633D01*
X1160117Y822467D01*
X1159700Y822133D01*
X1159367Y821550D01*
X1159200Y820967D01*
X1159283Y820467D01*
X1159617Y819883D01*
X1160117Y819467D01*
X1160783Y819300D01*
X1161283Y819383D01*
X1161867Y819717D01*
X1162200Y820050D01*
G01X1165133Y818050D02*
X1165717Y817717D01*
X1166383Y817633D01*
X1166967Y817717D01*
X1167467Y818133D01*
X1167800Y818717D01*
Y822633D01*
G01Y821967D02*
X1167467Y822300D01*
X1166967Y822550D01*
X1166383Y822633D01*
X1165717Y822467D01*
X1165300Y822133D01*
X1164967Y821550D01*
X1164800Y820967D01*
X1164883Y820467D01*
X1165217Y819883D01*
X1165717Y819467D01*
X1166383Y819300D01*
X1166883Y819383D01*
X1167467Y819717D01*
X1167800Y820050D01*
G01X1171900Y822633D02*
Y819300D01*
G01Y823967D02*
X1171733Y824050D01*
Y824217D01*
X1171900Y824300D01*
X1172067Y824217D01*
Y824050D01*
X1171900Y823967D01*
G01X1176083Y819300D02*
Y822633D01*
G01Y821800D02*
X1176417Y822217D01*
X1176917Y822550D01*
X1177583Y822633D01*
X1178167Y822550D01*
X1178667Y822217D01*
X1178917Y821633D01*
Y819300D01*
G01X1181933Y818050D02*
X1182517Y817717D01*
X1183183Y817633D01*
X1183767Y817717D01*
X1184267Y818133D01*
X1184600Y818717D01*
Y822633D01*
G01Y821967D02*
X1184267Y822300D01*
X1183767Y822550D01*
X1183183Y822633D01*
X1182517Y822467D01*
X1182100Y822133D01*
X1181767Y821550D01*
X1181600Y820967D01*
X1181683Y820467D01*
X1182017Y819883D01*
X1182517Y819467D01*
X1183183Y819300D01*
X1183683Y819383D01*
X1184267Y819717D01*
X1184600Y820050D01*
G01X1139600Y424800D02*
Y174800D01*
G01X1147100Y459300D02*
Y464300D01*
G01Y461800D02*
X1147517Y462300D01*
X1148017Y462550D01*
X1148517Y462633D01*
X1149267Y462467D01*
X1149767Y462133D01*
X1150100Y461550D01*
Y460883D01*
X1149933Y460217D01*
X1149600Y459717D01*
X1149017Y459383D01*
X1148517Y459300D01*
X1148017Y459383D01*
X1147517Y459633D01*
X1147100Y460050D01*
G01X1152783Y462633D02*
Y460300D01*
X1153117Y459717D01*
X1153617Y459383D01*
X1154200Y459300D01*
X1154783Y459383D01*
X1155283Y459717D01*
X1155617Y460300D01*
G01Y459300D02*
Y462633D01*
G01X1158300Y459300D02*
Y464300D01*
G01Y461800D02*
X1158717Y462300D01*
X1159217Y462550D01*
X1159717Y462633D01*
X1160467Y462467D01*
X1160967Y462133D01*
X1161300Y461550D01*
Y460883D01*
X1161133Y460217D01*
X1160800Y459717D01*
X1160217Y459383D01*
X1159717Y459300D01*
X1159217Y459383D01*
X1158717Y459633D01*
X1158300Y460050D01*
G01X1163900Y459300D02*
Y464300D01*
G01Y461800D02*
X1164317Y462300D01*
X1164817Y462550D01*
X1165317Y462633D01*
X1166067Y462467D01*
X1166567Y462133D01*
X1166900Y461550D01*
Y460883D01*
X1166733Y460217D01*
X1166400Y459717D01*
X1165817Y459383D01*
X1165317Y459300D01*
X1164817Y459383D01*
X1164317Y459633D01*
X1163900Y460050D01*
G01X1171000Y459300D02*
Y464300D01*
G01X1175350Y461550D02*
X1178017D01*
X1177767Y462133D01*
X1177350Y462467D01*
X1176767Y462633D01*
X1176183Y462550D01*
X1175683Y462300D01*
X1175350Y461717D01*
X1175183Y461217D01*
Y460717D01*
X1175350Y460217D01*
X1175767Y459717D01*
X1176267Y459383D01*
X1176850Y459300D01*
X1177433Y459467D01*
X1178017Y459967D01*
G01X1187800Y462633D02*
Y459300D01*
G01Y463967D02*
X1187633Y464050D01*
Y464217D01*
X1187800Y464300D01*
X1187967Y464217D01*
Y464050D01*
X1187800Y463967D01*
G01X1191983Y459300D02*
Y462633D01*
G01Y461800D02*
X1192317Y462217D01*
X1192817Y462550D01*
X1193483Y462633D01*
X1194067Y462550D01*
X1194567Y462217D01*
X1194817Y461633D01*
Y459300D01*
G01X1197750Y459883D02*
X1198167Y459550D01*
X1198750Y459300D01*
X1199250D01*
X1199750Y459467D01*
X1200083Y459717D01*
X1200250Y460050D01*
X1200167Y460550D01*
X1199833Y460800D01*
X1198333Y461300D01*
X1198000Y461883D01*
X1198167Y462300D01*
X1198500Y462550D01*
X1199000Y462633D01*
X1199500Y462550D01*
X1200000Y462300D01*
G01X1204600Y462633D02*
Y459300D01*
G01Y463967D02*
X1204433Y464050D01*
Y464217D01*
X1204600Y464300D01*
X1204767Y464217D01*
Y464050D01*
X1204600Y463967D01*
G01X1211700Y464300D02*
Y459300D01*
G01Y460050D02*
X1211367Y459633D01*
X1210867Y459383D01*
X1210283Y459300D01*
X1209617Y459467D01*
X1209117Y459883D01*
X1208783Y460383D01*
X1208700Y460967D01*
X1208783Y461550D01*
X1209117Y462050D01*
X1209617Y462467D01*
X1210283Y462633D01*
X1210867Y462550D01*
X1211283Y462383D01*
X1211700Y462050D01*
G01X1214550Y461550D02*
X1217217D01*
X1216967Y462133D01*
X1216550Y462467D01*
X1215967Y462633D01*
X1215383Y462550D01*
X1214883Y462300D01*
X1214550Y461717D01*
X1214383Y461217D01*
Y460717D01*
X1214550Y460217D01*
X1214967Y459717D01*
X1215467Y459383D01*
X1216050Y459300D01*
X1216633Y459467D01*
X1217217Y459967D01*
G01X1227000Y464300D02*
Y459300D01*
G01X1225833Y462633D02*
X1228167D01*
G01X1231183Y459300D02*
Y464300D01*
G01Y461883D02*
X1231600Y462300D01*
X1232017Y462550D01*
X1232683Y462633D01*
X1233183Y462550D01*
X1233767Y462217D01*
X1234017Y461717D01*
Y459300D01*
G01X1236950Y461550D02*
X1239617D01*
X1239367Y462133D01*
X1238950Y462467D01*
X1238367Y462633D01*
X1237783Y462550D01*
X1237283Y462300D01*
X1236950Y461717D01*
X1236783Y461217D01*
Y460717D01*
X1236950Y460217D01*
X1237367Y459717D01*
X1237867Y459383D01*
X1238450Y459300D01*
X1239033Y459467D01*
X1239617Y459967D01*
G01X1248233Y459300D02*
Y462633D01*
G01Y461967D02*
X1248650Y462300D01*
X1249067Y462550D01*
X1249650Y462633D01*
X1250067Y462550D01*
X1250567Y462300D01*
G01X1253750Y461550D02*
X1256417D01*
X1256167Y462133D01*
X1255750Y462467D01*
X1255167Y462633D01*
X1254583Y462550D01*
X1254083Y462300D01*
X1253750Y461717D01*
X1253583Y461217D01*
Y460717D01*
X1253750Y460217D01*
X1254167Y459717D01*
X1254667Y459383D01*
X1255250Y459300D01*
X1255833Y459467D01*
X1256417Y459967D01*
G01X1259350Y459883D02*
X1259767Y459550D01*
X1260350Y459300D01*
X1260850D01*
X1261350Y459467D01*
X1261683Y459717D01*
X1261850Y460050D01*
X1261767Y460550D01*
X1261433Y460800D01*
X1259933Y461300D01*
X1259600Y461883D01*
X1259767Y462300D01*
X1260100Y462550D01*
X1260600Y462633D01*
X1261100Y462550D01*
X1261600Y462300D01*
G01X1266200Y462633D02*
Y459300D01*
G01Y463967D02*
X1266033Y464050D01*
Y464217D01*
X1266200Y464300D01*
X1266367Y464217D01*
Y464050D01*
X1266200Y463967D01*
G01X1270383Y459300D02*
Y462633D01*
G01Y461800D02*
X1270717Y462217D01*
X1271217Y462550D01*
X1271883Y462633D01*
X1272467Y462550D01*
X1272967Y462217D01*
X1273217Y461633D01*
Y459300D01*
G01X1277400Y459133D02*
X1277233Y459217D01*
Y459383D01*
X1277400Y459467D01*
X1277567Y459383D01*
Y459217D01*
X1277400Y459133D01*
G01X1147100Y502300D02*
Y507300D01*
G01Y504800D02*
X1147517Y505300D01*
X1148017Y505550D01*
X1148517Y505633D01*
X1149267Y505467D01*
X1149767Y505133D01*
X1150100Y504550D01*
Y503883D01*
X1149933Y503217D01*
X1149600Y502717D01*
X1149017Y502383D01*
X1148517Y502300D01*
X1148017Y502383D01*
X1147517Y502633D01*
X1147100Y503050D01*
G01X1152783Y505633D02*
Y503300D01*
X1153117Y502717D01*
X1153617Y502383D01*
X1154200Y502300D01*
X1154783Y502383D01*
X1155283Y502717D01*
X1155617Y503300D01*
G01Y502300D02*
Y505633D01*
G01X1158300Y502300D02*
Y507300D01*
G01Y504800D02*
X1158717Y505300D01*
X1159217Y505550D01*
X1159717Y505633D01*
X1160467Y505467D01*
X1160967Y505133D01*
X1161300Y504550D01*
Y503883D01*
X1161133Y503217D01*
X1160800Y502717D01*
X1160217Y502383D01*
X1159717Y502300D01*
X1159217Y502383D01*
X1158717Y502633D01*
X1158300Y503050D01*
G01X1163900Y502300D02*
Y507300D01*
G01Y504800D02*
X1164317Y505300D01*
X1164817Y505550D01*
X1165317Y505633D01*
X1166067Y505467D01*
X1166567Y505133D01*
X1166900Y504550D01*
Y503883D01*
X1166733Y503217D01*
X1166400Y502717D01*
X1165817Y502383D01*
X1165317Y502300D01*
X1164817Y502383D01*
X1164317Y502633D01*
X1163900Y503050D01*
G01X1171000Y502300D02*
Y507300D01*
G01X1175350Y504550D02*
X1178017D01*
X1177767Y505133D01*
X1177350Y505467D01*
X1176767Y505633D01*
X1176183Y505550D01*
X1175683Y505300D01*
X1175350Y504717D01*
X1175183Y504217D01*
Y503717D01*
X1175350Y503217D01*
X1175767Y502717D01*
X1176267Y502383D01*
X1176850Y502300D01*
X1177433Y502467D01*
X1178017Y502967D01*
G01X1187800Y505633D02*
Y502300D01*
G01Y506967D02*
X1187633Y507050D01*
Y507217D01*
X1187800Y507300D01*
X1187967Y507217D01*
Y507050D01*
X1187800Y506967D01*
G01X1191983Y502300D02*
Y505633D01*
G01Y504800D02*
X1192317Y505217D01*
X1192817Y505550D01*
X1193483Y505633D01*
X1194067Y505550D01*
X1194567Y505217D01*
X1194817Y504633D01*
Y502300D01*
G01X1197750Y502883D02*
X1198167Y502550D01*
X1198750Y502300D01*
X1199250D01*
X1199750Y502467D01*
X1200083Y502717D01*
X1200250Y503050D01*
X1200167Y503550D01*
X1199833Y503800D01*
X1198333Y504300D01*
X1198000Y504883D01*
X1198167Y505300D01*
X1198500Y505550D01*
X1199000Y505633D01*
X1199500Y505550D01*
X1200000Y505300D01*
G01X1204600Y505633D02*
Y502300D01*
G01Y506967D02*
X1204433Y507050D01*
Y507217D01*
X1204600Y507300D01*
X1204767Y507217D01*
Y507050D01*
X1204600Y506967D01*
G01X1211700Y507300D02*
Y502300D01*
G01Y503050D02*
X1211367Y502633D01*
X1210867Y502383D01*
X1210283Y502300D01*
X1209617Y502467D01*
X1209117Y502883D01*
X1208783Y503383D01*
X1208700Y503967D01*
X1208783Y504550D01*
X1209117Y505050D01*
X1209617Y505467D01*
X1210283Y505633D01*
X1210867Y505550D01*
X1211283Y505383D01*
X1211700Y505050D01*
G01X1214550Y504550D02*
X1217217D01*
X1216967Y505133D01*
X1216550Y505467D01*
X1215967Y505633D01*
X1215383Y505550D01*
X1214883Y505300D01*
X1214550Y504717D01*
X1214383Y504217D01*
Y503717D01*
X1214550Y503217D01*
X1214967Y502717D01*
X1215467Y502383D01*
X1216050Y502300D01*
X1216633Y502467D01*
X1217217Y502967D01*
G01X1227000Y507300D02*
Y502300D01*
G01X1225833Y505633D02*
X1228167D01*
G01X1231183Y502300D02*
Y507300D01*
G01Y504883D02*
X1231600Y505300D01*
X1232017Y505550D01*
X1232683Y505633D01*
X1233183Y505550D01*
X1233767Y505217D01*
X1234017Y504717D01*
Y502300D01*
G01X1236950Y504550D02*
X1239617D01*
X1239367Y505133D01*
X1238950Y505467D01*
X1238367Y505633D01*
X1237783Y505550D01*
X1237283Y505300D01*
X1236950Y504717D01*
X1236783Y504217D01*
Y503717D01*
X1236950Y503217D01*
X1237367Y502717D01*
X1237867Y502383D01*
X1238450Y502300D01*
X1239033Y502467D01*
X1239617Y502967D01*
G01X1248233Y502300D02*
Y505633D01*
G01Y504967D02*
X1248650Y505300D01*
X1249067Y505550D01*
X1249650Y505633D01*
X1250067Y505550D01*
X1250567Y505300D01*
G01X1253750Y504550D02*
X1256417D01*
X1256167Y505133D01*
X1255750Y505467D01*
X1255167Y505633D01*
X1254583Y505550D01*
X1254083Y505300D01*
X1253750Y504717D01*
X1253583Y504217D01*
Y503717D01*
X1253750Y503217D01*
X1254167Y502717D01*
X1254667Y502383D01*
X1255250Y502300D01*
X1255833Y502467D01*
X1256417Y502967D01*
G01X1259350Y502883D02*
X1259767Y502550D01*
X1260350Y502300D01*
X1260850D01*
X1261350Y502467D01*
X1261683Y502717D01*
X1261850Y503050D01*
X1261767Y503550D01*
X1261433Y503800D01*
X1259933Y504300D01*
X1259600Y504883D01*
X1259767Y505300D01*
X1260100Y505550D01*
X1260600Y505633D01*
X1261100Y505550D01*
X1261600Y505300D01*
G01X1266200Y505633D02*
Y502300D01*
G01Y506967D02*
X1266033Y507050D01*
Y507217D01*
X1266200Y507300D01*
X1266367Y507217D01*
Y507050D01*
X1266200Y506967D01*
G01X1270383Y502300D02*
Y505633D01*
G01Y504800D02*
X1270717Y505217D01*
X1271217Y505550D01*
X1271883Y505633D01*
X1272467Y505550D01*
X1272967Y505217D01*
X1273217Y504633D01*
Y502300D01*
G01X1277400Y502133D02*
X1277233Y502217D01*
Y502383D01*
X1277400Y502467D01*
X1277567Y502383D01*
Y502217D01*
X1277400Y502133D01*
G01X1139017Y534300D02*
X1141100Y529300D01*
X1143183Y534300D01*
G01X1146700Y532633D02*
Y529300D01*
G01Y533967D02*
X1146533Y534050D01*
Y534217D01*
X1146700Y534300D01*
X1146867Y534217D01*
Y534050D01*
X1146700Y533967D01*
G01X1153800Y529300D02*
Y532633D01*
G01Y532050D02*
X1153467Y532383D01*
X1152967Y532550D01*
X1152383Y532633D01*
X1151800Y532467D01*
X1151300Y532133D01*
X1150967Y531633D01*
X1150800Y530967D01*
X1150967Y530300D01*
X1151300Y529800D01*
X1151800Y529467D01*
X1152383Y529300D01*
X1152967Y529383D01*
X1153467Y529633D01*
X1153800Y529967D01*
G01X1162250Y529883D02*
X1162667Y529550D01*
X1163250Y529300D01*
X1163750D01*
X1164250Y529467D01*
X1164583Y529717D01*
X1164750Y530050D01*
X1164667Y530550D01*
X1164333Y530800D01*
X1162833Y531300D01*
X1162500Y531883D01*
X1162667Y532300D01*
X1163000Y532550D01*
X1163500Y532633D01*
X1164000Y532550D01*
X1164500Y532300D01*
G01X1167683Y529300D02*
Y534300D01*
G01Y531883D02*
X1168100Y532300D01*
X1168517Y532550D01*
X1169183Y532633D01*
X1169683Y532550D01*
X1170267Y532217D01*
X1170517Y531717D01*
Y529300D01*
G01X1174700D02*
X1174200Y529383D01*
X1173700Y529717D01*
X1173367Y530300D01*
X1173200Y530967D01*
X1173367Y531633D01*
X1173700Y532217D01*
X1174200Y532550D01*
X1174700Y532633D01*
X1175200Y532550D01*
X1175700Y532217D01*
X1176033Y531633D01*
X1176117Y530967D01*
X1176033Y530300D01*
X1175700Y529717D01*
X1175200Y529383D01*
X1174700Y529300D01*
G01X1178883Y532633D02*
Y530300D01*
X1179217Y529717D01*
X1179717Y529383D01*
X1180300Y529300D01*
X1180883Y529383D01*
X1181383Y529717D01*
X1181717Y530300D01*
G01Y529300D02*
Y532633D01*
G01X1185900Y529300D02*
Y534300D01*
G01X1193000D02*
Y529300D01*
G01Y530050D02*
X1192667Y529633D01*
X1192167Y529383D01*
X1191583Y529300D01*
X1190917Y529467D01*
X1190417Y529883D01*
X1190083Y530383D01*
X1190000Y530967D01*
X1190083Y531550D01*
X1190417Y532050D01*
X1190917Y532467D01*
X1191583Y532633D01*
X1192167Y532550D01*
X1192583Y532383D01*
X1193000Y532050D01*
G01X1201200Y529300D02*
Y534300D01*
G01Y531800D02*
X1201617Y532300D01*
X1202117Y532550D01*
X1202617Y532633D01*
X1203367Y532467D01*
X1203867Y532133D01*
X1204200Y531550D01*
Y530883D01*
X1204033Y530217D01*
X1203700Y529717D01*
X1203117Y529383D01*
X1202617Y529300D01*
X1202117Y529383D01*
X1201617Y529633D01*
X1201200Y530050D01*
G01X1207050Y531550D02*
X1209717D01*
X1209467Y532133D01*
X1209050Y532467D01*
X1208467Y532633D01*
X1207883Y532550D01*
X1207383Y532300D01*
X1207050Y531717D01*
X1206883Y531217D01*
Y530717D01*
X1207050Y530217D01*
X1207467Y529717D01*
X1207967Y529383D01*
X1208550Y529300D01*
X1209133Y529467D01*
X1209717Y529967D01*
G01X1218000Y527633D02*
Y532633D01*
G01Y531883D02*
X1218417Y532300D01*
X1218833Y532550D01*
X1219500Y532633D01*
X1220083Y532550D01*
X1220667Y532133D01*
X1220917Y531550D01*
X1221000Y530967D01*
X1220917Y530383D01*
X1220667Y529800D01*
X1220167Y529467D01*
X1219500Y529300D01*
X1218917Y529383D01*
X1218333Y529633D01*
X1218000Y529967D01*
G01X1225100Y529300D02*
Y534300D01*
G01X1229283Y532633D02*
Y530300D01*
X1229617Y529717D01*
X1230117Y529383D01*
X1230700Y529300D01*
X1231283Y529383D01*
X1231783Y529717D01*
X1232117Y530300D01*
G01Y529300D02*
Y532633D01*
G01X1235133Y528050D02*
X1235717Y527717D01*
X1236383Y527633D01*
X1236967Y527717D01*
X1237467Y528133D01*
X1237800Y528717D01*
Y532633D01*
G01Y531967D02*
X1237467Y532300D01*
X1236967Y532550D01*
X1236383Y532633D01*
X1235717Y532467D01*
X1235300Y532133D01*
X1234967Y531550D01*
X1234800Y530967D01*
X1234883Y530467D01*
X1235217Y529883D01*
X1235717Y529467D01*
X1236383Y529300D01*
X1236883Y529383D01*
X1237467Y529717D01*
X1237800Y530050D01*
G01X1240733Y528050D02*
X1241317Y527717D01*
X1241983Y527633D01*
X1242567Y527717D01*
X1243067Y528133D01*
X1243400Y528717D01*
Y532633D01*
G01Y531967D02*
X1243067Y532300D01*
X1242567Y532550D01*
X1241983Y532633D01*
X1241317Y532467D01*
X1240900Y532133D01*
X1240567Y531550D01*
X1240400Y530967D01*
X1240483Y530467D01*
X1240817Y529883D01*
X1241317Y529467D01*
X1241983Y529300D01*
X1242483Y529383D01*
X1243067Y529717D01*
X1243400Y530050D01*
G01X1246250Y531550D02*
X1248917D01*
X1248667Y532133D01*
X1248250Y532467D01*
X1247667Y532633D01*
X1247083Y532550D01*
X1246583Y532300D01*
X1246250Y531717D01*
X1246083Y531217D01*
Y530717D01*
X1246250Y530217D01*
X1246667Y529717D01*
X1247167Y529383D01*
X1247750Y529300D01*
X1248333Y529467D01*
X1248917Y529967D01*
G01X1254600Y534300D02*
Y529300D01*
G01Y530050D02*
X1254267Y529633D01*
X1253767Y529383D01*
X1253183Y529300D01*
X1252517Y529467D01*
X1252017Y529883D01*
X1251683Y530383D01*
X1251600Y530967D01*
X1251683Y531550D01*
X1252017Y532050D01*
X1252517Y532467D01*
X1253183Y532633D01*
X1253767Y532550D01*
X1254183Y532383D01*
X1254600Y532050D01*
G01X1262217Y532633D02*
X1263217Y529300D01*
X1264300Y532633D01*
X1265383Y529300D01*
X1266383Y532633D01*
G01X1269900D02*
Y529300D01*
G01Y533967D02*
X1269733Y534050D01*
Y534217D01*
X1269900Y534300D01*
X1270067Y534217D01*
Y534050D01*
X1269900Y533967D01*
G01X1275500Y534300D02*
Y529300D01*
G01X1274333Y532633D02*
X1276667D01*
G01X1279683Y529300D02*
Y534300D01*
G01Y531883D02*
X1280100Y532300D01*
X1280517Y532550D01*
X1281183Y532633D01*
X1281683Y532550D01*
X1282267Y532217D01*
X1282517Y531717D01*
Y529300D01*
G01X1290633D02*
X1293967Y530967D01*
X1290633Y532633D01*
G01X1296483Y529883D02*
X1297067Y529467D01*
X1297733Y529300D01*
X1298400Y529467D01*
X1298983Y529967D01*
X1299400Y530717D01*
X1299567Y531467D01*
Y532383D01*
X1299400Y533133D01*
X1298983Y533800D01*
X1298483Y534133D01*
X1297900Y534300D01*
X1297233Y534133D01*
X1296733Y533800D01*
X1296400Y533300D01*
X1296233Y532633D01*
X1296400Y532050D01*
X1296817Y531467D01*
X1297317Y531133D01*
X1297900Y531050D01*
X1298567Y531217D01*
X1299067Y531633D01*
X1299567Y532383D01*
G01X1303500Y534300D02*
X1302833Y534133D01*
X1302333Y533717D01*
X1302000Y533217D01*
X1301750Y532550D01*
X1301667Y531800D01*
X1301750Y531050D01*
X1302000Y530383D01*
X1302333Y529883D01*
X1302833Y529467D01*
X1303500Y529300D01*
X1304167Y529467D01*
X1304667Y529883D01*
X1305000Y530383D01*
X1305250Y531050D01*
X1305333Y531800D01*
X1305250Y532550D01*
X1305000Y533217D01*
X1304667Y533717D01*
X1304167Y534133D01*
X1303500Y534300D01*
G01X1307600Y529133D02*
X1310600Y534300D01*
G01X1307600D02*
X1307100Y534133D01*
X1306850Y533883D01*
X1306683Y533383D01*
X1306850Y532883D01*
X1307100Y532633D01*
X1307600Y532467D01*
X1308100Y532633D01*
X1308350Y532883D01*
X1308517Y533383D01*
X1308350Y533883D01*
X1308100Y534133D01*
X1307600Y534300D01*
G01X1310600Y530967D02*
X1310100Y530800D01*
X1309850Y530550D01*
X1309683Y530050D01*
X1309850Y529550D01*
X1310100Y529300D01*
X1310600Y529133D01*
X1311100Y529300D01*
X1311350Y529550D01*
X1311517Y530050D01*
X1311350Y530550D01*
X1311100Y530800D01*
X1310600Y530967D01*
G01X1319133Y529300D02*
Y532633D01*
G01Y531967D02*
X1319550Y532300D01*
X1319967Y532550D01*
X1320550Y532633D01*
X1320967Y532550D01*
X1321467Y532300D01*
G01X1324650Y531550D02*
X1327317D01*
X1327067Y532133D01*
X1326650Y532467D01*
X1326067Y532633D01*
X1325483Y532550D01*
X1324983Y532300D01*
X1324650Y531717D01*
X1324483Y531217D01*
Y530717D01*
X1324650Y530217D01*
X1325067Y529717D01*
X1325567Y529383D01*
X1326150Y529300D01*
X1326733Y529467D01*
X1327317Y529967D01*
G01X1330250Y529883D02*
X1330667Y529550D01*
X1331250Y529300D01*
X1331750D01*
X1332250Y529467D01*
X1332583Y529717D01*
X1332750Y530050D01*
X1332667Y530550D01*
X1332333Y530800D01*
X1330833Y531300D01*
X1330500Y531883D01*
X1330667Y532300D01*
X1331000Y532550D01*
X1331500Y532633D01*
X1332000Y532550D01*
X1332500Y532300D01*
G01X1337100Y532633D02*
Y529300D01*
G01Y533967D02*
X1336933Y534050D01*
Y534217D01*
X1337100Y534300D01*
X1337267Y534217D01*
Y534050D01*
X1337100Y533967D01*
G01X1341283Y529300D02*
Y532633D01*
G01Y531800D02*
X1341617Y532217D01*
X1342117Y532550D01*
X1342783Y532633D01*
X1343367Y532550D01*
X1343867Y532217D01*
X1344117Y531633D01*
Y529300D01*
G01X1137517Y555300D02*
X1139600Y550300D01*
X1141683Y555300D01*
G01X1145200Y553633D02*
Y550300D01*
G01Y554967D02*
X1145033Y555050D01*
Y555217D01*
X1145200Y555300D01*
X1145367Y555217D01*
Y555050D01*
X1145200Y554967D01*
G01X1152300Y550300D02*
Y553633D01*
G01Y553050D02*
X1151967Y553383D01*
X1151467Y553550D01*
X1150883Y553633D01*
X1150300Y553467D01*
X1149800Y553133D01*
X1149467Y552633D01*
X1149300Y551967D01*
X1149467Y551300D01*
X1149800Y550800D01*
X1150300Y550467D01*
X1150883Y550300D01*
X1151467Y550383D01*
X1151967Y550633D01*
X1152300Y550967D01*
G01X1160750Y550883D02*
X1161167Y550550D01*
X1161750Y550300D01*
X1162250D01*
X1162750Y550467D01*
X1163083Y550717D01*
X1163250Y551050D01*
X1163167Y551550D01*
X1162833Y551800D01*
X1161333Y552300D01*
X1161000Y552883D01*
X1161167Y553300D01*
X1161500Y553550D01*
X1162000Y553633D01*
X1162500Y553550D01*
X1163000Y553300D01*
G01X1166183Y550300D02*
Y555300D01*
G01Y552883D02*
X1166600Y553300D01*
X1167017Y553550D01*
X1167683Y553633D01*
X1168183Y553550D01*
X1168767Y553217D01*
X1169017Y552717D01*
Y550300D01*
G01X1173200D02*
X1172700Y550383D01*
X1172200Y550717D01*
X1171867Y551300D01*
X1171700Y551967D01*
X1171867Y552633D01*
X1172200Y553217D01*
X1172700Y553550D01*
X1173200Y553633D01*
X1173700Y553550D01*
X1174200Y553217D01*
X1174533Y552633D01*
X1174617Y551967D01*
X1174533Y551300D01*
X1174200Y550717D01*
X1173700Y550383D01*
X1173200Y550300D01*
G01X1177383Y553633D02*
Y551300D01*
X1177717Y550717D01*
X1178217Y550383D01*
X1178800Y550300D01*
X1179383Y550383D01*
X1179883Y550717D01*
X1180217Y551300D01*
G01Y550300D02*
Y553633D01*
G01X1184400Y550300D02*
Y555300D01*
G01X1191500D02*
Y550300D01*
G01Y551050D02*
X1191167Y550633D01*
X1190667Y550383D01*
X1190083Y550300D01*
X1189417Y550467D01*
X1188917Y550883D01*
X1188583Y551383D01*
X1188500Y551967D01*
X1188583Y552550D01*
X1188917Y553050D01*
X1189417Y553467D01*
X1190083Y553633D01*
X1190667Y553550D01*
X1191083Y553383D01*
X1191500Y553050D01*
G01X1199700Y550300D02*
Y555300D01*
G01Y552800D02*
X1200117Y553300D01*
X1200617Y553550D01*
X1201117Y553633D01*
X1201867Y553467D01*
X1202367Y553133D01*
X1202700Y552550D01*
Y551883D01*
X1202533Y551217D01*
X1202200Y550717D01*
X1201617Y550383D01*
X1201117Y550300D01*
X1200617Y550383D01*
X1200117Y550633D01*
X1199700Y551050D01*
G01X1205550Y552550D02*
X1208217D01*
X1207967Y553133D01*
X1207550Y553467D01*
X1206967Y553633D01*
X1206383Y553550D01*
X1205883Y553300D01*
X1205550Y552717D01*
X1205383Y552217D01*
Y551717D01*
X1205550Y551217D01*
X1205967Y550717D01*
X1206467Y550383D01*
X1207050Y550300D01*
X1207633Y550467D01*
X1208217Y550967D01*
G01X1216500Y548633D02*
Y553633D01*
G01Y552883D02*
X1216917Y553300D01*
X1217333Y553550D01*
X1218000Y553633D01*
X1218583Y553550D01*
X1219167Y553133D01*
X1219417Y552550D01*
X1219500Y551967D01*
X1219417Y551383D01*
X1219167Y550800D01*
X1218667Y550467D01*
X1218000Y550300D01*
X1217417Y550383D01*
X1216833Y550633D01*
X1216500Y550967D01*
G01X1223600Y550300D02*
Y555300D01*
G01X1227783Y553633D02*
Y551300D01*
X1228117Y550717D01*
X1228617Y550383D01*
X1229200Y550300D01*
X1229783Y550383D01*
X1230283Y550717D01*
X1230617Y551300D01*
G01Y550300D02*
Y553633D01*
G01X1233633Y549050D02*
X1234217Y548717D01*
X1234883Y548633D01*
X1235467Y548717D01*
X1235967Y549133D01*
X1236300Y549717D01*
Y553633D01*
G01Y552967D02*
X1235967Y553300D01*
X1235467Y553550D01*
X1234883Y553633D01*
X1234217Y553467D01*
X1233800Y553133D01*
X1233467Y552550D01*
X1233300Y551967D01*
X1233383Y551467D01*
X1233717Y550883D01*
X1234217Y550467D01*
X1234883Y550300D01*
X1235383Y550383D01*
X1235967Y550717D01*
X1236300Y551050D01*
G01X1239233Y549050D02*
X1239817Y548717D01*
X1240483Y548633D01*
X1241067Y548717D01*
X1241567Y549133D01*
X1241900Y549717D01*
Y553633D01*
G01Y552967D02*
X1241567Y553300D01*
X1241067Y553550D01*
X1240483Y553633D01*
X1239817Y553467D01*
X1239400Y553133D01*
X1239067Y552550D01*
X1238900Y551967D01*
X1238983Y551467D01*
X1239317Y550883D01*
X1239817Y550467D01*
X1240483Y550300D01*
X1240983Y550383D01*
X1241567Y550717D01*
X1241900Y551050D01*
G01X1244750Y552550D02*
X1247417D01*
X1247167Y553133D01*
X1246750Y553467D01*
X1246167Y553633D01*
X1245583Y553550D01*
X1245083Y553300D01*
X1244750Y552717D01*
X1244583Y552217D01*
Y551717D01*
X1244750Y551217D01*
X1245167Y550717D01*
X1245667Y550383D01*
X1246250Y550300D01*
X1246833Y550467D01*
X1247417Y550967D01*
G01X1253100Y555300D02*
Y550300D01*
G01Y551050D02*
X1252767Y550633D01*
X1252267Y550383D01*
X1251683Y550300D01*
X1251017Y550467D01*
X1250517Y550883D01*
X1250183Y551383D01*
X1250100Y551967D01*
X1250183Y552550D01*
X1250517Y553050D01*
X1251017Y553467D01*
X1251683Y553633D01*
X1252267Y553550D01*
X1252683Y553383D01*
X1253100Y553050D01*
G01X1263800Y550300D02*
Y555300D01*
X1260717Y551717D01*
X1264883D01*
G01X1268400Y555300D02*
X1267733Y555133D01*
X1267233Y554717D01*
X1266900Y554217D01*
X1266650Y553550D01*
X1266567Y552800D01*
X1266650Y552050D01*
X1266900Y551383D01*
X1267233Y550883D01*
X1267733Y550467D01*
X1268400Y550300D01*
X1269067Y550467D01*
X1269567Y550883D01*
X1269900Y551383D01*
X1270150Y552050D01*
X1270233Y552800D01*
X1270150Y553550D01*
X1269900Y554217D01*
X1269567Y554717D01*
X1269067Y555133D01*
X1268400Y555300D01*
G01X1272500Y550133D02*
X1275500Y555300D01*
G01X1272500D02*
X1272000Y555133D01*
X1271750Y554883D01*
X1271583Y554383D01*
X1271750Y553883D01*
X1272000Y553633D01*
X1272500Y553467D01*
X1273000Y553633D01*
X1273250Y553883D01*
X1273417Y554383D01*
X1273250Y554883D01*
X1273000Y555133D01*
X1272500Y555300D01*
G01X1275500Y551967D02*
X1275000Y551800D01*
X1274750Y551550D01*
X1274583Y551050D01*
X1274750Y550550D01*
X1275000Y550300D01*
X1275500Y550133D01*
X1276000Y550300D01*
X1276250Y550550D01*
X1276417Y551050D01*
X1276250Y551550D01*
X1276000Y551800D01*
X1275500Y551967D01*
G01X1282700D02*
X1283533Y553633D01*
X1284367D01*
X1286033Y550300D01*
X1286867D01*
X1287700Y551967D01*
G01X1296400Y550300D02*
Y555300D01*
X1295400Y554300D01*
G01Y550300D02*
X1297400D01*
G01X1302000Y555300D02*
X1301333Y555133D01*
X1300833Y554717D01*
X1300500Y554217D01*
X1300250Y553550D01*
X1300167Y552800D01*
X1300250Y552050D01*
X1300500Y551383D01*
X1300833Y550883D01*
X1301333Y550467D01*
X1302000Y550300D01*
X1302667Y550467D01*
X1303167Y550883D01*
X1303500Y551383D01*
X1303750Y552050D01*
X1303833Y552800D01*
X1303750Y553550D01*
X1303500Y554217D01*
X1303167Y554717D01*
X1302667Y555133D01*
X1302000Y555300D01*
G01X1307600D02*
X1306933Y555133D01*
X1306433Y554717D01*
X1306100Y554217D01*
X1305850Y553550D01*
X1305767Y552800D01*
X1305850Y552050D01*
X1306100Y551383D01*
X1306433Y550883D01*
X1306933Y550467D01*
X1307600Y550300D01*
X1308267Y550467D01*
X1308767Y550883D01*
X1309100Y551383D01*
X1309350Y552050D01*
X1309433Y552800D01*
X1309350Y553550D01*
X1309100Y554217D01*
X1308767Y554717D01*
X1308267Y555133D01*
X1307600Y555300D01*
G01X1311700Y550133D02*
X1314700Y555300D01*
G01X1311700D02*
X1311200Y555133D01*
X1310950Y554883D01*
X1310783Y554383D01*
X1310950Y553883D01*
X1311200Y553633D01*
X1311700Y553467D01*
X1312200Y553633D01*
X1312450Y553883D01*
X1312617Y554383D01*
X1312450Y554883D01*
X1312200Y555133D01*
X1311700Y555300D01*
G01X1314700Y551967D02*
X1314200Y551800D01*
X1313950Y551550D01*
X1313783Y551050D01*
X1313950Y550550D01*
X1314200Y550300D01*
X1314700Y550133D01*
X1315200Y550300D01*
X1315450Y550550D01*
X1315617Y551050D01*
X1315450Y551550D01*
X1315200Y551800D01*
X1314700Y551967D01*
G01X1323150Y550883D02*
X1323567Y550550D01*
X1324150Y550300D01*
X1324650D01*
X1325150Y550467D01*
X1325483Y550717D01*
X1325650Y551050D01*
X1325567Y551550D01*
X1325233Y551800D01*
X1323733Y552300D01*
X1323400Y552883D01*
X1323567Y553300D01*
X1323900Y553550D01*
X1324400Y553633D01*
X1324900Y553550D01*
X1325400Y553300D01*
G01X1330000Y550300D02*
X1329500Y550383D01*
X1329000Y550717D01*
X1328667Y551300D01*
X1328500Y551967D01*
X1328667Y552633D01*
X1329000Y553217D01*
X1329500Y553550D01*
X1330000Y553633D01*
X1330500Y553550D01*
X1331000Y553217D01*
X1331333Y552633D01*
X1331417Y551967D01*
X1331333Y551300D01*
X1331000Y550717D01*
X1330500Y550383D01*
X1330000Y550300D01*
G01X1335600D02*
Y555300D01*
G01X1342700D02*
Y550300D01*
G01Y551050D02*
X1342367Y550633D01*
X1341867Y550383D01*
X1341283Y550300D01*
X1340617Y550467D01*
X1340117Y550883D01*
X1339783Y551383D01*
X1339700Y551967D01*
X1339783Y552550D01*
X1340117Y553050D01*
X1340617Y553467D01*
X1341283Y553633D01*
X1341867Y553550D01*
X1342283Y553383D01*
X1342700Y553050D01*
G01X1345550Y552550D02*
X1348217D01*
X1347967Y553133D01*
X1347550Y553467D01*
X1346967Y553633D01*
X1346383Y553550D01*
X1345883Y553300D01*
X1345550Y552717D01*
X1345383Y552217D01*
Y551717D01*
X1345550Y551217D01*
X1345967Y550717D01*
X1346467Y550383D01*
X1347050Y550300D01*
X1347633Y550467D01*
X1348217Y550967D01*
G01X1351233Y550300D02*
Y553633D01*
G01Y552967D02*
X1351650Y553300D01*
X1352067Y553550D01*
X1352650Y553633D01*
X1353067Y553550D01*
X1353567Y553300D01*
G01X1361100Y550300D02*
Y553633D01*
G01Y552717D02*
X1361350Y553133D01*
X1361767Y553467D01*
X1362350Y553633D01*
X1362933Y553467D01*
X1363350Y553133D01*
X1363600Y552717D01*
Y550300D01*
G01Y552717D02*
X1363850Y553133D01*
X1364267Y553467D01*
X1364850Y553633D01*
X1365433Y553467D01*
X1365850Y553133D01*
X1366100Y552633D01*
Y550300D01*
G01X1370700D02*
Y553633D01*
G01Y553050D02*
X1370367Y553383D01*
X1369867Y553550D01*
X1369283Y553633D01*
X1368700Y553467D01*
X1368200Y553133D01*
X1367867Y552633D01*
X1367700Y551967D01*
X1367867Y551300D01*
X1368200Y550800D01*
X1368700Y550467D01*
X1369283Y550300D01*
X1369867Y550383D01*
X1370367Y550633D01*
X1370700Y550967D01*
G01X1373550Y550883D02*
X1373967Y550550D01*
X1374550Y550300D01*
X1375050D01*
X1375550Y550467D01*
X1375883Y550717D01*
X1376050Y551050D01*
X1375967Y551550D01*
X1375633Y551800D01*
X1374133Y552300D01*
X1373800Y552883D01*
X1373967Y553300D01*
X1374300Y553550D01*
X1374800Y553633D01*
X1375300Y553550D01*
X1375800Y553300D01*
G01X1378983Y550300D02*
Y555300D01*
G01X1381650Y553633D02*
X1378983Y551717D01*
G01X1380067Y552467D02*
X1381817Y550300D01*
G01X1160100Y574633D02*
X1161600Y571300D01*
X1163100Y574633D01*
G01X1167200D02*
Y571300D01*
G01Y575967D02*
X1167033Y576050D01*
Y576217D01*
X1167200Y576300D01*
X1167367Y576217D01*
Y576050D01*
X1167200Y575967D01*
G01X1174300Y571300D02*
Y574633D01*
G01Y574050D02*
X1173967Y574383D01*
X1173467Y574550D01*
X1172883Y574633D01*
X1172300Y574467D01*
X1171800Y574133D01*
X1171467Y573633D01*
X1171300Y572967D01*
X1171467Y572300D01*
X1171800Y571800D01*
X1172300Y571467D01*
X1172883Y571300D01*
X1173467Y571383D01*
X1173967Y571633D01*
X1174300Y571967D01*
G01X1182750Y571883D02*
X1183167Y571550D01*
X1183750Y571300D01*
X1184250D01*
X1184750Y571467D01*
X1185083Y571717D01*
X1185250Y572050D01*
X1185167Y572550D01*
X1184833Y572800D01*
X1183333Y573300D01*
X1183000Y573883D01*
X1183167Y574300D01*
X1183500Y574550D01*
X1184000Y574633D01*
X1184500Y574550D01*
X1185000Y574300D01*
G01X1188183Y571300D02*
Y576300D01*
G01Y573883D02*
X1188600Y574300D01*
X1189017Y574550D01*
X1189683Y574633D01*
X1190183Y574550D01*
X1190767Y574217D01*
X1191017Y573717D01*
Y571300D01*
G01X1196700D02*
Y574633D01*
G01Y574050D02*
X1196367Y574383D01*
X1195867Y574550D01*
X1195283Y574633D01*
X1194700Y574467D01*
X1194200Y574133D01*
X1193867Y573633D01*
X1193700Y572967D01*
X1193867Y572300D01*
X1194200Y571800D01*
X1194700Y571467D01*
X1195283Y571300D01*
X1195867Y571383D01*
X1196367Y571633D01*
X1196700Y571967D01*
G01X1200800Y571300D02*
Y576300D01*
G01X1206400Y571300D02*
Y576300D01*
G01X1216100Y571300D02*
Y576300D01*
G01Y573800D02*
X1216517Y574300D01*
X1217017Y574550D01*
X1217517Y574633D01*
X1218267Y574467D01*
X1218767Y574133D01*
X1219100Y573550D01*
Y572883D01*
X1218933Y572217D01*
X1218600Y571717D01*
X1218017Y571383D01*
X1217517Y571300D01*
X1217017Y571383D01*
X1216517Y571633D01*
X1216100Y572050D01*
G01X1221950Y573550D02*
X1224617D01*
X1224367Y574133D01*
X1223950Y574467D01*
X1223367Y574633D01*
X1222783Y574550D01*
X1222283Y574300D01*
X1221950Y573717D01*
X1221783Y573217D01*
Y572717D01*
X1221950Y572217D01*
X1222367Y571717D01*
X1222867Y571383D01*
X1223450Y571300D01*
X1224033Y571467D01*
X1224617Y571967D01*
G01X1232317Y574633D02*
X1233317Y571300D01*
X1234400Y574633D01*
X1235483Y571300D01*
X1236483Y574633D01*
G01X1240000D02*
Y571300D01*
G01Y575967D02*
X1239833Y576050D01*
Y576217D01*
X1240000Y576300D01*
X1240167Y576217D01*
Y576050D01*
X1240000Y575967D01*
G01X1245600Y576300D02*
Y571300D01*
G01X1244433Y574633D02*
X1246767D01*
G01X1249783Y571300D02*
Y576300D01*
G01Y573883D02*
X1250200Y574300D01*
X1250617Y574550D01*
X1251283Y574633D01*
X1251783Y574550D01*
X1252367Y574217D01*
X1252617Y573717D01*
Y571300D01*
G01X1264067D02*
X1260733Y572967D01*
X1264067Y574633D01*
G01X1273600Y571300D02*
X1274183Y571383D01*
X1274850Y571633D01*
X1275267Y572050D01*
X1275433Y572633D01*
X1275267Y573217D01*
X1274767Y573717D01*
X1274017Y573967D01*
X1273183D01*
X1272683Y574133D01*
X1272267Y574550D01*
X1272100Y575133D01*
X1272350Y575717D01*
X1272933Y576133D01*
X1273600Y576300D01*
X1274267Y576133D01*
X1274850Y575717D01*
X1275100Y575133D01*
X1274933Y574550D01*
X1274517Y574133D01*
X1274017Y573967D01*
X1273183D01*
X1272433Y573717D01*
X1271933Y573217D01*
X1271767Y572633D01*
X1271933Y572050D01*
X1272350Y571633D01*
X1273017Y571383D01*
X1273600Y571300D01*
G01X1279200Y576300D02*
X1278533Y576133D01*
X1278033Y575717D01*
X1277700Y575217D01*
X1277450Y574550D01*
X1277367Y573800D01*
X1277450Y573050D01*
X1277700Y572383D01*
X1278033Y571883D01*
X1278533Y571467D01*
X1279200Y571300D01*
X1279867Y571467D01*
X1280367Y571883D01*
X1280700Y572383D01*
X1280950Y573050D01*
X1281033Y573800D01*
X1280950Y574550D01*
X1280700Y575217D01*
X1280367Y575717D01*
X1279867Y576133D01*
X1279200Y576300D01*
G01X1288900Y571133D02*
X1291900Y576300D01*
G01X1288900D02*
X1288400Y576133D01*
X1288150Y575883D01*
X1287983Y575383D01*
X1288150Y574883D01*
X1288400Y574633D01*
X1288900Y574467D01*
X1289400Y574633D01*
X1289650Y574883D01*
X1289817Y575383D01*
X1289650Y575883D01*
X1289400Y576133D01*
X1288900Y576300D01*
G01X1291900Y572967D02*
X1291400Y572800D01*
X1291150Y572550D01*
X1290983Y572050D01*
X1291150Y571550D01*
X1291400Y571300D01*
X1291900Y571133D01*
X1292400Y571300D01*
X1292650Y571550D01*
X1292817Y572050D01*
X1292650Y572550D01*
X1292400Y572800D01*
X1291900Y572967D01*
G01X1300350Y571883D02*
X1300767Y571550D01*
X1301350Y571300D01*
X1301850D01*
X1302350Y571467D01*
X1302683Y571717D01*
X1302850Y572050D01*
X1302767Y572550D01*
X1302433Y572800D01*
X1300933Y573300D01*
X1300600Y573883D01*
X1300767Y574300D01*
X1301100Y574550D01*
X1301600Y574633D01*
X1302100Y574550D01*
X1302600Y574300D01*
G01X1307200Y571300D02*
X1306700Y571383D01*
X1306200Y571717D01*
X1305867Y572300D01*
X1305700Y572967D01*
X1305867Y573633D01*
X1306200Y574217D01*
X1306700Y574550D01*
X1307200Y574633D01*
X1307700Y574550D01*
X1308200Y574217D01*
X1308533Y573633D01*
X1308617Y572967D01*
X1308533Y572300D01*
X1308200Y571717D01*
X1307700Y571383D01*
X1307200Y571300D01*
G01X1312800D02*
Y576300D01*
G01X1319900D02*
Y571300D01*
G01Y572050D02*
X1319567Y571633D01*
X1319067Y571383D01*
X1318483Y571300D01*
X1317817Y571467D01*
X1317317Y571883D01*
X1316983Y572383D01*
X1316900Y572967D01*
X1316983Y573550D01*
X1317317Y574050D01*
X1317817Y574467D01*
X1318483Y574633D01*
X1319067Y574550D01*
X1319483Y574383D01*
X1319900Y574050D01*
G01X1322750Y573550D02*
X1325417D01*
X1325167Y574133D01*
X1324750Y574467D01*
X1324167Y574633D01*
X1323583Y574550D01*
X1323083Y574300D01*
X1322750Y573717D01*
X1322583Y573217D01*
Y572717D01*
X1322750Y572217D01*
X1323167Y571717D01*
X1323667Y571383D01*
X1324250Y571300D01*
X1324833Y571467D01*
X1325417Y571967D01*
G01X1328433Y571300D02*
Y574633D01*
G01Y573967D02*
X1328850Y574300D01*
X1329267Y574550D01*
X1329850Y574633D01*
X1330267Y574550D01*
X1330767Y574300D01*
G01X1338300Y571300D02*
Y574633D01*
G01Y573717D02*
X1338550Y574133D01*
X1338967Y574467D01*
X1339550Y574633D01*
X1340133Y574467D01*
X1340550Y574133D01*
X1340800Y573717D01*
Y571300D01*
G01Y573717D02*
X1341050Y574133D01*
X1341467Y574467D01*
X1342050Y574633D01*
X1342633Y574467D01*
X1343050Y574133D01*
X1343300Y573633D01*
Y571300D01*
G01X1347900D02*
Y574633D01*
G01Y574050D02*
X1347567Y574383D01*
X1347067Y574550D01*
X1346483Y574633D01*
X1345900Y574467D01*
X1345400Y574133D01*
X1345067Y573633D01*
X1344900Y572967D01*
X1345067Y572300D01*
X1345400Y571800D01*
X1345900Y571467D01*
X1346483Y571300D01*
X1347067Y571383D01*
X1347567Y571633D01*
X1347900Y571967D01*
G01X1350750Y571883D02*
X1351167Y571550D01*
X1351750Y571300D01*
X1352250D01*
X1352750Y571467D01*
X1353083Y571717D01*
X1353250Y572050D01*
X1353167Y572550D01*
X1352833Y572800D01*
X1351333Y573300D01*
X1351000Y573883D01*
X1351167Y574300D01*
X1351500Y574550D01*
X1352000Y574633D01*
X1352500Y574550D01*
X1353000Y574300D01*
G01X1356183Y571300D02*
Y576300D01*
G01X1358850Y574633D02*
X1356183Y572717D01*
G01X1357267Y573467D02*
X1359017Y571300D01*
G01X1149100Y580300D02*
Y585300D01*
G01Y582800D02*
X1149517Y583300D01*
X1150017Y583550D01*
X1150517Y583633D01*
X1151267Y583467D01*
X1151767Y583133D01*
X1152100Y582550D01*
Y581883D01*
X1151933Y581217D01*
X1151600Y580717D01*
X1151017Y580383D01*
X1150517Y580300D01*
X1150017Y580383D01*
X1149517Y580633D01*
X1149100Y581050D01*
G01X1156200Y580133D02*
X1156033Y580217D01*
Y580383D01*
X1156200Y580467D01*
X1156367Y580383D01*
Y580217D01*
X1156200Y580133D01*
G01X1162467Y582967D02*
X1162800Y583217D01*
X1163050Y583633D01*
X1163217Y584217D01*
X1163050Y584717D01*
X1162717Y585050D01*
X1162133Y585300D01*
X1159883D01*
Y580300D01*
X1162633D01*
X1163217Y580633D01*
X1163550Y581133D01*
X1163717Y581717D01*
X1163550Y582300D01*
X1163050Y582800D01*
X1162467Y582967D01*
X1159883D01*
G01X1167400Y580300D02*
X1166900Y580383D01*
X1166400Y580717D01*
X1166067Y581300D01*
X1165900Y581967D01*
X1166067Y582633D01*
X1166400Y583217D01*
X1166900Y583550D01*
X1167400Y583633D01*
X1167900Y583550D01*
X1168400Y583217D01*
X1168733Y582633D01*
X1168817Y581967D01*
X1168733Y581300D01*
X1168400Y580717D01*
X1167900Y580383D01*
X1167400Y580300D01*
G01X1174500D02*
Y583633D01*
G01Y583050D02*
X1174167Y583383D01*
X1173667Y583550D01*
X1173083Y583633D01*
X1172500Y583467D01*
X1172000Y583133D01*
X1171667Y582633D01*
X1171500Y581967D01*
X1171667Y581300D01*
X1172000Y580800D01*
X1172500Y580467D01*
X1173083Y580300D01*
X1173667Y580383D01*
X1174167Y580633D01*
X1174500Y580967D01*
G01X1177433Y580300D02*
Y583633D01*
G01Y582967D02*
X1177850Y583300D01*
X1178267Y583550D01*
X1178850Y583633D01*
X1179267Y583550D01*
X1179767Y583300D01*
G01X1185700Y585300D02*
Y580300D01*
G01Y581050D02*
X1185367Y580633D01*
X1184867Y580383D01*
X1184283Y580300D01*
X1183617Y580467D01*
X1183117Y580883D01*
X1182783Y581383D01*
X1182700Y581967D01*
X1182783Y582550D01*
X1183117Y583050D01*
X1183617Y583467D01*
X1184283Y583633D01*
X1184867Y583550D01*
X1185283Y583383D01*
X1185700Y583050D01*
G01X1195400Y585300D02*
Y580300D01*
G01X1194233Y583633D02*
X1196567D01*
G01X1199583Y580300D02*
Y585300D01*
G01Y582883D02*
X1200000Y583300D01*
X1200417Y583550D01*
X1201083Y583633D01*
X1201583Y583550D01*
X1202167Y583217D01*
X1202417Y582717D01*
Y580300D01*
G01X1206600Y583633D02*
Y580300D01*
G01Y584967D02*
X1206433Y585050D01*
Y585217D01*
X1206600Y585300D01*
X1206767Y585217D01*
Y585050D01*
X1206600Y584967D01*
G01X1213533Y583217D02*
X1212950Y583550D01*
X1212450Y583633D01*
X1211783Y583467D01*
X1211283Y583133D01*
X1210950Y582550D01*
X1210867Y581967D01*
X1210950Y581383D01*
X1211283Y580883D01*
X1211783Y580467D01*
X1212450Y580300D01*
X1213033Y580467D01*
X1213533Y580800D01*
G01X1216383Y580300D02*
Y585300D01*
G01X1219050Y583633D02*
X1216383Y581717D01*
G01X1217467Y582467D02*
X1219217Y580300D01*
G01X1221983D02*
Y583633D01*
G01Y582800D02*
X1222317Y583217D01*
X1222817Y583550D01*
X1223483Y583633D01*
X1224067Y583550D01*
X1224567Y583217D01*
X1224817Y582633D01*
Y580300D01*
G01X1227750Y582550D02*
X1230417D01*
X1230167Y583133D01*
X1229750Y583467D01*
X1229167Y583633D01*
X1228583Y583550D01*
X1228083Y583300D01*
X1227750Y582717D01*
X1227583Y582217D01*
Y581717D01*
X1227750Y581217D01*
X1228167Y580717D01*
X1228667Y580383D01*
X1229250Y580300D01*
X1229833Y580467D01*
X1230417Y580967D01*
G01X1233350Y580883D02*
X1233767Y580550D01*
X1234350Y580300D01*
X1234850D01*
X1235350Y580467D01*
X1235683Y580717D01*
X1235850Y581050D01*
X1235767Y581550D01*
X1235433Y581800D01*
X1233933Y582300D01*
X1233600Y582883D01*
X1233767Y583300D01*
X1234100Y583550D01*
X1234600Y583633D01*
X1235100Y583550D01*
X1235600Y583300D01*
G01X1238950Y580883D02*
X1239367Y580550D01*
X1239950Y580300D01*
X1240450D01*
X1240950Y580467D01*
X1241283Y580717D01*
X1241450Y581050D01*
X1241367Y581550D01*
X1241033Y581800D01*
X1239533Y582300D01*
X1239200Y582883D01*
X1239367Y583300D01*
X1239700Y583550D01*
X1240200Y583633D01*
X1240700Y583550D01*
X1241200Y583300D01*
G01X1253067Y580300D02*
X1249733Y581967D01*
X1253067Y583633D01*
G01X1262600Y585300D02*
X1261933Y585133D01*
X1261433Y584717D01*
X1261100Y584217D01*
X1260850Y583550D01*
X1260767Y582800D01*
X1260850Y582050D01*
X1261100Y581383D01*
X1261433Y580883D01*
X1261933Y580467D01*
X1262600Y580300D01*
X1263267Y580467D01*
X1263767Y580883D01*
X1264100Y581383D01*
X1264350Y582050D01*
X1264433Y582800D01*
X1264350Y583550D01*
X1264100Y584217D01*
X1263767Y584717D01*
X1263267Y585133D01*
X1262600Y585300D01*
G01X1268200Y580133D02*
X1268033Y580217D01*
Y580383D01*
X1268200Y580467D01*
X1268367Y580383D01*
Y580217D01*
X1268200Y580133D01*
G01X1272383Y580883D02*
X1272967Y580467D01*
X1273633Y580300D01*
X1274300Y580467D01*
X1274883Y580967D01*
X1275300Y581717D01*
X1275467Y582467D01*
Y583383D01*
X1275300Y584133D01*
X1274883Y584800D01*
X1274383Y585133D01*
X1273800Y585300D01*
X1273133Y585133D01*
X1272633Y584800D01*
X1272300Y584300D01*
X1272133Y583633D01*
X1272300Y583050D01*
X1272717Y582467D01*
X1273217Y582133D01*
X1273800Y582050D01*
X1274467Y582217D01*
X1274967Y582633D01*
X1275467Y583383D01*
G01X1276900Y580300D02*
Y583633D01*
G01Y582717D02*
X1277150Y583133D01*
X1277567Y583467D01*
X1278150Y583633D01*
X1278733Y583467D01*
X1279150Y583133D01*
X1279400Y582717D01*
Y580300D01*
G01Y582717D02*
X1279650Y583133D01*
X1280067Y583467D01*
X1280650Y583633D01*
X1281233Y583467D01*
X1281650Y583133D01*
X1281900Y582633D01*
Y580300D01*
G01X1282500D02*
Y583633D01*
G01Y582717D02*
X1282750Y583133D01*
X1283167Y583467D01*
X1283750Y583633D01*
X1284333Y583467D01*
X1284750Y583133D01*
X1285000Y582717D01*
Y580300D01*
G01Y582717D02*
X1285250Y583133D01*
X1285667Y583467D01*
X1286250Y583633D01*
X1286833Y583467D01*
X1287250Y583133D01*
X1287500Y582633D01*
Y580300D01*
G01X1290600Y580133D02*
X1290433Y580217D01*
Y580383D01*
X1290600Y580467D01*
X1290767Y580383D01*
Y580217D01*
X1290600Y580133D01*
G01Y582383D02*
X1290433Y582467D01*
Y582633D01*
X1290600Y582717D01*
X1290767Y582633D01*
Y582467D01*
X1290600Y582383D01*
G01X1159100Y593633D02*
X1160600Y590300D01*
X1162100Y593633D01*
G01X1166200D02*
Y590300D01*
G01Y594967D02*
X1166033Y595050D01*
Y595217D01*
X1166200Y595300D01*
X1166367Y595217D01*
Y595050D01*
X1166200Y594967D01*
G01X1173300Y590300D02*
Y593633D01*
G01Y593050D02*
X1172967Y593383D01*
X1172467Y593550D01*
X1171883Y593633D01*
X1171300Y593467D01*
X1170800Y593133D01*
X1170467Y592633D01*
X1170300Y591967D01*
X1170467Y591300D01*
X1170800Y590800D01*
X1171300Y590467D01*
X1171883Y590300D01*
X1172467Y590383D01*
X1172967Y590633D01*
X1173300Y590967D01*
G01X1181750Y590883D02*
X1182167Y590550D01*
X1182750Y590300D01*
X1183250D01*
X1183750Y590467D01*
X1184083Y590717D01*
X1184250Y591050D01*
X1184167Y591550D01*
X1183833Y591800D01*
X1182333Y592300D01*
X1182000Y592883D01*
X1182167Y593300D01*
X1182500Y593550D01*
X1183000Y593633D01*
X1183500Y593550D01*
X1184000Y593300D01*
G01X1187183Y590300D02*
Y595300D01*
G01Y592883D02*
X1187600Y593300D01*
X1188017Y593550D01*
X1188683Y593633D01*
X1189183Y593550D01*
X1189767Y593217D01*
X1190017Y592717D01*
Y590300D01*
G01X1195700D02*
Y593633D01*
G01Y593050D02*
X1195367Y593383D01*
X1194867Y593550D01*
X1194283Y593633D01*
X1193700Y593467D01*
X1193200Y593133D01*
X1192867Y592633D01*
X1192700Y591967D01*
X1192867Y591300D01*
X1193200Y590800D01*
X1193700Y590467D01*
X1194283Y590300D01*
X1194867Y590383D01*
X1195367Y590633D01*
X1195700Y590967D01*
G01X1199800Y590300D02*
Y595300D01*
G01X1205400Y590300D02*
Y595300D01*
G01X1215100Y590300D02*
Y595300D01*
G01Y592800D02*
X1215517Y593300D01*
X1216017Y593550D01*
X1216517Y593633D01*
X1217267Y593467D01*
X1217767Y593133D01*
X1218100Y592550D01*
Y591883D01*
X1217933Y591217D01*
X1217600Y590717D01*
X1217017Y590383D01*
X1216517Y590300D01*
X1216017Y590383D01*
X1215517Y590633D01*
X1215100Y591050D01*
G01X1220950Y592550D02*
X1223617D01*
X1223367Y593133D01*
X1222950Y593467D01*
X1222367Y593633D01*
X1221783Y593550D01*
X1221283Y593300D01*
X1220950Y592717D01*
X1220783Y592217D01*
Y591717D01*
X1220950Y591217D01*
X1221367Y590717D01*
X1221867Y590383D01*
X1222450Y590300D01*
X1223033Y590467D01*
X1223617Y590967D01*
G01X1231900Y588633D02*
Y593633D01*
G01Y592883D02*
X1232317Y593300D01*
X1232733Y593550D01*
X1233400Y593633D01*
X1233983Y593550D01*
X1234567Y593133D01*
X1234817Y592550D01*
X1234900Y591967D01*
X1234817Y591383D01*
X1234567Y590800D01*
X1234067Y590467D01*
X1233400Y590300D01*
X1232817Y590383D01*
X1232233Y590633D01*
X1231900Y590967D01*
G01X1239000Y590300D02*
Y595300D01*
G01X1243183Y593633D02*
Y591300D01*
X1243517Y590717D01*
X1244017Y590383D01*
X1244600Y590300D01*
X1245183Y590383D01*
X1245683Y590717D01*
X1246017Y591300D01*
G01Y590300D02*
Y593633D01*
G01X1249033Y589050D02*
X1249617Y588717D01*
X1250283Y588633D01*
X1250867Y588717D01*
X1251367Y589133D01*
X1251700Y589717D01*
Y593633D01*
G01Y592967D02*
X1251367Y593300D01*
X1250867Y593550D01*
X1250283Y593633D01*
X1249617Y593467D01*
X1249200Y593133D01*
X1248867Y592550D01*
X1248700Y591967D01*
X1248783Y591467D01*
X1249117Y590883D01*
X1249617Y590467D01*
X1250283Y590300D01*
X1250783Y590383D01*
X1251367Y590717D01*
X1251700Y591050D01*
G01X1254633Y589050D02*
X1255217Y588717D01*
X1255883Y588633D01*
X1256467Y588717D01*
X1256967Y589133D01*
X1257300Y589717D01*
Y593633D01*
G01Y592967D02*
X1256967Y593300D01*
X1256467Y593550D01*
X1255883Y593633D01*
X1255217Y593467D01*
X1254800Y593133D01*
X1254467Y592550D01*
X1254300Y591967D01*
X1254383Y591467D01*
X1254717Y590883D01*
X1255217Y590467D01*
X1255883Y590300D01*
X1256383Y590383D01*
X1256967Y590717D01*
X1257300Y591050D01*
G01X1260150Y592550D02*
X1262817D01*
X1262567Y593133D01*
X1262150Y593467D01*
X1261567Y593633D01*
X1260983Y593550D01*
X1260483Y593300D01*
X1260150Y592717D01*
X1259983Y592217D01*
Y591717D01*
X1260150Y591217D01*
X1260567Y590717D01*
X1261067Y590383D01*
X1261650Y590300D01*
X1262233Y590467D01*
X1262817Y590967D01*
G01X1268500Y595300D02*
Y590300D01*
G01Y591050D02*
X1268167Y590633D01*
X1267667Y590383D01*
X1267083Y590300D01*
X1266417Y590467D01*
X1265917Y590883D01*
X1265583Y591383D01*
X1265500Y591967D01*
X1265583Y592550D01*
X1265917Y593050D01*
X1266417Y593467D01*
X1267083Y593633D01*
X1267667Y593550D01*
X1268083Y593383D01*
X1268500Y593050D01*
G01X1276117Y593633D02*
X1277117Y590300D01*
X1278200Y593633D01*
X1279283Y590300D01*
X1280283Y593633D01*
G01X1283800D02*
Y590300D01*
G01Y594967D02*
X1283633Y595050D01*
Y595217D01*
X1283800Y595300D01*
X1283967Y595217D01*
Y595050D01*
X1283800Y594967D01*
G01X1289400Y595300D02*
Y590300D01*
G01X1288233Y593633D02*
X1290567D01*
G01X1293583Y590300D02*
Y595300D01*
G01Y592883D02*
X1294000Y593300D01*
X1294417Y593550D01*
X1295083Y593633D01*
X1295583Y593550D01*
X1296167Y593217D01*
X1296417Y592717D01*
Y590300D01*
G01X1307867D02*
X1304533Y591967D01*
X1307867Y593633D01*
G01X1315567Y591050D02*
X1316067Y590633D01*
X1316650Y590383D01*
X1317400Y590300D01*
X1318150Y590467D01*
X1318733Y590800D01*
X1319150Y591383D01*
X1319233Y592050D01*
X1319067Y592717D01*
X1318650Y593133D01*
X1318067Y593467D01*
X1317483Y593550D01*
X1316900Y593467D01*
X1316150Y593133D01*
X1316400Y595300D01*
X1318650D01*
G01X1323000D02*
X1322333Y595133D01*
X1321833Y594717D01*
X1321500Y594217D01*
X1321250Y593550D01*
X1321167Y592800D01*
X1321250Y592050D01*
X1321500Y591383D01*
X1321833Y590883D01*
X1322333Y590467D01*
X1323000Y590300D01*
X1323667Y590467D01*
X1324167Y590883D01*
X1324500Y591383D01*
X1324750Y592050D01*
X1324833Y592800D01*
X1324750Y593550D01*
X1324500Y594217D01*
X1324167Y594717D01*
X1323667Y595133D01*
X1323000Y595300D01*
G01X1332700Y590133D02*
X1335700Y595300D01*
G01X1332700D02*
X1332200Y595133D01*
X1331950Y594883D01*
X1331783Y594383D01*
X1331950Y593883D01*
X1332200Y593633D01*
X1332700Y593467D01*
X1333200Y593633D01*
X1333450Y593883D01*
X1333617Y594383D01*
X1333450Y594883D01*
X1333200Y595133D01*
X1332700Y595300D01*
G01X1335700Y591967D02*
X1335200Y591800D01*
X1334950Y591550D01*
X1334783Y591050D01*
X1334950Y590550D01*
X1335200Y590300D01*
X1335700Y590133D01*
X1336200Y590300D01*
X1336450Y590550D01*
X1336617Y591050D01*
X1336450Y591550D01*
X1336200Y591800D01*
X1335700Y591967D01*
G01X1344150Y590883D02*
X1344567Y590550D01*
X1345150Y590300D01*
X1345650D01*
X1346150Y590467D01*
X1346483Y590717D01*
X1346650Y591050D01*
X1346567Y591550D01*
X1346233Y591800D01*
X1344733Y592300D01*
X1344400Y592883D01*
X1344567Y593300D01*
X1344900Y593550D01*
X1345400Y593633D01*
X1345900Y593550D01*
X1346400Y593300D01*
G01X1351000Y590300D02*
X1350500Y590383D01*
X1350000Y590717D01*
X1349667Y591300D01*
X1349500Y591967D01*
X1349667Y592633D01*
X1350000Y593217D01*
X1350500Y593550D01*
X1351000Y593633D01*
X1351500Y593550D01*
X1352000Y593217D01*
X1352333Y592633D01*
X1352417Y591967D01*
X1352333Y591300D01*
X1352000Y590717D01*
X1351500Y590383D01*
X1351000Y590300D01*
G01X1356600D02*
Y595300D01*
G01X1363700D02*
Y590300D01*
G01Y591050D02*
X1363367Y590633D01*
X1362867Y590383D01*
X1362283Y590300D01*
X1361617Y590467D01*
X1361117Y590883D01*
X1360783Y591383D01*
X1360700Y591967D01*
X1360783Y592550D01*
X1361117Y593050D01*
X1361617Y593467D01*
X1362283Y593633D01*
X1362867Y593550D01*
X1363283Y593383D01*
X1363700Y593050D01*
G01X1366550Y592550D02*
X1369217D01*
X1368967Y593133D01*
X1368550Y593467D01*
X1367967Y593633D01*
X1367383Y593550D01*
X1366883Y593300D01*
X1366550Y592717D01*
X1366383Y592217D01*
Y591717D01*
X1366550Y591217D01*
X1366967Y590717D01*
X1367467Y590383D01*
X1368050Y590300D01*
X1368633Y590467D01*
X1369217Y590967D01*
G01X1372233Y590300D02*
Y593633D01*
G01Y592967D02*
X1372650Y593300D01*
X1373067Y593550D01*
X1373650Y593633D01*
X1374067Y593550D01*
X1374567Y593300D01*
G01X1382100Y590300D02*
Y593633D01*
G01Y592717D02*
X1382350Y593133D01*
X1382767Y593467D01*
X1383350Y593633D01*
X1383933Y593467D01*
X1384350Y593133D01*
X1384600Y592717D01*
Y590300D01*
G01Y592717D02*
X1384850Y593133D01*
X1385267Y593467D01*
X1385850Y593633D01*
X1386433Y593467D01*
X1386850Y593133D01*
X1387100Y592633D01*
Y590300D01*
G01X1391700D02*
Y593633D01*
G01Y593050D02*
X1391367Y593383D01*
X1390867Y593550D01*
X1390283Y593633D01*
X1389700Y593467D01*
X1389200Y593133D01*
X1388867Y592633D01*
X1388700Y591967D01*
X1388867Y591300D01*
X1389200Y590800D01*
X1389700Y590467D01*
X1390283Y590300D01*
X1390867Y590383D01*
X1391367Y590633D01*
X1391700Y590967D01*
G01X1394550Y590883D02*
X1394967Y590550D01*
X1395550Y590300D01*
X1396050D01*
X1396550Y590467D01*
X1396883Y590717D01*
X1397050Y591050D01*
X1396967Y591550D01*
X1396633Y591800D01*
X1395133Y592300D01*
X1394800Y592883D01*
X1394967Y593300D01*
X1395300Y593550D01*
X1395800Y593633D01*
X1396300Y593550D01*
X1396800Y593300D01*
G01X1399983Y590300D02*
Y595300D01*
G01X1402650Y593633D02*
X1399983Y591717D01*
G01X1401067Y592467D02*
X1402817Y590300D01*
G01X1406833Y589383D02*
X1407167Y590467D01*
G01X1152100Y599300D02*
Y602633D01*
G01Y602050D02*
X1151767Y602383D01*
X1151267Y602550D01*
X1150683Y602633D01*
X1150100Y602467D01*
X1149600Y602133D01*
X1149267Y601633D01*
X1149100Y600967D01*
X1149267Y600300D01*
X1149600Y599800D01*
X1150100Y599467D01*
X1150683Y599300D01*
X1151267Y599383D01*
X1151767Y599633D01*
X1152100Y599967D01*
G01X1156200Y599133D02*
X1156033Y599217D01*
Y599383D01*
X1156200Y599467D01*
X1156367Y599383D01*
Y599217D01*
X1156200Y599133D01*
G01X1162467Y601967D02*
X1162800Y602217D01*
X1163050Y602633D01*
X1163217Y603217D01*
X1163050Y603717D01*
X1162717Y604050D01*
X1162133Y604300D01*
X1159883D01*
Y599300D01*
X1162633D01*
X1163217Y599633D01*
X1163550Y600133D01*
X1163717Y600717D01*
X1163550Y601300D01*
X1163050Y601800D01*
X1162467Y601967D01*
X1159883D01*
G01X1167400Y599300D02*
X1166900Y599383D01*
X1166400Y599717D01*
X1166067Y600300D01*
X1165900Y600967D01*
X1166067Y601633D01*
X1166400Y602217D01*
X1166900Y602550D01*
X1167400Y602633D01*
X1167900Y602550D01*
X1168400Y602217D01*
X1168733Y601633D01*
X1168817Y600967D01*
X1168733Y600300D01*
X1168400Y599717D01*
X1167900Y599383D01*
X1167400Y599300D01*
G01X1174500D02*
Y602633D01*
G01Y602050D02*
X1174167Y602383D01*
X1173667Y602550D01*
X1173083Y602633D01*
X1172500Y602467D01*
X1172000Y602133D01*
X1171667Y601633D01*
X1171500Y600967D01*
X1171667Y600300D01*
X1172000Y599800D01*
X1172500Y599467D01*
X1173083Y599300D01*
X1173667Y599383D01*
X1174167Y599633D01*
X1174500Y599967D01*
G01X1177433Y599300D02*
Y602633D01*
G01Y601967D02*
X1177850Y602300D01*
X1178267Y602550D01*
X1178850Y602633D01*
X1179267Y602550D01*
X1179767Y602300D01*
G01X1185700Y604300D02*
Y599300D01*
G01Y600050D02*
X1185367Y599633D01*
X1184867Y599383D01*
X1184283Y599300D01*
X1183617Y599467D01*
X1183117Y599883D01*
X1182783Y600383D01*
X1182700Y600967D01*
X1182783Y601550D01*
X1183117Y602050D01*
X1183617Y602467D01*
X1184283Y602633D01*
X1184867Y602550D01*
X1185283Y602383D01*
X1185700Y602050D01*
G01X1195400Y604300D02*
Y599300D01*
G01X1194233Y602633D02*
X1196567D01*
G01X1199583Y599300D02*
Y604300D01*
G01Y601883D02*
X1200000Y602300D01*
X1200417Y602550D01*
X1201083Y602633D01*
X1201583Y602550D01*
X1202167Y602217D01*
X1202417Y601717D01*
Y599300D01*
G01X1206600Y602633D02*
Y599300D01*
G01Y603967D02*
X1206433Y604050D01*
Y604217D01*
X1206600Y604300D01*
X1206767Y604217D01*
Y604050D01*
X1206600Y603967D01*
G01X1213533Y602217D02*
X1212950Y602550D01*
X1212450Y602633D01*
X1211783Y602467D01*
X1211283Y602133D01*
X1210950Y601550D01*
X1210867Y600967D01*
X1210950Y600383D01*
X1211283Y599883D01*
X1211783Y599467D01*
X1212450Y599300D01*
X1213033Y599467D01*
X1213533Y599800D01*
G01X1216383Y599300D02*
Y604300D01*
G01X1219050Y602633D02*
X1216383Y600717D01*
G01X1217467Y601467D02*
X1219217Y599300D01*
G01X1221983D02*
Y602633D01*
G01Y601800D02*
X1222317Y602217D01*
X1222817Y602550D01*
X1223483Y602633D01*
X1224067Y602550D01*
X1224567Y602217D01*
X1224817Y601633D01*
Y599300D01*
G01X1227750Y601550D02*
X1230417D01*
X1230167Y602133D01*
X1229750Y602467D01*
X1229167Y602633D01*
X1228583Y602550D01*
X1228083Y602300D01*
X1227750Y601717D01*
X1227583Y601217D01*
Y600717D01*
X1227750Y600217D01*
X1228167Y599717D01*
X1228667Y599383D01*
X1229250Y599300D01*
X1229833Y599467D01*
X1230417Y599967D01*
G01X1233350Y599883D02*
X1233767Y599550D01*
X1234350Y599300D01*
X1234850D01*
X1235350Y599467D01*
X1235683Y599717D01*
X1235850Y600050D01*
X1235767Y600550D01*
X1235433Y600800D01*
X1233933Y601300D01*
X1233600Y601883D01*
X1233767Y602300D01*
X1234100Y602550D01*
X1234600Y602633D01*
X1235100Y602550D01*
X1235600Y602300D01*
G01X1238950Y599883D02*
X1239367Y599550D01*
X1239950Y599300D01*
X1240450D01*
X1240950Y599467D01*
X1241283Y599717D01*
X1241450Y600050D01*
X1241367Y600550D01*
X1241033Y600800D01*
X1239533Y601300D01*
X1239200Y601883D01*
X1239367Y602300D01*
X1239700Y602550D01*
X1240200Y602633D01*
X1240700Y602550D01*
X1241200Y602300D01*
G01X1244133Y599300D02*
X1247467Y600967D01*
X1244133Y602633D01*
G01X1250317Y600217D02*
X1252483D01*
G01Y601717D02*
X1250317D01*
G01X1262600Y604300D02*
X1261933Y604133D01*
X1261433Y603717D01*
X1261100Y603217D01*
X1260850Y602550D01*
X1260767Y601800D01*
X1260850Y601050D01*
X1261100Y600383D01*
X1261433Y599883D01*
X1261933Y599467D01*
X1262600Y599300D01*
X1263267Y599467D01*
X1263767Y599883D01*
X1264100Y600383D01*
X1264350Y601050D01*
X1264433Y601800D01*
X1264350Y602550D01*
X1264100Y603217D01*
X1263767Y603717D01*
X1263267Y604133D01*
X1262600Y604300D01*
G01X1268200Y599133D02*
X1268033Y599217D01*
Y599383D01*
X1268200Y599467D01*
X1268367Y599383D01*
Y599217D01*
X1268200Y599133D01*
G01X1272383Y599883D02*
X1272967Y599467D01*
X1273633Y599300D01*
X1274300Y599467D01*
X1274883Y599967D01*
X1275300Y600717D01*
X1275467Y601467D01*
Y602383D01*
X1275300Y603133D01*
X1274883Y603800D01*
X1274383Y604133D01*
X1273800Y604300D01*
X1273133Y604133D01*
X1272633Y603800D01*
X1272300Y603300D01*
X1272133Y602633D01*
X1272300Y602050D01*
X1272717Y601467D01*
X1273217Y601133D01*
X1273800Y601050D01*
X1274467Y601217D01*
X1274967Y601633D01*
X1275467Y602383D01*
G01X1276900Y599300D02*
Y602633D01*
G01Y601717D02*
X1277150Y602133D01*
X1277567Y602467D01*
X1278150Y602633D01*
X1278733Y602467D01*
X1279150Y602133D01*
X1279400Y601717D01*
Y599300D01*
G01Y601717D02*
X1279650Y602133D01*
X1280067Y602467D01*
X1280650Y602633D01*
X1281233Y602467D01*
X1281650Y602133D01*
X1281900Y601633D01*
Y599300D01*
G01X1285000Y599133D02*
X1284833Y599217D01*
Y599383D01*
X1285000Y599467D01*
X1285167Y599383D01*
Y599217D01*
X1285000Y599133D01*
G01Y601383D02*
X1284833Y601467D01*
Y601633D01*
X1285000Y601717D01*
X1285167Y601633D01*
Y601467D01*
X1285000Y601383D01*
G01X1147850Y609300D02*
Y614300D01*
G01X1151350D02*
Y609300D01*
G01Y611800D02*
X1147850D01*
G01X1156700Y609300D02*
Y612633D01*
G01Y612050D02*
X1156367Y612383D01*
X1155867Y612550D01*
X1155283Y612633D01*
X1154700Y612467D01*
X1154200Y612133D01*
X1153867Y611633D01*
X1153700Y610967D01*
X1153867Y610300D01*
X1154200Y609800D01*
X1154700Y609467D01*
X1155283Y609300D01*
X1155867Y609383D01*
X1156367Y609633D01*
X1156700Y609967D01*
G01X1160800Y609300D02*
Y614300D01*
G01X1165900Y609300D02*
Y613550D01*
X1166067Y613967D01*
X1166400Y614217D01*
X1166900Y614300D01*
X1167400Y614133D01*
X1167650Y613717D01*
G01X1166650Y612300D02*
X1164983D01*
G01X1170917Y610967D02*
X1173083D01*
G01X1176100Y607633D02*
Y612633D01*
G01Y611883D02*
X1176517Y612300D01*
X1176933Y612550D01*
X1177600Y612633D01*
X1178183Y612550D01*
X1178767Y612133D01*
X1179017Y611550D01*
X1179100Y610967D01*
X1179017Y610383D01*
X1178767Y609800D01*
X1178267Y609467D01*
X1177600Y609300D01*
X1177017Y609383D01*
X1176433Y609633D01*
X1176100Y609967D01*
G01X1183200Y609300D02*
Y614300D01*
G01X1187383Y612633D02*
Y610300D01*
X1187717Y609717D01*
X1188217Y609383D01*
X1188800Y609300D01*
X1189383Y609383D01*
X1189883Y609717D01*
X1190217Y610300D01*
G01Y609300D02*
Y612633D01*
G01X1193233Y608050D02*
X1193817Y607717D01*
X1194483Y607633D01*
X1195067Y607717D01*
X1195567Y608133D01*
X1195900Y608717D01*
Y612633D01*
G01Y611967D02*
X1195567Y612300D01*
X1195067Y612550D01*
X1194483Y612633D01*
X1193817Y612467D01*
X1193400Y612133D01*
X1193067Y611550D01*
X1192900Y610967D01*
X1192983Y610467D01*
X1193317Y609883D01*
X1193817Y609467D01*
X1194483Y609300D01*
X1194983Y609383D01*
X1195567Y609717D01*
X1195900Y610050D01*
G01X1198833Y608050D02*
X1199417Y607717D01*
X1200083Y607633D01*
X1200667Y607717D01*
X1201167Y608133D01*
X1201500Y608717D01*
Y612633D01*
G01Y611967D02*
X1201167Y612300D01*
X1200667Y612550D01*
X1200083Y612633D01*
X1199417Y612467D01*
X1199000Y612133D01*
X1198667Y611550D01*
X1198500Y610967D01*
X1198583Y610467D01*
X1198917Y609883D01*
X1199417Y609467D01*
X1200083Y609300D01*
X1200583Y609383D01*
X1201167Y609717D01*
X1201500Y610050D01*
G01X1205600Y612633D02*
Y609300D01*
G01Y613967D02*
X1205433Y614050D01*
Y614217D01*
X1205600Y614300D01*
X1205767Y614217D01*
Y614050D01*
X1205600Y613967D01*
G01X1209783Y609300D02*
Y612633D01*
G01Y611800D02*
X1210117Y612217D01*
X1210617Y612550D01*
X1211283Y612633D01*
X1211867Y612550D01*
X1212367Y612217D01*
X1212617Y611633D01*
Y609300D01*
G01X1215633Y608050D02*
X1216217Y607717D01*
X1216883Y607633D01*
X1217467Y607717D01*
X1217967Y608133D01*
X1218300Y608717D01*
Y612633D01*
G01Y611967D02*
X1217967Y612300D01*
X1217467Y612550D01*
X1216883Y612633D01*
X1216217Y612467D01*
X1215800Y612133D01*
X1215467Y611550D01*
X1215300Y610967D01*
X1215383Y610467D01*
X1215717Y609883D01*
X1216217Y609467D01*
X1216883Y609300D01*
X1217383Y609383D01*
X1217967Y609717D01*
X1218300Y610050D01*
G01X1228000Y609133D02*
X1227833Y609217D01*
Y609383D01*
X1228000Y609467D01*
X1228167Y609383D01*
Y609217D01*
X1228000Y609133D01*
G01Y611383D02*
X1227833Y611467D01*
Y611633D01*
X1228000Y611717D01*
X1228167Y611633D01*
Y611467D01*
X1228000Y611383D01*
G01X1239200Y614300D02*
Y609300D01*
G01X1238033Y612633D02*
X1240367D01*
G01X1243383Y609300D02*
Y614300D01*
G01Y611883D02*
X1243800Y612300D01*
X1244217Y612550D01*
X1244883Y612633D01*
X1245383Y612550D01*
X1245967Y612217D01*
X1246217Y611717D01*
Y609300D01*
G01X1249150Y611550D02*
X1251817D01*
X1251567Y612133D01*
X1251150Y612467D01*
X1250567Y612633D01*
X1249983Y612550D01*
X1249483Y612300D01*
X1249150Y611717D01*
X1248983Y611217D01*
Y610717D01*
X1249150Y610217D01*
X1249567Y609717D01*
X1250067Y609383D01*
X1250650Y609300D01*
X1251233Y609467D01*
X1251817Y609967D01*
G01X1260100Y607633D02*
Y612633D01*
G01Y611883D02*
X1260517Y612300D01*
X1260933Y612550D01*
X1261600Y612633D01*
X1262183Y612550D01*
X1262767Y612133D01*
X1263017Y611550D01*
X1263100Y610967D01*
X1263017Y610383D01*
X1262767Y609800D01*
X1262267Y609467D01*
X1261600Y609300D01*
X1261017Y609383D01*
X1260433Y609633D01*
X1260100Y609967D01*
G01X1267200Y609300D02*
Y614300D01*
G01X1271383Y612633D02*
Y610300D01*
X1271717Y609717D01*
X1272217Y609383D01*
X1272800Y609300D01*
X1273383Y609383D01*
X1273883Y609717D01*
X1274217Y610300D01*
G01Y609300D02*
Y612633D01*
G01X1277233Y608050D02*
X1277817Y607717D01*
X1278483Y607633D01*
X1279067Y607717D01*
X1279567Y608133D01*
X1279900Y608717D01*
Y612633D01*
G01Y611967D02*
X1279567Y612300D01*
X1279067Y612550D01*
X1278483Y612633D01*
X1277817Y612467D01*
X1277400Y612133D01*
X1277067Y611550D01*
X1276900Y610967D01*
X1276983Y610467D01*
X1277317Y609883D01*
X1277817Y609467D01*
X1278483Y609300D01*
X1278983Y609383D01*
X1279567Y609717D01*
X1279900Y610050D01*
G01X1282833Y608050D02*
X1283417Y607717D01*
X1284083Y607633D01*
X1284667Y607717D01*
X1285167Y608133D01*
X1285500Y608717D01*
Y612633D01*
G01Y611967D02*
X1285167Y612300D01*
X1284667Y612550D01*
X1284083Y612633D01*
X1283417Y612467D01*
X1283000Y612133D01*
X1282667Y611550D01*
X1282500Y610967D01*
X1282583Y610467D01*
X1282917Y609883D01*
X1283417Y609467D01*
X1284083Y609300D01*
X1284583Y609383D01*
X1285167Y609717D01*
X1285500Y610050D01*
G01X1289600Y612633D02*
Y609300D01*
G01Y613967D02*
X1289433Y614050D01*
Y614217D01*
X1289600Y614300D01*
X1289767Y614217D01*
Y614050D01*
X1289600Y613967D01*
G01X1293783Y609300D02*
Y612633D01*
G01Y611800D02*
X1294117Y612217D01*
X1294617Y612550D01*
X1295283Y612633D01*
X1295867Y612550D01*
X1296367Y612217D01*
X1296617Y611633D01*
Y609300D01*
G01X1299633Y608050D02*
X1300217Y607717D01*
X1300883Y607633D01*
X1301467Y607717D01*
X1301967Y608133D01*
X1302300Y608717D01*
Y612633D01*
G01Y611967D02*
X1301967Y612300D01*
X1301467Y612550D01*
X1300883Y612633D01*
X1300217Y612467D01*
X1299800Y612133D01*
X1299467Y611550D01*
X1299300Y610967D01*
X1299383Y610467D01*
X1299717Y609883D01*
X1300217Y609467D01*
X1300883Y609300D01*
X1301383Y609383D01*
X1301967Y609717D01*
X1302300Y610050D01*
G01X1310833Y609300D02*
Y612633D01*
G01Y611967D02*
X1311250Y612300D01*
X1311667Y612550D01*
X1312250Y612633D01*
X1312667Y612550D01*
X1313167Y612300D01*
G01X1319100Y609300D02*
Y612633D01*
G01Y612050D02*
X1318767Y612383D01*
X1318267Y612550D01*
X1317683Y612633D01*
X1317100Y612467D01*
X1316600Y612133D01*
X1316267Y611633D01*
X1316100Y610967D01*
X1316267Y610300D01*
X1316600Y609800D01*
X1317100Y609467D01*
X1317683Y609300D01*
X1318267Y609383D01*
X1318767Y609633D01*
X1319100Y609967D01*
G01X1323200Y614300D02*
Y609300D01*
G01X1322033Y612633D02*
X1324367D01*
G01X1328800D02*
Y609300D01*
G01Y613967D02*
X1328633Y614050D01*
Y614217D01*
X1328800Y614300D01*
X1328967Y614217D01*
Y614050D01*
X1328800Y613967D01*
G01X1334400Y609300D02*
X1333900Y609383D01*
X1333400Y609717D01*
X1333067Y610300D01*
X1332900Y610967D01*
X1333067Y611633D01*
X1333400Y612217D01*
X1333900Y612550D01*
X1334400Y612633D01*
X1334900Y612550D01*
X1335400Y612217D01*
X1335733Y611633D01*
X1335817Y610967D01*
X1335733Y610300D01*
X1335400Y609717D01*
X1334900Y609383D01*
X1334400Y609300D01*
G01X1344100Y607633D02*
Y612633D01*
G01Y611883D02*
X1344517Y612300D01*
X1344933Y612550D01*
X1345600Y612633D01*
X1346183Y612550D01*
X1346767Y612133D01*
X1347017Y611550D01*
X1347100Y610967D01*
X1347017Y610383D01*
X1346767Y609800D01*
X1346267Y609467D01*
X1345600Y609300D01*
X1345017Y609383D01*
X1344433Y609633D01*
X1344100Y609967D01*
G01X1349950Y611550D02*
X1352617D01*
X1352367Y612133D01*
X1351950Y612467D01*
X1351367Y612633D01*
X1350783Y612550D01*
X1350283Y612300D01*
X1349950Y611717D01*
X1349783Y611217D01*
Y610717D01*
X1349950Y610217D01*
X1350367Y609717D01*
X1350867Y609383D01*
X1351450Y609300D01*
X1352033Y609467D01*
X1352617Y609967D01*
G01X1355633Y609300D02*
Y612633D01*
G01Y611967D02*
X1356050Y612300D01*
X1356467Y612550D01*
X1357050Y612633D01*
X1357467Y612550D01*
X1357967Y612300D01*
G01X1367500Y609300D02*
Y613550D01*
X1367667Y613967D01*
X1368000Y614217D01*
X1368500Y614300D01*
X1369000Y614133D01*
X1369250Y613717D01*
G01X1368250Y612300D02*
X1366583D01*
G01X1373600Y609300D02*
X1373100Y609383D01*
X1372600Y609717D01*
X1372267Y610300D01*
X1372100Y610967D01*
X1372267Y611633D01*
X1372600Y612217D01*
X1373100Y612550D01*
X1373600Y612633D01*
X1374100Y612550D01*
X1374600Y612217D01*
X1374933Y611633D01*
X1375017Y610967D01*
X1374933Y610300D01*
X1374600Y609717D01*
X1374100Y609383D01*
X1373600Y609300D01*
G01X1379200D02*
Y614300D01*
G01X1384800Y609300D02*
Y614300D01*
G01X1390400Y609300D02*
X1389900Y609383D01*
X1389400Y609717D01*
X1389067Y610300D01*
X1388900Y610967D01*
X1389067Y611633D01*
X1389400Y612217D01*
X1389900Y612550D01*
X1390400Y612633D01*
X1390900Y612550D01*
X1391400Y612217D01*
X1391733Y611633D01*
X1391817Y610967D01*
X1391733Y610300D01*
X1391400Y609717D01*
X1390900Y609383D01*
X1390400Y609300D01*
G01X1393917Y612633D02*
X1394917Y609300D01*
X1396000Y612633D01*
X1397083Y609300D01*
X1398083Y612633D01*
G01X1401600D02*
Y609300D01*
G01Y613967D02*
X1401433Y614050D01*
Y614217D01*
X1401600Y614300D01*
X1401767Y614217D01*
Y614050D01*
X1401600Y613967D01*
G01X1405783Y609300D02*
Y612633D01*
G01Y611800D02*
X1406117Y612217D01*
X1406617Y612550D01*
X1407283Y612633D01*
X1407867Y612550D01*
X1408367Y612217D01*
X1408617Y611633D01*
Y609300D01*
G01X1411633Y608050D02*
X1412217Y607717D01*
X1412883Y607633D01*
X1413467Y607717D01*
X1413967Y608133D01*
X1414300Y608717D01*
Y612633D01*
G01Y611967D02*
X1413967Y612300D01*
X1413467Y612550D01*
X1412883Y612633D01*
X1412217Y612467D01*
X1411800Y612133D01*
X1411467Y611550D01*
X1411300Y610967D01*
X1411383Y610467D01*
X1411717Y609883D01*
X1412217Y609467D01*
X1412883Y609300D01*
X1413383Y609383D01*
X1413967Y609717D01*
X1414300Y610050D01*
G01X1418400Y609133D02*
X1418233Y609217D01*
Y609383D01*
X1418400Y609467D01*
X1418567Y609383D01*
Y609217D01*
X1418400Y609133D01*
G01Y611383D02*
X1418233Y611467D01*
Y611633D01*
X1418400Y611717D01*
X1418567Y611633D01*
Y611467D01*
X1418400Y611383D01*
G01X1147100Y618300D02*
Y623300D01*
G01Y620800D02*
X1147517Y621300D01*
X1148017Y621550D01*
X1148517Y621633D01*
X1149267Y621467D01*
X1149767Y621133D01*
X1150100Y620550D01*
Y619883D01*
X1149933Y619217D01*
X1149600Y618717D01*
X1149017Y618383D01*
X1148517Y618300D01*
X1148017Y618383D01*
X1147517Y618633D01*
X1147100Y619050D01*
G01X1152950Y620550D02*
X1155617D01*
X1155367Y621133D01*
X1154950Y621467D01*
X1154367Y621633D01*
X1153783Y621550D01*
X1153283Y621300D01*
X1152950Y620717D01*
X1152783Y620217D01*
Y619717D01*
X1152950Y619217D01*
X1153367Y618717D01*
X1153867Y618383D01*
X1154450Y618300D01*
X1155033Y618467D01*
X1155617Y618967D01*
G01X1164900Y618300D02*
Y622550D01*
X1165067Y622967D01*
X1165400Y623217D01*
X1165900Y623300D01*
X1166400Y623133D01*
X1166650Y622717D01*
G01X1165650Y621300D02*
X1163983D01*
G01X1169833Y618300D02*
Y621633D01*
G01Y620967D02*
X1170250Y621300D01*
X1170667Y621550D01*
X1171250Y621633D01*
X1171667Y621550D01*
X1172167Y621300D01*
G01X1175350Y620550D02*
X1178017D01*
X1177767Y621133D01*
X1177350Y621467D01*
X1176767Y621633D01*
X1176183Y621550D01*
X1175683Y621300D01*
X1175350Y620717D01*
X1175183Y620217D01*
Y619717D01*
X1175350Y619217D01*
X1175767Y618717D01*
X1176267Y618383D01*
X1176850Y618300D01*
X1177433Y618467D01*
X1178017Y618967D01*
G01X1180950Y620550D02*
X1183617D01*
X1183367Y621133D01*
X1182950Y621467D01*
X1182367Y621633D01*
X1181783Y621550D01*
X1181283Y621300D01*
X1180950Y620717D01*
X1180783Y620217D01*
Y619717D01*
X1180950Y619217D01*
X1181367Y618717D01*
X1181867Y618383D01*
X1182450Y618300D01*
X1183033Y618467D01*
X1183617Y618967D01*
G01X1192900Y618300D02*
Y622550D01*
X1193067Y622967D01*
X1193400Y623217D01*
X1193900Y623300D01*
X1194400Y623133D01*
X1194650Y622717D01*
G01X1193650Y621300D02*
X1191983D01*
G01X1197833Y618300D02*
Y621633D01*
G01Y620967D02*
X1198250Y621300D01*
X1198667Y621550D01*
X1199250Y621633D01*
X1199667Y621550D01*
X1200167Y621300D01*
G01X1204600Y618300D02*
X1204100Y618383D01*
X1203600Y618717D01*
X1203267Y619300D01*
X1203100Y619967D01*
X1203267Y620633D01*
X1203600Y621217D01*
X1204100Y621550D01*
X1204600Y621633D01*
X1205100Y621550D01*
X1205600Y621217D01*
X1205933Y620633D01*
X1206017Y619967D01*
X1205933Y619300D01*
X1205600Y618717D01*
X1205100Y618383D01*
X1204600Y618300D01*
G01X1207700D02*
Y621633D01*
G01Y620717D02*
X1207950Y621133D01*
X1208367Y621467D01*
X1208950Y621633D01*
X1209533Y621467D01*
X1209950Y621133D01*
X1210200Y620717D01*
Y618300D01*
G01Y620717D02*
X1210450Y621133D01*
X1210867Y621467D01*
X1211450Y621633D01*
X1212033Y621467D01*
X1212450Y621133D01*
X1212700Y620633D01*
Y618300D01*
G01X1220150Y618883D02*
X1220567Y618550D01*
X1221150Y618300D01*
X1221650D01*
X1222150Y618467D01*
X1222483Y618717D01*
X1222650Y619050D01*
X1222567Y619550D01*
X1222233Y619800D01*
X1220733Y620300D01*
X1220400Y620883D01*
X1220567Y621300D01*
X1220900Y621550D01*
X1221400Y621633D01*
X1221900Y621550D01*
X1222400Y621300D01*
G01X1227000Y618300D02*
X1226500Y618383D01*
X1226000Y618717D01*
X1225667Y619300D01*
X1225500Y619967D01*
X1225667Y620633D01*
X1226000Y621217D01*
X1226500Y621550D01*
X1227000Y621633D01*
X1227500Y621550D01*
X1228000Y621217D01*
X1228333Y620633D01*
X1228417Y619967D01*
X1228333Y619300D01*
X1228000Y618717D01*
X1227500Y618383D01*
X1227000Y618300D01*
G01X1232600D02*
Y623300D01*
G01X1239700D02*
Y618300D01*
G01Y619050D02*
X1239367Y618633D01*
X1238867Y618383D01*
X1238283Y618300D01*
X1237617Y618467D01*
X1237117Y618883D01*
X1236783Y619383D01*
X1236700Y619967D01*
X1236783Y620550D01*
X1237117Y621050D01*
X1237617Y621467D01*
X1238283Y621633D01*
X1238867Y621550D01*
X1239283Y621383D01*
X1239700Y621050D01*
G01X1242550Y620550D02*
X1245217D01*
X1244967Y621133D01*
X1244550Y621467D01*
X1243967Y621633D01*
X1243383Y621550D01*
X1242883Y621300D01*
X1242550Y620717D01*
X1242383Y620217D01*
Y619717D01*
X1242550Y619217D01*
X1242967Y618717D01*
X1243467Y618383D01*
X1244050Y618300D01*
X1244633Y618467D01*
X1245217Y618967D01*
G01X1248233Y618300D02*
Y621633D01*
G01Y620967D02*
X1248650Y621300D01*
X1249067Y621550D01*
X1249650Y621633D01*
X1250067Y621550D01*
X1250567Y621300D01*
G01X1258100Y618300D02*
Y621633D01*
G01Y620717D02*
X1258350Y621133D01*
X1258767Y621467D01*
X1259350Y621633D01*
X1259933Y621467D01*
X1260350Y621133D01*
X1260600Y620717D01*
Y618300D01*
G01Y620717D02*
X1260850Y621133D01*
X1261267Y621467D01*
X1261850Y621633D01*
X1262433Y621467D01*
X1262850Y621133D01*
X1263100Y620633D01*
Y618300D01*
G01X1267700D02*
Y621633D01*
G01Y621050D02*
X1267367Y621383D01*
X1266867Y621550D01*
X1266283Y621633D01*
X1265700Y621467D01*
X1265200Y621133D01*
X1264867Y620633D01*
X1264700Y619967D01*
X1264867Y619300D01*
X1265200Y618800D01*
X1265700Y618467D01*
X1266283Y618300D01*
X1266867Y618383D01*
X1267367Y618633D01*
X1267700Y618967D01*
G01X1270550Y618883D02*
X1270967Y618550D01*
X1271550Y618300D01*
X1272050D01*
X1272550Y618467D01*
X1272883Y618717D01*
X1273050Y619050D01*
X1272967Y619550D01*
X1272633Y619800D01*
X1271133Y620300D01*
X1270800Y620883D01*
X1270967Y621300D01*
X1271300Y621550D01*
X1271800Y621633D01*
X1272300Y621550D01*
X1272800Y621300D01*
G01X1275983Y618300D02*
Y623300D01*
G01X1278650Y621633D02*
X1275983Y619717D01*
G01X1277067Y620467D02*
X1278817Y618300D01*
G01X1283000Y618133D02*
X1282833Y618217D01*
Y618383D01*
X1283000Y618467D01*
X1283167Y618383D01*
Y618217D01*
X1283000Y618133D01*
G01X1146100Y641300D02*
Y646300D01*
G01Y643800D02*
X1146517Y644300D01*
X1147017Y644550D01*
X1147517Y644633D01*
X1148267Y644467D01*
X1148767Y644133D01*
X1149100Y643550D01*
Y642883D01*
X1148933Y642217D01*
X1148600Y641717D01*
X1148017Y641383D01*
X1147517Y641300D01*
X1147017Y641383D01*
X1146517Y641633D01*
X1146100Y642050D01*
G01X1151950Y643550D02*
X1154617D01*
X1154367Y644133D01*
X1153950Y644467D01*
X1153367Y644633D01*
X1152783Y644550D01*
X1152283Y644300D01*
X1151950Y643717D01*
X1151783Y643217D01*
Y642717D01*
X1151950Y642217D01*
X1152367Y641717D01*
X1152867Y641383D01*
X1153450Y641300D01*
X1154033Y641467D01*
X1154617Y641967D01*
G01X1164400Y646300D02*
Y641300D01*
G01X1163233Y644633D02*
X1165567D01*
G01X1168750Y643550D02*
X1171417D01*
X1171167Y644133D01*
X1170750Y644467D01*
X1170167Y644633D01*
X1169583Y644550D01*
X1169083Y644300D01*
X1168750Y643717D01*
X1168583Y643217D01*
Y642717D01*
X1168750Y642217D01*
X1169167Y641717D01*
X1169667Y641383D01*
X1170250Y641300D01*
X1170833Y641467D01*
X1171417Y641967D01*
G01X1174183Y641300D02*
Y644633D01*
G01Y643800D02*
X1174517Y644217D01*
X1175017Y644550D01*
X1175683Y644633D01*
X1176267Y644550D01*
X1176767Y644217D01*
X1177017Y643633D01*
Y641300D01*
G01X1181200Y646300D02*
Y641300D01*
G01X1180033Y644633D02*
X1182367D01*
G01X1185550Y643550D02*
X1188217D01*
X1187967Y644133D01*
X1187550Y644467D01*
X1186967Y644633D01*
X1186383Y644550D01*
X1185883Y644300D01*
X1185550Y643717D01*
X1185383Y643217D01*
Y642717D01*
X1185550Y642217D01*
X1185967Y641717D01*
X1186467Y641383D01*
X1187050Y641300D01*
X1187633Y641467D01*
X1188217Y641967D01*
G01X1193900Y646300D02*
Y641300D01*
G01Y642050D02*
X1193567Y641633D01*
X1193067Y641383D01*
X1192483Y641300D01*
X1191817Y641467D01*
X1191317Y641883D01*
X1190983Y642383D01*
X1190900Y642967D01*
X1190983Y643550D01*
X1191317Y644050D01*
X1191817Y644467D01*
X1192483Y644633D01*
X1193067Y644550D01*
X1193483Y644383D01*
X1193900Y644050D01*
G01X1201517Y644633D02*
X1202517Y641300D01*
X1203600Y644633D01*
X1204683Y641300D01*
X1205683Y644633D01*
G01X1209200D02*
Y641300D01*
G01Y645967D02*
X1209033Y646050D01*
Y646217D01*
X1209200Y646300D01*
X1209367Y646217D01*
Y646050D01*
X1209200Y645967D01*
G01X1214800Y646300D02*
Y641300D01*
G01X1213633Y644633D02*
X1215967D01*
G01X1218983Y641300D02*
Y646300D01*
G01Y643883D02*
X1219400Y644300D01*
X1219817Y644550D01*
X1220483Y644633D01*
X1220983Y644550D01*
X1221567Y644217D01*
X1221817Y643717D01*
Y641300D01*
G01X1230350Y641883D02*
X1230767Y641550D01*
X1231350Y641300D01*
X1231850D01*
X1232350Y641467D01*
X1232683Y641717D01*
X1232850Y642050D01*
X1232767Y642550D01*
X1232433Y642800D01*
X1230933Y643300D01*
X1230600Y643883D01*
X1230767Y644300D01*
X1231100Y644550D01*
X1231600Y644633D01*
X1232100Y644550D01*
X1232600Y644300D01*
G01X1237200Y641300D02*
X1236700Y641383D01*
X1236200Y641717D01*
X1235867Y642300D01*
X1235700Y642967D01*
X1235867Y643633D01*
X1236200Y644217D01*
X1236700Y644550D01*
X1237200Y644633D01*
X1237700Y644550D01*
X1238200Y644217D01*
X1238533Y643633D01*
X1238617Y642967D01*
X1238533Y642300D01*
X1238200Y641717D01*
X1237700Y641383D01*
X1237200Y641300D01*
G01X1242800D02*
Y646300D01*
G01X1249900D02*
Y641300D01*
G01Y642050D02*
X1249567Y641633D01*
X1249067Y641383D01*
X1248483Y641300D01*
X1247817Y641467D01*
X1247317Y641883D01*
X1246983Y642383D01*
X1246900Y642967D01*
X1246983Y643550D01*
X1247317Y644050D01*
X1247817Y644467D01*
X1248483Y644633D01*
X1249067Y644550D01*
X1249483Y644383D01*
X1249900Y644050D01*
G01X1252750Y643550D02*
X1255417D01*
X1255167Y644133D01*
X1254750Y644467D01*
X1254167Y644633D01*
X1253583Y644550D01*
X1253083Y644300D01*
X1252750Y643717D01*
X1252583Y643217D01*
Y642717D01*
X1252750Y642217D01*
X1253167Y641717D01*
X1253667Y641383D01*
X1254250Y641300D01*
X1254833Y641467D01*
X1255417Y641967D01*
G01X1258433Y641300D02*
Y644633D01*
G01Y643967D02*
X1258850Y644300D01*
X1259267Y644550D01*
X1259850Y644633D01*
X1260267Y644550D01*
X1260767Y644300D01*
G01X1268300Y641300D02*
Y644633D01*
G01Y643717D02*
X1268550Y644133D01*
X1268967Y644467D01*
X1269550Y644633D01*
X1270133Y644467D01*
X1270550Y644133D01*
X1270800Y643717D01*
Y641300D01*
G01Y643717D02*
X1271050Y644133D01*
X1271467Y644467D01*
X1272050Y644633D01*
X1272633Y644467D01*
X1273050Y644133D01*
X1273300Y643633D01*
Y641300D01*
G01X1277900D02*
Y644633D01*
G01Y644050D02*
X1277567Y644383D01*
X1277067Y644550D01*
X1276483Y644633D01*
X1275900Y644467D01*
X1275400Y644133D01*
X1275067Y643633D01*
X1274900Y642967D01*
X1275067Y642300D01*
X1275400Y641800D01*
X1275900Y641467D01*
X1276483Y641300D01*
X1277067Y641383D01*
X1277567Y641633D01*
X1277900Y641967D01*
G01X1280750Y641883D02*
X1281167Y641550D01*
X1281750Y641300D01*
X1282250D01*
X1282750Y641467D01*
X1283083Y641717D01*
X1283250Y642050D01*
X1283167Y642550D01*
X1282833Y642800D01*
X1281333Y643300D01*
X1281000Y643883D01*
X1281167Y644300D01*
X1281500Y644550D01*
X1282000Y644633D01*
X1282500Y644550D01*
X1283000Y644300D01*
G01X1286183Y641300D02*
Y646300D01*
G01X1288850Y644633D02*
X1286183Y642717D01*
G01X1287267Y643467D02*
X1289017Y641300D01*
G01X1293200Y641133D02*
X1293033Y641217D01*
Y641383D01*
X1293200Y641467D01*
X1293367Y641383D01*
Y641217D01*
X1293200Y641133D01*
G01X1147600Y655300D02*
Y650300D01*
G01X1146433Y653633D02*
X1148767D01*
G01X1153200Y650300D02*
X1152700Y650383D01*
X1152200Y650717D01*
X1151867Y651300D01*
X1151700Y651967D01*
X1151867Y652633D01*
X1152200Y653217D01*
X1152700Y653550D01*
X1153200Y653633D01*
X1153700Y653550D01*
X1154200Y653217D01*
X1154533Y652633D01*
X1154617Y651967D01*
X1154533Y651300D01*
X1154200Y650717D01*
X1153700Y650383D01*
X1153200Y650300D01*
G01X1162900D02*
Y655300D01*
G01Y652800D02*
X1163317Y653300D01*
X1163817Y653550D01*
X1164317Y653633D01*
X1165067Y653467D01*
X1165567Y653133D01*
X1165900Y652550D01*
Y651883D01*
X1165733Y651217D01*
X1165400Y650717D01*
X1164817Y650383D01*
X1164317Y650300D01*
X1163817Y650383D01*
X1163317Y650633D01*
X1162900Y651050D01*
G01X1168750Y652550D02*
X1171417D01*
X1171167Y653133D01*
X1170750Y653467D01*
X1170167Y653633D01*
X1169583Y653550D01*
X1169083Y653300D01*
X1168750Y652717D01*
X1168583Y652217D01*
Y651717D01*
X1168750Y651217D01*
X1169167Y650717D01*
X1169667Y650383D01*
X1170250Y650300D01*
X1170833Y650467D01*
X1171417Y650967D01*
G01X1182533Y653217D02*
X1181950Y653550D01*
X1181450Y653633D01*
X1180783Y653467D01*
X1180283Y653133D01*
X1179950Y652550D01*
X1179867Y651967D01*
X1179950Y651383D01*
X1180283Y650883D01*
X1180783Y650467D01*
X1181450Y650300D01*
X1182033Y650467D01*
X1182533Y650800D01*
G01X1186800Y650300D02*
X1186300Y650383D01*
X1185800Y650717D01*
X1185467Y651300D01*
X1185300Y651967D01*
X1185467Y652633D01*
X1185800Y653217D01*
X1186300Y653550D01*
X1186800Y653633D01*
X1187300Y653550D01*
X1187800Y653217D01*
X1188133Y652633D01*
X1188217Y651967D01*
X1188133Y651300D01*
X1187800Y650717D01*
X1187300Y650383D01*
X1186800Y650300D01*
G01X1190900Y653633D02*
X1192400Y650300D01*
X1193900Y653633D01*
G01X1196750Y652550D02*
X1199417D01*
X1199167Y653133D01*
X1198750Y653467D01*
X1198167Y653633D01*
X1197583Y653550D01*
X1197083Y653300D01*
X1196750Y652717D01*
X1196583Y652217D01*
Y651717D01*
X1196750Y651217D01*
X1197167Y650717D01*
X1197667Y650383D01*
X1198250Y650300D01*
X1198833Y650467D01*
X1199417Y650967D01*
G01X1202433Y650300D02*
Y653633D01*
G01Y652967D02*
X1202850Y653300D01*
X1203267Y653550D01*
X1203850Y653633D01*
X1204267Y653550D01*
X1204767Y653300D01*
G01X1207950Y652550D02*
X1210617D01*
X1210367Y653133D01*
X1209950Y653467D01*
X1209367Y653633D01*
X1208783Y653550D01*
X1208283Y653300D01*
X1207950Y652717D01*
X1207783Y652217D01*
Y651717D01*
X1207950Y651217D01*
X1208367Y650717D01*
X1208867Y650383D01*
X1209450Y650300D01*
X1210033Y650467D01*
X1210617Y650967D01*
G01X1216300Y655300D02*
Y650300D01*
G01Y651050D02*
X1215967Y650633D01*
X1215467Y650383D01*
X1214883Y650300D01*
X1214217Y650467D01*
X1213717Y650883D01*
X1213383Y651383D01*
X1213300Y651967D01*
X1213383Y652550D01*
X1213717Y653050D01*
X1214217Y653467D01*
X1214883Y653633D01*
X1215467Y653550D01*
X1215883Y653383D01*
X1216300Y653050D01*
G01X1224500Y650300D02*
Y655300D01*
G01Y652800D02*
X1224917Y653300D01*
X1225417Y653550D01*
X1225917Y653633D01*
X1226667Y653467D01*
X1227167Y653133D01*
X1227500Y652550D01*
Y651883D01*
X1227333Y651217D01*
X1227000Y650717D01*
X1226417Y650383D01*
X1225917Y650300D01*
X1225417Y650383D01*
X1224917Y650633D01*
X1224500Y651050D01*
G01X1229850Y648800D02*
X1230350Y648633D01*
X1231017Y648800D01*
X1231433Y649133D01*
X1231767Y649550D01*
X1232267Y650883D01*
X1233350Y653633D01*
G01X1230683D02*
X1232267Y650883D01*
G01X1241550D02*
X1241967Y650550D01*
X1242550Y650300D01*
X1243050D01*
X1243550Y650467D01*
X1243883Y650717D01*
X1244050Y651050D01*
X1243967Y651550D01*
X1243633Y651800D01*
X1242133Y652300D01*
X1241800Y652883D01*
X1241967Y653300D01*
X1242300Y653550D01*
X1242800Y653633D01*
X1243300Y653550D01*
X1243800Y653300D01*
G01X1248400Y650300D02*
X1247900Y650383D01*
X1247400Y650717D01*
X1247067Y651300D01*
X1246900Y651967D01*
X1247067Y652633D01*
X1247400Y653217D01*
X1247900Y653550D01*
X1248400Y653633D01*
X1248900Y653550D01*
X1249400Y653217D01*
X1249733Y652633D01*
X1249817Y651967D01*
X1249733Y651300D01*
X1249400Y650717D01*
X1248900Y650383D01*
X1248400Y650300D01*
G01X1254000D02*
Y655300D01*
G01X1261100D02*
Y650300D01*
G01Y651050D02*
X1260767Y650633D01*
X1260267Y650383D01*
X1259683Y650300D01*
X1259017Y650467D01*
X1258517Y650883D01*
X1258183Y651383D01*
X1258100Y651967D01*
X1258183Y652550D01*
X1258517Y653050D01*
X1259017Y653467D01*
X1259683Y653633D01*
X1260267Y653550D01*
X1260683Y653383D01*
X1261100Y653050D01*
G01X1263950Y652550D02*
X1266617D01*
X1266367Y653133D01*
X1265950Y653467D01*
X1265367Y653633D01*
X1264783Y653550D01*
X1264283Y653300D01*
X1263950Y652717D01*
X1263783Y652217D01*
Y651717D01*
X1263950Y651217D01*
X1264367Y650717D01*
X1264867Y650383D01*
X1265450Y650300D01*
X1266033Y650467D01*
X1266617Y650967D01*
G01X1269633Y650300D02*
Y653633D01*
G01Y652967D02*
X1270050Y653300D01*
X1270467Y653550D01*
X1271050Y653633D01*
X1271467Y653550D01*
X1271967Y653300D01*
G01X1279500Y650300D02*
Y653633D01*
G01Y652717D02*
X1279750Y653133D01*
X1280167Y653467D01*
X1280750Y653633D01*
X1281333Y653467D01*
X1281750Y653133D01*
X1282000Y652717D01*
Y650300D01*
G01Y652717D02*
X1282250Y653133D01*
X1282667Y653467D01*
X1283250Y653633D01*
X1283833Y653467D01*
X1284250Y653133D01*
X1284500Y652633D01*
Y650300D01*
G01X1289100D02*
Y653633D01*
G01Y653050D02*
X1288767Y653383D01*
X1288267Y653550D01*
X1287683Y653633D01*
X1287100Y653467D01*
X1286600Y653133D01*
X1286267Y652633D01*
X1286100Y651967D01*
X1286267Y651300D01*
X1286600Y650800D01*
X1287100Y650467D01*
X1287683Y650300D01*
X1288267Y650383D01*
X1288767Y650633D01*
X1289100Y650967D01*
G01X1291950Y650883D02*
X1292367Y650550D01*
X1292950Y650300D01*
X1293450D01*
X1293950Y650467D01*
X1294283Y650717D01*
X1294450Y651050D01*
X1294367Y651550D01*
X1294033Y651800D01*
X1292533Y652300D01*
X1292200Y652883D01*
X1292367Y653300D01*
X1292700Y653550D01*
X1293200Y653633D01*
X1293700Y653550D01*
X1294200Y653300D01*
G01X1297383Y650300D02*
Y655300D01*
G01X1300050Y653633D02*
X1297383Y651717D01*
G01X1298467Y652467D02*
X1300217Y650300D01*
G01X1311500D02*
Y653633D01*
G01Y653050D02*
X1311167Y653383D01*
X1310667Y653550D01*
X1310083Y653633D01*
X1309500Y653467D01*
X1309000Y653133D01*
X1308667Y652633D01*
X1308500Y651967D01*
X1308667Y651300D01*
X1309000Y650800D01*
X1309500Y650467D01*
X1310083Y650300D01*
X1310667Y650383D01*
X1311167Y650633D01*
X1311500Y650967D01*
G01X1314183Y650300D02*
Y653633D01*
G01Y652800D02*
X1314517Y653217D01*
X1315017Y653550D01*
X1315683Y653633D01*
X1316267Y653550D01*
X1316767Y653217D01*
X1317017Y652633D01*
Y650300D01*
G01X1322700Y655300D02*
Y650300D01*
G01Y651050D02*
X1322367Y650633D01*
X1321867Y650383D01*
X1321283Y650300D01*
X1320617Y650467D01*
X1320117Y650883D01*
X1319783Y651383D01*
X1319700Y651967D01*
X1319783Y652550D01*
X1320117Y653050D01*
X1320617Y653467D01*
X1321283Y653633D01*
X1321867Y653550D01*
X1322283Y653383D01*
X1322700Y653050D01*
G01X1330983Y650300D02*
Y655300D01*
G01Y652883D02*
X1331400Y653300D01*
X1331817Y653550D01*
X1332483Y653633D01*
X1332983Y653550D01*
X1333567Y653217D01*
X1333817Y652717D01*
Y650300D01*
G01X1338000D02*
X1337500Y650383D01*
X1337000Y650717D01*
X1336667Y651300D01*
X1336500Y651967D01*
X1336667Y652633D01*
X1337000Y653217D01*
X1337500Y653550D01*
X1338000Y653633D01*
X1338500Y653550D01*
X1339000Y653217D01*
X1339333Y652633D01*
X1339417Y651967D01*
X1339333Y651300D01*
X1339000Y650717D01*
X1338500Y650383D01*
X1338000Y650300D01*
G01X1343600D02*
Y655300D01*
G01X1347950Y652550D02*
X1350617D01*
X1350367Y653133D01*
X1349950Y653467D01*
X1349367Y653633D01*
X1348783Y653550D01*
X1348283Y653300D01*
X1347950Y652717D01*
X1347783Y652217D01*
Y651717D01*
X1347950Y651217D01*
X1348367Y650717D01*
X1348867Y650383D01*
X1349450Y650300D01*
X1350033Y650467D01*
X1350617Y650967D01*
G01X1361900Y650300D02*
Y653633D01*
G01Y653050D02*
X1361567Y653383D01*
X1361067Y653550D01*
X1360483Y653633D01*
X1359900Y653467D01*
X1359400Y653133D01*
X1359067Y652633D01*
X1358900Y651967D01*
X1359067Y651300D01*
X1359400Y650800D01*
X1359900Y650467D01*
X1360483Y650300D01*
X1361067Y650383D01*
X1361567Y650633D01*
X1361900Y650967D01*
G01X1366000Y650300D02*
Y655300D01*
G01X1370350Y650883D02*
X1370767Y650550D01*
X1371350Y650300D01*
X1371850D01*
X1372350Y650467D01*
X1372683Y650717D01*
X1372850Y651050D01*
X1372767Y651550D01*
X1372433Y651800D01*
X1370933Y652300D01*
X1370600Y652883D01*
X1370767Y653300D01*
X1371100Y653550D01*
X1371600Y653633D01*
X1372100Y653550D01*
X1372600Y653300D01*
G01X1377200Y650300D02*
X1376700Y650383D01*
X1376200Y650717D01*
X1375867Y651300D01*
X1375700Y651967D01*
X1375867Y652633D01*
X1376200Y653217D01*
X1376700Y653550D01*
X1377200Y653633D01*
X1377700Y653550D01*
X1378200Y653217D01*
X1378533Y652633D01*
X1378617Y651967D01*
X1378533Y651300D01*
X1378200Y650717D01*
X1377700Y650383D01*
X1377200Y650300D01*
G01X1386983D02*
Y653633D01*
G01Y652800D02*
X1387317Y653217D01*
X1387817Y653550D01*
X1388483Y653633D01*
X1389067Y653550D01*
X1389567Y653217D01*
X1389817Y652633D01*
Y650300D01*
G01X1392750Y652550D02*
X1395417D01*
X1395167Y653133D01*
X1394750Y653467D01*
X1394167Y653633D01*
X1393583Y653550D01*
X1393083Y653300D01*
X1392750Y652717D01*
X1392583Y652217D01*
Y651717D01*
X1392750Y651217D01*
X1393167Y650717D01*
X1393667Y650383D01*
X1394250Y650300D01*
X1394833Y650467D01*
X1395417Y650967D01*
G01X1398350Y652550D02*
X1401017D01*
X1400767Y653133D01*
X1400350Y653467D01*
X1399767Y653633D01*
X1399183Y653550D01*
X1398683Y653300D01*
X1398350Y652717D01*
X1398183Y652217D01*
Y651717D01*
X1398350Y651217D01*
X1398767Y650717D01*
X1399267Y650383D01*
X1399850Y650300D01*
X1400433Y650467D01*
X1401017Y650967D01*
G01X1406700Y655300D02*
Y650300D01*
G01Y651050D02*
X1406367Y650633D01*
X1405867Y650383D01*
X1405283Y650300D01*
X1404617Y650467D01*
X1404117Y650883D01*
X1403783Y651383D01*
X1403700Y651967D01*
X1403783Y652550D01*
X1404117Y653050D01*
X1404617Y653467D01*
X1405283Y653633D01*
X1405867Y653550D01*
X1406283Y653383D01*
X1406700Y653050D01*
G01X1416400Y655300D02*
Y650300D01*
G01X1415233Y653633D02*
X1417567D01*
G01X1422000Y650300D02*
X1421500Y650383D01*
X1421000Y650717D01*
X1420667Y651300D01*
X1420500Y651967D01*
X1420667Y652633D01*
X1421000Y653217D01*
X1421500Y653550D01*
X1422000Y653633D01*
X1422500Y653550D01*
X1423000Y653217D01*
X1423333Y652633D01*
X1423417Y651967D01*
X1423333Y651300D01*
X1423000Y650717D01*
X1422500Y650383D01*
X1422000Y650300D01*
G01X1201267Y212800D02*
Y217800D01*
X1202933D01*
X1203600Y217550D01*
X1204100Y217217D01*
X1204517Y216717D01*
X1204850Y216133D01*
X1204933Y215300D01*
X1204850Y214467D01*
X1204517Y213883D01*
X1204100Y213383D01*
X1203600Y213050D01*
X1202933Y212800D01*
X1201267D01*
G01X1207533D02*
Y216133D01*
G01Y215467D02*
X1207950Y215800D01*
X1208367Y216050D01*
X1208950Y216133D01*
X1209367Y216050D01*
X1209867Y215800D01*
G01X1214300Y216133D02*
Y212800D01*
G01Y217467D02*
X1214133Y217550D01*
Y217717D01*
X1214300Y217800D01*
X1214467Y217717D01*
Y217550D01*
X1214300Y217467D01*
G01X1219900Y212800D02*
Y217800D01*
G01X1225500Y212800D02*
Y217800D01*
G01X1235117Y212800D02*
Y217800D01*
X1238283D01*
G01X1237117Y215383D02*
X1235117D01*
G01X1241133Y212800D02*
Y216133D01*
G01Y215467D02*
X1241550Y215800D01*
X1241967Y216050D01*
X1242550Y216133D01*
X1242967Y216050D01*
X1243467Y215800D01*
G01X1247900Y212800D02*
X1247400Y212883D01*
X1246900Y213217D01*
X1246567Y213800D01*
X1246400Y214467D01*
X1246567Y215133D01*
X1246900Y215717D01*
X1247400Y216050D01*
X1247900Y216133D01*
X1248400Y216050D01*
X1248900Y215717D01*
X1249233Y215133D01*
X1249317Y214467D01*
X1249233Y213800D01*
X1248900Y213217D01*
X1248400Y212883D01*
X1247900Y212800D01*
G01X1251000D02*
Y216133D01*
G01Y215217D02*
X1251250Y215633D01*
X1251667Y215967D01*
X1252250Y216133D01*
X1252833Y215967D01*
X1253250Y215633D01*
X1253500Y215217D01*
Y212800D01*
G01Y215217D02*
X1253750Y215633D01*
X1254167Y215967D01*
X1254750Y216133D01*
X1255333Y215967D01*
X1255750Y215633D01*
X1256000Y215133D01*
Y212800D01*
G01X1281083Y211133D02*
X1280250Y211967D01*
X1279833Y212800D01*
Y216133D01*
X1280250Y216967D01*
X1281083Y217800D01*
G01X1287767Y215467D02*
X1288100Y215717D01*
X1288350Y216133D01*
X1288517Y216717D01*
X1288350Y217217D01*
X1288017Y217550D01*
X1287433Y217800D01*
X1285183D01*
Y212800D01*
X1287933D01*
X1288517Y213133D01*
X1288850Y213633D01*
X1289017Y214217D01*
X1288850Y214800D01*
X1288350Y215300D01*
X1287767Y215467D01*
X1285183D01*
G01X1292700Y212800D02*
X1292033Y212883D01*
X1291450Y213217D01*
X1290950Y213717D01*
X1290617Y214300D01*
X1290450Y214967D01*
Y215633D01*
X1290617Y216300D01*
X1290950Y216883D01*
X1291450Y217383D01*
X1292033Y217717D01*
X1292700Y217800D01*
X1293367Y217717D01*
X1293950Y217383D01*
X1294450Y216883D01*
X1294783Y216300D01*
X1294950Y215633D01*
Y214967D01*
X1294783Y214300D01*
X1294450Y213717D01*
X1293950Y213217D01*
X1293367Y212883D01*
X1292700Y212800D01*
G01X1298300Y217800D02*
Y212800D01*
G01X1296383Y217800D02*
X1300217D01*
G01X1303900D02*
Y212800D01*
G01X1301983Y217800D02*
X1305817D01*
G01X1309500Y212800D02*
X1308833Y212883D01*
X1308250Y213217D01*
X1307750Y213717D01*
X1307417Y214300D01*
X1307250Y214967D01*
Y215633D01*
X1307417Y216300D01*
X1307750Y216883D01*
X1308250Y217383D01*
X1308833Y217717D01*
X1309500Y217800D01*
X1310167Y217717D01*
X1310750Y217383D01*
X1311250Y216883D01*
X1311583Y216300D01*
X1311750Y215633D01*
Y214967D01*
X1311583Y214300D01*
X1311250Y213717D01*
X1310750Y213217D01*
X1310167Y212883D01*
X1309500Y212800D01*
G01X1312933D02*
Y217800D01*
X1315100Y213633D01*
X1317267Y217800D01*
Y212800D01*
G01X1321117Y211133D02*
X1321950Y211967D01*
X1322367Y212800D01*
Y216133D01*
X1321950Y216967D01*
X1321117Y217800D01*
G01X1331900D02*
Y212800D01*
G01X1330733Y216133D02*
X1333067D01*
G01X1337500Y212800D02*
X1337000Y212883D01*
X1336500Y213217D01*
X1336167Y213800D01*
X1336000Y214467D01*
X1336167Y215133D01*
X1336500Y215717D01*
X1337000Y216050D01*
X1337500Y216133D01*
X1338000Y216050D01*
X1338500Y215717D01*
X1338833Y215133D01*
X1338917Y214467D01*
X1338833Y213800D01*
X1338500Y213217D01*
X1338000Y212883D01*
X1337500Y212800D01*
G01X1347033Y217800D02*
Y212800D01*
X1350367D01*
G01X1353050Y216133D02*
X1355550Y212800D01*
G01Y216133D02*
X1353050Y212800D01*
G01X1203093Y193500D02*
Y188500D01*
X1206427D01*
G01X1209110Y191833D02*
X1211610Y188500D01*
G01Y191833D02*
X1209110Y188500D01*
G01X1215960Y188333D02*
X1215793Y188417D01*
Y188583D01*
X1215960Y188667D01*
X1216127Y188583D01*
Y188417D01*
X1215960Y188333D01*
G01Y190583D02*
X1215793Y190667D01*
Y190833D01*
X1215960Y190917D01*
X1216127Y190833D01*
Y190667D01*
X1215960Y190583D01*
G01X1224660Y188500D02*
Y191833D01*
G01Y190917D02*
X1224910Y191333D01*
X1225327Y191667D01*
X1225910Y191833D01*
X1226493Y191667D01*
X1226910Y191333D01*
X1227160Y190917D01*
Y188500D01*
G01Y190917D02*
X1227410Y191333D01*
X1227827Y191667D01*
X1228410Y191833D01*
X1228993Y191667D01*
X1229410Y191333D01*
X1229660Y190833D01*
Y188500D01*
G01X1231343Y191833D02*
Y189500D01*
X1231677Y188917D01*
X1232177Y188583D01*
X1232760Y188500D01*
X1233343Y188583D01*
X1233843Y188917D01*
X1234177Y189500D01*
G01Y188500D02*
Y191833D01*
G01X1237110Y189083D02*
X1237527Y188750D01*
X1238110Y188500D01*
X1238610D01*
X1239110Y188667D01*
X1239443Y188917D01*
X1239610Y189250D01*
X1239527Y189750D01*
X1239193Y190000D01*
X1237693Y190500D01*
X1237360Y191083D01*
X1237527Y191500D01*
X1237860Y191750D01*
X1238360Y191833D01*
X1238860Y191750D01*
X1239360Y191500D01*
G01X1243960Y193500D02*
Y188500D01*
G01X1242793Y191833D02*
X1245127D01*
G01X1253660Y188500D02*
Y193500D01*
G01Y191000D02*
X1254077Y191500D01*
X1254577Y191750D01*
X1255077Y191833D01*
X1255827Y191667D01*
X1256327Y191333D01*
X1256660Y190750D01*
Y190083D01*
X1256493Y189417D01*
X1256160Y188917D01*
X1255577Y188583D01*
X1255077Y188500D01*
X1254577Y188583D01*
X1254077Y188833D01*
X1253660Y189250D01*
G01X1259510Y190750D02*
X1262177D01*
X1261927Y191333D01*
X1261510Y191667D01*
X1260927Y191833D01*
X1260343Y191750D01*
X1259843Y191500D01*
X1259510Y190917D01*
X1259343Y190417D01*
Y189917D01*
X1259510Y189417D01*
X1259927Y188917D01*
X1260427Y188583D01*
X1261010Y188500D01*
X1261593Y188667D01*
X1262177Y189167D01*
G01X1270460Y188500D02*
Y193500D01*
G01Y191000D02*
X1270877Y191500D01*
X1271377Y191750D01*
X1271877Y191833D01*
X1272627Y191667D01*
X1273127Y191333D01*
X1273460Y190750D01*
Y190083D01*
X1273293Y189417D01*
X1272960Y188917D01*
X1272377Y188583D01*
X1271877Y188500D01*
X1271377Y188583D01*
X1270877Y188833D01*
X1270460Y189250D01*
G01X1276393Y188500D02*
Y191833D01*
G01Y191167D02*
X1276810Y191500D01*
X1277227Y191750D01*
X1277810Y191833D01*
X1278227Y191750D01*
X1278727Y191500D01*
G01X1283160Y188500D02*
X1282660Y188583D01*
X1282160Y188917D01*
X1281827Y189500D01*
X1281660Y190167D01*
X1281827Y190833D01*
X1282160Y191417D01*
X1282660Y191750D01*
X1283160Y191833D01*
X1283660Y191750D01*
X1284160Y191417D01*
X1284493Y190833D01*
X1284577Y190167D01*
X1284493Y189500D01*
X1284160Y188917D01*
X1283660Y188583D01*
X1283160Y188500D01*
G01X1287343D02*
Y193500D01*
G01X1290010Y191833D02*
X1287343Y189917D01*
G01X1288427Y190667D02*
X1290177Y188500D01*
G01X1293110Y190750D02*
X1295777D01*
X1295527Y191333D01*
X1295110Y191667D01*
X1294527Y191833D01*
X1293943Y191750D01*
X1293443Y191500D01*
X1293110Y190917D01*
X1292943Y190417D01*
Y189917D01*
X1293110Y189417D01*
X1293527Y188917D01*
X1294027Y188583D01*
X1294610Y188500D01*
X1295193Y188667D01*
X1295777Y189167D01*
G01X1298543Y188500D02*
Y191833D01*
G01Y191000D02*
X1298877Y191417D01*
X1299377Y191750D01*
X1300043Y191833D01*
X1300627Y191750D01*
X1301127Y191417D01*
X1301377Y190833D01*
Y188500D01*
G01X1311160D02*
Y193500D01*
G01X1318260Y188500D02*
Y191833D01*
G01Y191250D02*
X1317927Y191583D01*
X1317427Y191750D01*
X1316843Y191833D01*
X1316260Y191667D01*
X1315760Y191333D01*
X1315427Y190833D01*
X1315260Y190167D01*
X1315427Y189500D01*
X1315760Y189000D01*
X1316260Y188667D01*
X1316843Y188500D01*
X1317427Y188583D01*
X1317927Y188833D01*
X1318260Y189167D01*
G01X1320610Y187000D02*
X1321110Y186833D01*
X1321777Y187000D01*
X1322193Y187333D01*
X1322527Y187750D01*
X1323027Y189083D01*
X1324110Y191833D01*
G01X1321443D02*
X1323027Y189083D01*
G01X1326710Y190750D02*
X1329377D01*
X1329127Y191333D01*
X1328710Y191667D01*
X1328127Y191833D01*
X1327543Y191750D01*
X1327043Y191500D01*
X1326710Y190917D01*
X1326543Y190417D01*
Y189917D01*
X1326710Y189417D01*
X1327127Y188917D01*
X1327627Y188583D01*
X1328210Y188500D01*
X1328793Y188667D01*
X1329377Y189167D01*
G01X1332393Y188500D02*
Y191833D01*
G01Y191167D02*
X1332810Y191500D01*
X1333227Y191750D01*
X1333810Y191833D01*
X1334227Y191750D01*
X1334727Y191500D01*
G01X1202493Y206000D02*
Y201000D01*
X1205827D01*
G01X1208343D02*
Y204333D01*
G01Y203500D02*
X1208677Y203917D01*
X1209177Y204250D01*
X1209843Y204333D01*
X1210427Y204250D01*
X1210927Y203917D01*
X1211177Y203333D01*
Y201000D01*
G01X1215360Y200833D02*
X1215193Y200917D01*
Y201083D01*
X1215360Y201167D01*
X1215527Y201083D01*
Y200917D01*
X1215360Y200833D01*
G01Y203083D02*
X1215193Y203167D01*
Y203333D01*
X1215360Y203417D01*
X1215527Y203333D01*
Y203167D01*
X1215360Y203083D01*
G01X1227893Y203917D02*
X1227310Y204250D01*
X1226810Y204333D01*
X1226143Y204167D01*
X1225643Y203833D01*
X1225310Y203250D01*
X1225227Y202667D01*
X1225310Y202083D01*
X1225643Y201583D01*
X1226143Y201167D01*
X1226810Y201000D01*
X1227393Y201167D01*
X1227893Y201500D01*
G01X1233660Y201000D02*
Y204333D01*
G01Y203750D02*
X1233327Y204083D01*
X1232827Y204250D01*
X1232243Y204333D01*
X1231660Y204167D01*
X1231160Y203833D01*
X1230827Y203333D01*
X1230660Y202667D01*
X1230827Y202000D01*
X1231160Y201500D01*
X1231660Y201167D01*
X1232243Y201000D01*
X1232827Y201083D01*
X1233327Y201333D01*
X1233660Y201667D01*
G01X1236343Y201000D02*
Y204333D01*
G01Y203500D02*
X1236677Y203917D01*
X1237177Y204250D01*
X1237843Y204333D01*
X1238427Y204250D01*
X1238927Y203917D01*
X1239177Y203333D01*
Y201000D01*
G01X1243360Y204333D02*
X1244193Y205375D01*
Y206000D01*
X1243568D01*
Y205375D01*
X1244193D01*
G01X1248960Y206000D02*
Y201000D01*
G01X1247793Y204333D02*
X1250127D01*
G01X1258660Y201000D02*
Y206000D01*
G01Y203500D02*
X1259077Y204000D01*
X1259577Y204250D01*
X1260077Y204333D01*
X1260827Y204167D01*
X1261327Y203833D01*
X1261660Y203250D01*
Y202583D01*
X1261493Y201917D01*
X1261160Y201417D01*
X1260577Y201083D01*
X1260077Y201000D01*
X1259577Y201083D01*
X1259077Y201333D01*
X1258660Y201750D01*
G01X1264510Y203250D02*
X1267177D01*
X1266927Y203833D01*
X1266510Y204167D01*
X1265927Y204333D01*
X1265343Y204250D01*
X1264843Y204000D01*
X1264510Y203417D01*
X1264343Y202917D01*
Y202417D01*
X1264510Y201917D01*
X1264927Y201417D01*
X1265427Y201083D01*
X1266010Y201000D01*
X1266593Y201167D01*
X1267177Y201667D01*
G01X1275460Y201000D02*
Y206000D01*
G01Y203500D02*
X1275877Y204000D01*
X1276377Y204250D01*
X1276877Y204333D01*
X1277627Y204167D01*
X1278127Y203833D01*
X1278460Y203250D01*
Y202583D01*
X1278293Y201917D01*
X1277960Y201417D01*
X1277377Y201083D01*
X1276877Y201000D01*
X1276377Y201083D01*
X1275877Y201333D01*
X1275460Y201750D01*
G01X1281393Y201000D02*
Y204333D01*
G01Y203667D02*
X1281810Y204000D01*
X1282227Y204250D01*
X1282810Y204333D01*
X1283227Y204250D01*
X1283727Y204000D01*
G01X1288160Y201000D02*
X1287660Y201083D01*
X1287160Y201417D01*
X1286827Y202000D01*
X1286660Y202667D01*
X1286827Y203333D01*
X1287160Y203917D01*
X1287660Y204250D01*
X1288160Y204333D01*
X1288660Y204250D01*
X1289160Y203917D01*
X1289493Y203333D01*
X1289577Y202667D01*
X1289493Y202000D01*
X1289160Y201417D01*
X1288660Y201083D01*
X1288160Y201000D01*
G01X1292343D02*
Y206000D01*
G01X1295010Y204333D02*
X1292343Y202417D01*
G01X1293427Y203167D02*
X1295177Y201000D01*
G01X1298110Y203250D02*
X1300777D01*
X1300527Y203833D01*
X1300110Y204167D01*
X1299527Y204333D01*
X1298943Y204250D01*
X1298443Y204000D01*
X1298110Y203417D01*
X1297943Y202917D01*
Y202417D01*
X1298110Y201917D01*
X1298527Y201417D01*
X1299027Y201083D01*
X1299610Y201000D01*
X1300193Y201167D01*
X1300777Y201667D01*
G01X1303543Y201000D02*
Y204333D01*
G01Y203500D02*
X1303877Y203917D01*
X1304377Y204250D01*
X1305043Y204333D01*
X1305627Y204250D01*
X1306127Y203917D01*
X1306377Y203333D01*
Y201000D01*
G01X1316160D02*
Y206000D01*
G01X1323260Y201000D02*
Y204333D01*
G01Y203750D02*
X1322927Y204083D01*
X1322427Y204250D01*
X1321843Y204333D01*
X1321260Y204167D01*
X1320760Y203833D01*
X1320427Y203333D01*
X1320260Y202667D01*
X1320427Y202000D01*
X1320760Y201500D01*
X1321260Y201167D01*
X1321843Y201000D01*
X1322427Y201083D01*
X1322927Y201333D01*
X1323260Y201667D01*
G01X1325610Y199500D02*
X1326110Y199333D01*
X1326777Y199500D01*
X1327193Y199833D01*
X1327527Y200250D01*
X1328027Y201583D01*
X1329110Y204333D01*
G01X1326443D02*
X1328027Y201583D01*
G01X1331710Y203250D02*
X1334377D01*
X1334127Y203833D01*
X1333710Y204167D01*
X1333127Y204333D01*
X1332543Y204250D01*
X1332043Y204000D01*
X1331710Y203417D01*
X1331543Y202917D01*
Y202417D01*
X1331710Y201917D01*
X1332127Y201417D01*
X1332627Y201083D01*
X1333210Y201000D01*
X1333793Y201167D01*
X1334377Y201667D01*
G01X1337393Y201000D02*
Y204333D01*
G01Y203667D02*
X1337810Y204000D01*
X1338227Y204250D01*
X1338810Y204333D01*
X1339227Y204250D01*
X1339727Y204000D01*
G01X1223433Y679300D02*
Y684300D01*
X1225433D01*
X1226100Y684050D01*
X1226600Y683467D01*
X1226767Y682800D01*
X1226600Y682133D01*
X1226183Y681633D01*
X1225433Y681383D01*
X1223433D01*
G01X1230700Y679300D02*
Y684300D01*
G01X1234883Y682633D02*
Y680300D01*
X1235217Y679717D01*
X1235717Y679383D01*
X1236300Y679300D01*
X1236883Y679383D01*
X1237383Y679717D01*
X1237717Y680300D01*
G01Y679300D02*
Y682633D01*
G01X1240733Y678050D02*
X1241317Y677717D01*
X1241983Y677633D01*
X1242567Y677717D01*
X1243067Y678133D01*
X1243400Y678717D01*
Y682633D01*
G01Y681967D02*
X1243067Y682300D01*
X1242567Y682550D01*
X1241983Y682633D01*
X1241317Y682467D01*
X1240900Y682133D01*
X1240567Y681550D01*
X1240400Y680967D01*
X1240483Y680467D01*
X1240817Y679883D01*
X1241317Y679467D01*
X1241983Y679300D01*
X1242483Y679383D01*
X1243067Y679717D01*
X1243400Y680050D01*
G01X1246333Y678050D02*
X1246917Y677717D01*
X1247583Y677633D01*
X1248167Y677717D01*
X1248667Y678133D01*
X1249000Y678717D01*
Y682633D01*
G01Y681967D02*
X1248667Y682300D01*
X1248167Y682550D01*
X1247583Y682633D01*
X1246917Y682467D01*
X1246500Y682133D01*
X1246167Y681550D01*
X1246000Y680967D01*
X1246083Y680467D01*
X1246417Y679883D01*
X1246917Y679467D01*
X1247583Y679300D01*
X1248083Y679383D01*
X1248667Y679717D01*
X1249000Y680050D01*
G01X1253100Y682633D02*
Y679300D01*
G01Y683967D02*
X1252933Y684050D01*
Y684217D01*
X1253100Y684300D01*
X1253267Y684217D01*
Y684050D01*
X1253100Y683967D01*
G01X1257283Y679300D02*
Y682633D01*
G01Y681800D02*
X1257617Y682217D01*
X1258117Y682550D01*
X1258783Y682633D01*
X1259367Y682550D01*
X1259867Y682217D01*
X1260117Y681633D01*
Y679300D01*
G01X1263133Y678050D02*
X1263717Y677717D01*
X1264383Y677633D01*
X1264967Y677717D01*
X1265467Y678133D01*
X1265800Y678717D01*
Y682633D01*
G01Y681967D02*
X1265467Y682300D01*
X1264967Y682550D01*
X1264383Y682633D01*
X1263717Y682467D01*
X1263300Y682133D01*
X1262967Y681550D01*
X1262800Y680967D01*
X1262883Y680467D01*
X1263217Y679883D01*
X1263717Y679467D01*
X1264383Y679300D01*
X1264883Y679383D01*
X1265467Y679717D01*
X1265800Y680050D01*
G01X1276833Y682217D02*
X1276250Y682550D01*
X1275750Y682633D01*
X1275083Y682467D01*
X1274583Y682133D01*
X1274250Y681550D01*
X1274167Y680967D01*
X1274250Y680383D01*
X1274583Y679883D01*
X1275083Y679467D01*
X1275750Y679300D01*
X1276333Y679467D01*
X1276833Y679800D01*
G01X1279933Y679300D02*
Y682633D01*
G01Y681967D02*
X1280350Y682300D01*
X1280767Y682550D01*
X1281350Y682633D01*
X1281767Y682550D01*
X1282267Y682300D01*
G01X1286700Y682633D02*
Y679300D01*
G01Y683967D02*
X1286533Y684050D01*
Y684217D01*
X1286700Y684300D01*
X1286867Y684217D01*
Y684050D01*
X1286700Y683967D01*
G01X1292300Y684300D02*
Y679300D01*
G01X1291133Y682633D02*
X1293467D01*
G01X1296650Y681550D02*
X1299317D01*
X1299067Y682133D01*
X1298650Y682467D01*
X1298067Y682633D01*
X1297483Y682550D01*
X1296983Y682300D01*
X1296650Y681717D01*
X1296483Y681217D01*
Y680717D01*
X1296650Y680217D01*
X1297067Y679717D01*
X1297567Y679383D01*
X1298150Y679300D01*
X1298733Y679467D01*
X1299317Y679967D01*
G01X1302333Y679300D02*
Y682633D01*
G01Y681967D02*
X1302750Y682300D01*
X1303167Y682550D01*
X1303750Y682633D01*
X1304167Y682550D01*
X1304667Y682300D01*
G01X1309100Y682633D02*
Y679300D01*
G01Y683967D02*
X1308933Y684050D01*
Y684217D01*
X1309100Y684300D01*
X1309267Y684217D01*
Y684050D01*
X1309100Y683967D01*
G01X1316200Y679300D02*
Y682633D01*
G01Y682050D02*
X1315867Y682383D01*
X1315367Y682550D01*
X1314783Y682633D01*
X1314200Y682467D01*
X1313700Y682133D01*
X1313367Y681633D01*
X1313200Y680967D01*
X1313367Y680300D01*
X1313700Y679800D01*
X1314200Y679467D01*
X1314783Y679300D01*
X1315367Y679383D01*
X1315867Y679633D01*
X1316200Y679967D01*
G01X1220017Y824300D02*
X1222100Y819300D01*
X1224183Y824300D01*
G01X1226700D02*
X1228700D01*
G01X1227700D02*
Y819300D01*
G01X1226700D02*
X1228700D01*
G01X1231633D02*
Y824300D01*
X1233633D01*
X1234300Y824050D01*
X1234800Y823467D01*
X1234967Y822800D01*
X1234800Y822133D01*
X1234383Y821633D01*
X1233633Y821383D01*
X1231633D01*
G01X1249767Y246500D02*
Y251500D01*
X1251433D01*
X1252100Y251250D01*
X1252600Y250917D01*
X1253017Y250417D01*
X1253350Y249833D01*
X1253433Y249000D01*
X1253350Y248167D01*
X1253017Y247583D01*
X1252600Y247083D01*
X1252100Y246750D01*
X1251433Y246500D01*
X1249767D01*
G01X1255617Y250667D02*
X1256117Y251167D01*
X1256700Y251417D01*
X1257367Y251500D01*
X1258200Y251333D01*
X1258783Y250917D01*
X1258950Y250417D01*
X1258867Y249917D01*
X1258533Y249500D01*
X1256867Y248667D01*
X1256117Y248083D01*
X1255617Y247250D01*
X1255450Y246500D01*
X1258950D01*
G01X1248767Y404500D02*
Y409500D01*
X1250433D01*
X1251100Y409250D01*
X1251600Y408917D01*
X1252017Y408417D01*
X1252350Y407833D01*
X1252433Y407000D01*
X1252350Y406167D01*
X1252017Y405583D01*
X1251600Y405083D01*
X1251100Y404750D01*
X1250433Y404500D01*
X1248767D01*
G01X1256200D02*
Y409500D01*
X1255200Y408500D01*
G01Y404500D02*
X1257200D01*
G01X1250433Y708717D02*
X1249850Y709050D01*
X1249350Y709133D01*
X1248683Y708967D01*
X1248183Y708633D01*
X1247850Y708050D01*
X1247767Y707467D01*
X1247850Y706883D01*
X1248183Y706383D01*
X1248683Y705967D01*
X1249350Y705800D01*
X1249933Y705967D01*
X1250433Y706300D01*
G01X1254700Y705800D02*
X1254200Y705883D01*
X1253700Y706217D01*
X1253367Y706800D01*
X1253200Y707467D01*
X1253367Y708133D01*
X1253700Y708717D01*
X1254200Y709050D01*
X1254700Y709133D01*
X1255200Y709050D01*
X1255700Y708717D01*
X1256033Y708133D01*
X1256117Y707467D01*
X1256033Y706800D01*
X1255700Y706217D01*
X1255200Y705883D01*
X1254700Y705800D01*
G01X1258800Y704133D02*
Y709133D01*
G01Y708383D02*
X1259217Y708800D01*
X1259633Y709050D01*
X1260300Y709133D01*
X1260883Y709050D01*
X1261467Y708633D01*
X1261717Y708050D01*
X1261800Y707467D01*
X1261717Y706883D01*
X1261467Y706300D01*
X1260967Y705967D01*
X1260300Y705800D01*
X1259717Y705883D01*
X1259133Y706133D01*
X1258800Y706467D01*
G01X1264400Y704133D02*
Y709133D01*
G01Y708383D02*
X1264817Y708800D01*
X1265233Y709050D01*
X1265900Y709133D01*
X1266483Y709050D01*
X1267067Y708633D01*
X1267317Y708050D01*
X1267400Y707467D01*
X1267317Y706883D01*
X1267067Y706300D01*
X1266567Y705967D01*
X1265900Y705800D01*
X1265317Y705883D01*
X1264733Y706133D01*
X1264400Y706467D01*
G01X1270250Y708050D02*
X1272917D01*
X1272667Y708633D01*
X1272250Y708967D01*
X1271667Y709133D01*
X1271083Y709050D01*
X1270583Y708800D01*
X1270250Y708217D01*
X1270083Y707717D01*
Y707217D01*
X1270250Y706717D01*
X1270667Y706217D01*
X1271167Y705883D01*
X1271750Y705800D01*
X1272333Y705967D01*
X1272917Y706467D01*
G01X1275933Y705800D02*
Y709133D01*
G01Y708467D02*
X1276350Y708800D01*
X1276767Y709050D01*
X1277350Y709133D01*
X1277767Y709050D01*
X1278267Y708800D01*
G01X1298267Y239167D02*
X1298600Y239417D01*
X1298850Y239833D01*
X1299017Y240417D01*
X1298850Y240917D01*
X1298517Y241250D01*
X1297933Y241500D01*
X1295683D01*
Y236500D01*
X1298433D01*
X1299017Y236833D01*
X1299350Y237333D01*
X1299517Y237917D01*
X1299350Y238500D01*
X1298850Y239000D01*
X1298267Y239167D01*
X1295683D01*
G01X1301117Y236500D02*
X1303200Y241500D01*
X1305283Y236500D01*
G01X1304533Y238250D02*
X1301867D01*
G01X1310633Y241083D02*
X1310133Y241333D01*
X1309550Y241500D01*
X1308883D01*
X1308133Y241250D01*
X1307550Y240833D01*
X1307133Y240333D01*
X1306800Y239500D01*
X1306717Y238750D01*
X1306883Y238000D01*
X1307133Y237500D01*
X1307633Y237000D01*
X1308217Y236667D01*
X1308800Y236500D01*
X1309383D01*
X1309967Y236667D01*
X1310467Y236917D01*
X1310883Y237250D01*
G01X1312567Y236500D02*
Y241500D01*
G01X1315733D02*
X1312567Y238417D01*
G01X1316233Y236500D02*
X1313983Y239833D01*
G01X1323767Y236500D02*
Y241500D01*
X1325433D01*
X1326100Y241250D01*
X1326600Y240917D01*
X1327017Y240417D01*
X1327350Y239833D01*
X1327433Y239000D01*
X1327350Y238167D01*
X1327017Y237583D01*
X1326600Y237083D01*
X1326100Y236750D01*
X1325433Y236500D01*
X1323767D01*
G01X1329533D02*
Y241500D01*
X1331617D01*
X1332283Y241250D01*
X1332700Y240917D01*
X1332867Y240250D01*
X1332700Y239583D01*
X1332200Y239167D01*
X1331617Y238917D01*
X1329533D01*
G01X1331617D02*
X1332867Y236500D01*
G01X1335800Y241500D02*
X1337800D01*
G01X1336800D02*
Y236500D01*
G01X1335800D02*
X1337800D01*
G01X1340733Y241500D02*
Y236500D01*
X1344067D01*
G01X1346333Y241500D02*
Y236500D01*
X1349667D01*
G01X1373500D02*
Y239833D01*
G01Y238917D02*
X1373750Y239333D01*
X1374167Y239667D01*
X1374750Y239833D01*
X1375333Y239667D01*
X1375750Y239333D01*
X1376000Y238917D01*
Y236500D01*
G01Y238917D02*
X1376250Y239333D01*
X1376667Y239667D01*
X1377250Y239833D01*
X1377833Y239667D01*
X1378250Y239333D01*
X1378500Y238833D01*
Y236500D01*
G01X1381600Y239833D02*
Y236500D01*
G01Y241167D02*
X1381433Y241250D01*
Y241417D01*
X1381600Y241500D01*
X1381767Y241417D01*
Y241250D01*
X1381600Y241167D01*
G01X1387200Y236500D02*
Y241500D01*
G01X1391550Y237083D02*
X1391967Y236750D01*
X1392550Y236500D01*
X1393050D01*
X1393550Y236667D01*
X1393883Y236917D01*
X1394050Y237250D01*
X1393967Y237750D01*
X1393633Y238000D01*
X1392133Y238500D01*
X1391800Y239083D01*
X1391967Y239500D01*
X1392300Y239750D01*
X1392800Y239833D01*
X1393300Y239750D01*
X1393800Y239500D01*
G01X1397983Y234833D02*
X1397150Y235667D01*
X1396733Y236500D01*
Y239833D01*
X1397150Y240667D01*
X1397983Y241500D01*
G01X1402083Y236500D02*
Y241500D01*
X1405917Y236500D01*
Y241500D01*
G01X1407933Y236500D02*
Y241500D01*
X1409933D01*
X1410600Y241250D01*
X1411100Y240667D01*
X1411267Y240000D01*
X1411100Y239333D01*
X1410683Y238833D01*
X1409933Y238583D01*
X1407933D01*
G01X1415200Y241500D02*
Y236500D01*
G01X1413283Y241500D02*
X1417117D01*
G01X1419050Y236500D02*
Y241500D01*
G01X1422550D02*
Y236500D01*
G01Y239000D02*
X1419050D01*
G01X1426817Y234833D02*
X1427650Y235667D01*
X1428067Y236500D01*
Y239833D01*
X1427650Y240667D01*
X1426817Y241500D01*
G01X1323933Y307500D02*
Y302500D01*
X1327267D01*
G01X1329950Y305833D02*
X1332450Y302500D01*
G01Y305833D02*
X1329950Y302500D01*
G01X1320933Y349300D02*
Y344300D01*
X1324267D01*
G01X1326783D02*
Y347633D01*
G01Y346800D02*
X1327117Y347217D01*
X1327617Y347550D01*
X1328283Y347633D01*
X1328867Y347550D01*
X1329367Y347217D01*
X1329617Y346633D01*
Y344300D01*
G01X1292350Y404300D02*
Y409300D01*
G01X1295850D02*
Y404300D01*
G01Y406800D02*
X1292350D01*
G01X1299700Y404300D02*
X1299033Y404383D01*
X1298450Y404717D01*
X1297950Y405217D01*
X1297617Y405800D01*
X1297450Y406467D01*
Y407133D01*
X1297617Y407800D01*
X1297950Y408383D01*
X1298450Y408883D01*
X1299033Y409217D01*
X1299700Y409300D01*
X1300367Y409217D01*
X1300950Y408883D01*
X1301450Y408383D01*
X1301783Y407800D01*
X1301950Y407133D01*
Y406467D01*
X1301783Y405800D01*
X1301450Y405217D01*
X1300950Y404717D01*
X1300367Y404383D01*
X1299700Y404300D01*
G01X1303633Y409300D02*
Y404300D01*
X1306967D01*
G01X1312567D02*
X1309233D01*
Y409300D01*
X1312567D01*
G01X1311233Y406883D02*
X1309233D01*
G01X1336400Y404300D02*
Y407633D01*
G01Y406717D02*
X1336650Y407133D01*
X1337067Y407467D01*
X1337650Y407633D01*
X1338233Y407467D01*
X1338650Y407133D01*
X1338900Y406717D01*
Y404300D01*
G01Y406717D02*
X1339150Y407133D01*
X1339567Y407467D01*
X1340150Y407633D01*
X1340733Y407467D01*
X1341150Y407133D01*
X1341400Y406633D01*
Y404300D01*
G01X1344500Y407633D02*
Y404300D01*
G01Y408967D02*
X1344333Y409050D01*
Y409217D01*
X1344500Y409300D01*
X1344667Y409217D01*
Y409050D01*
X1344500Y408967D01*
G01X1350100Y404300D02*
Y409300D01*
G01X1354450Y404883D02*
X1354867Y404550D01*
X1355450Y404300D01*
X1355950D01*
X1356450Y404467D01*
X1356783Y404717D01*
X1356950Y405050D01*
X1356867Y405550D01*
X1356533Y405800D01*
X1355033Y406300D01*
X1354700Y406883D01*
X1354867Y407300D01*
X1355200Y407550D01*
X1355700Y407633D01*
X1356200Y407550D01*
X1356700Y407300D01*
G01X1360883Y402633D02*
X1360050Y403467D01*
X1359633Y404300D01*
Y407633D01*
X1360050Y408467D01*
X1360883Y409300D01*
G01X1365233Y404300D02*
Y409300D01*
X1367233D01*
X1367900Y409050D01*
X1368400Y408467D01*
X1368567Y407800D01*
X1368400Y407133D01*
X1367983Y406633D01*
X1367233Y406383D01*
X1365233D01*
G01X1372500Y409300D02*
Y404300D01*
G01X1370583Y409300D02*
X1374417D01*
G01X1376350Y404300D02*
Y409300D01*
G01X1379850D02*
Y404300D01*
G01Y406800D02*
X1376350D01*
G01X1384117Y402633D02*
X1384950Y403467D01*
X1385367Y404300D01*
Y407633D01*
X1384950Y408467D01*
X1384117Y409300D01*
G01X1294017Y823300D02*
X1296100Y818300D01*
X1298183Y823300D01*
G01X1301700Y818300D02*
X1301033Y818383D01*
X1300450Y818717D01*
X1299950Y819217D01*
X1299617Y819800D01*
X1299450Y820467D01*
Y821133D01*
X1299617Y821800D01*
X1299950Y822383D01*
X1300450Y822883D01*
X1301033Y823217D01*
X1301700Y823300D01*
X1302367Y823217D01*
X1302950Y822883D01*
X1303450Y822383D01*
X1303783Y821800D01*
X1303950Y821133D01*
Y820467D01*
X1303783Y819800D01*
X1303450Y819217D01*
X1302950Y818717D01*
X1302367Y818383D01*
X1301700Y818300D01*
G01X1305633D02*
Y823300D01*
X1307633D01*
X1308300Y823050D01*
X1308800Y822467D01*
X1308967Y821800D01*
X1308800Y821133D01*
X1308383Y820633D01*
X1307633Y820383D01*
X1305633D01*
G01X1331850Y370383D02*
X1332267Y370050D01*
X1332850Y369800D01*
X1333350D01*
X1333850Y369967D01*
X1334183Y370217D01*
X1334350Y370550D01*
X1334267Y371050D01*
X1333933Y371300D01*
X1332433Y371800D01*
X1332100Y372383D01*
X1332267Y372800D01*
X1332600Y373050D01*
X1333100Y373133D01*
X1333600Y373050D01*
X1334100Y372800D01*
G01X1338700Y374800D02*
Y369800D01*
G01X1337533Y373133D02*
X1339867D01*
G01X1342883D02*
Y370800D01*
X1343217Y370217D01*
X1343717Y369883D01*
X1344300Y369800D01*
X1344883Y369883D01*
X1345383Y370217D01*
X1345717Y370800D01*
G01Y369800D02*
Y373133D01*
G01X1348400Y369800D02*
Y374800D01*
G01Y372300D02*
X1348817Y372800D01*
X1349317Y373050D01*
X1349817Y373133D01*
X1350567Y372967D01*
X1351067Y372633D01*
X1351400Y372050D01*
Y371383D01*
X1351233Y370717D01*
X1350900Y370217D01*
X1350317Y369883D01*
X1349817Y369800D01*
X1349317Y369883D01*
X1348817Y370133D01*
X1348400Y370550D01*
G01X1361100Y369800D02*
Y374800D01*
G01X1365450Y372050D02*
X1368117D01*
X1367867Y372633D01*
X1367450Y372967D01*
X1366867Y373133D01*
X1366283Y373050D01*
X1365783Y372800D01*
X1365450Y372217D01*
X1365283Y371717D01*
Y371217D01*
X1365450Y370717D01*
X1365867Y370217D01*
X1366367Y369883D01*
X1366950Y369800D01*
X1367533Y369967D01*
X1368117Y370467D01*
G01X1370883Y369800D02*
Y373133D01*
G01Y372300D02*
X1371217Y372717D01*
X1371717Y373050D01*
X1372383Y373133D01*
X1372967Y373050D01*
X1373467Y372717D01*
X1373717Y372133D01*
Y369800D01*
G01X1376733Y368550D02*
X1377317Y368217D01*
X1377983Y368133D01*
X1378567Y368217D01*
X1379067Y368633D01*
X1379400Y369217D01*
Y373133D01*
G01Y372467D02*
X1379067Y372800D01*
X1378567Y373050D01*
X1377983Y373133D01*
X1377317Y372967D01*
X1376900Y372633D01*
X1376567Y372050D01*
X1376400Y371467D01*
X1376483Y370967D01*
X1376817Y370383D01*
X1377317Y369967D01*
X1377983Y369800D01*
X1378483Y369883D01*
X1379067Y370217D01*
X1379400Y370550D01*
G01X1383500Y374800D02*
Y369800D01*
G01X1382333Y373133D02*
X1384667D01*
G01X1387683Y369800D02*
Y374800D01*
G01Y372383D02*
X1388100Y372800D01*
X1388517Y373050D01*
X1389183Y373133D01*
X1389683Y373050D01*
X1390267Y372717D01*
X1390517Y372217D01*
Y369800D01*
G01X1393617Y370717D02*
X1395783D01*
G01Y372217D02*
X1393617D01*
G01X1398717Y371883D02*
X1399300Y372467D01*
X1399800Y372800D01*
X1400467Y372967D01*
X1401050Y372800D01*
X1401467Y372467D01*
X1401800Y371967D01*
X1401883Y371383D01*
X1401800Y370883D01*
X1401467Y370383D01*
X1400967Y369967D01*
X1400383Y369800D01*
X1399717Y369967D01*
X1399133Y370467D01*
X1398800Y371217D01*
X1398717Y372050D01*
X1398883Y373133D01*
X1399133Y373717D01*
X1399550Y374300D01*
X1400133Y374717D01*
X1400717Y374800D01*
X1401300Y374633D01*
X1401717Y374217D01*
G01X1404983Y371467D02*
X1406983D01*
G01X1405900Y372550D02*
Y370383D01*
G01X1410000Y369633D02*
X1413000Y374800D01*
G01X1416017Y371467D02*
X1418183D01*
G01X1420867Y370550D02*
X1421367Y370133D01*
X1421950Y369883D01*
X1422700Y369800D01*
X1423450Y369967D01*
X1424033Y370300D01*
X1424450Y370883D01*
X1424533Y371550D01*
X1424367Y372217D01*
X1423950Y372633D01*
X1423367Y372967D01*
X1422783Y373050D01*
X1422200Y372967D01*
X1421450Y372633D01*
X1421700Y374800D01*
X1423950D01*
G01X1425800Y369800D02*
Y373133D01*
G01Y372217D02*
X1426050Y372633D01*
X1426467Y372967D01*
X1427050Y373133D01*
X1427633Y372967D01*
X1428050Y372633D01*
X1428300Y372217D01*
Y369800D01*
G01Y372217D02*
X1428550Y372633D01*
X1428967Y372967D01*
X1429550Y373133D01*
X1430133Y372967D01*
X1430550Y372633D01*
X1430800Y372133D01*
Y369800D01*
G01X1433900Y373133D02*
Y369800D01*
G01Y374467D02*
X1433733Y374550D01*
Y374717D01*
X1433900Y374800D01*
X1434067Y374717D01*
Y374550D01*
X1433900Y374467D01*
G01X1439500Y369800D02*
Y374800D01*
G01X1356393Y874243D02*
X1355560Y875077D01*
X1355143Y875910D01*
Y879243D01*
X1355560Y880077D01*
X1356393Y880910D01*
G01X1362410Y875910D02*
Y880910D01*
X1361410Y879910D01*
G01Y875910D02*
X1363410D01*
G01X1368010Y875743D02*
X1367843Y875827D01*
Y875993D01*
X1368010Y876077D01*
X1368177Y875993D01*
Y875827D01*
X1368010Y875743D01*
G01X1372027Y880077D02*
X1372527Y880577D01*
X1373110Y880827D01*
X1373777Y880910D01*
X1374610Y880743D01*
X1375193Y880327D01*
X1375360Y879827D01*
X1375277Y879327D01*
X1374943Y878910D01*
X1373277Y878077D01*
X1372527Y877493D01*
X1372027Y876660D01*
X1371860Y875910D01*
X1375360D01*
G01X1376710D02*
Y879243D01*
G01Y878327D02*
X1376960Y878743D01*
X1377377Y879077D01*
X1377960Y879243D01*
X1378543Y879077D01*
X1378960Y878743D01*
X1379210Y878327D01*
Y875910D01*
G01Y878327D02*
X1379460Y878743D01*
X1379877Y879077D01*
X1380460Y879243D01*
X1381043Y879077D01*
X1381460Y878743D01*
X1381710Y878243D01*
Y875910D01*
G01X1382310D02*
Y879243D01*
G01Y878327D02*
X1382560Y878743D01*
X1382977Y879077D01*
X1383560Y879243D01*
X1384143Y879077D01*
X1384560Y878743D01*
X1384810Y878327D01*
Y875910D01*
G01Y878327D02*
X1385060Y878743D01*
X1385477Y879077D01*
X1386060Y879243D01*
X1386643Y879077D01*
X1387060Y878743D01*
X1387310Y878243D01*
Y875910D01*
G01X1393843D02*
Y880910D01*
X1396010Y876743D01*
X1398177Y880910D01*
Y875910D01*
G01X1403110D02*
Y879243D01*
G01Y878660D02*
X1402777Y878993D01*
X1402277Y879160D01*
X1401693Y879243D01*
X1401110Y879077D01*
X1400610Y878743D01*
X1400277Y878243D01*
X1400110Y877577D01*
X1400277Y876910D01*
X1400610Y876410D01*
X1401110Y876077D01*
X1401693Y875910D01*
X1402277Y875993D01*
X1402777Y876243D01*
X1403110Y876577D01*
G01X1405960Y879243D02*
X1408460Y875910D01*
G01Y879243D02*
X1405960Y875910D01*
G01X1413227Y874243D02*
X1414060Y875077D01*
X1414477Y875910D01*
Y879243D01*
X1414060Y880077D01*
X1413227Y880910D01*
G01X1358477Y886030D02*
X1355143Y887697D01*
X1358477Y889363D01*
G01X1361327Y886947D02*
X1363493D01*
G01Y888447D02*
X1361327D01*
G01X1368010Y891030D02*
X1367343Y890863D01*
X1366843Y890447D01*
X1366510Y889947D01*
X1366260Y889280D01*
X1366177Y888530D01*
X1366260Y887780D01*
X1366510Y887113D01*
X1366843Y886613D01*
X1367343Y886197D01*
X1368010Y886030D01*
X1368677Y886197D01*
X1369177Y886613D01*
X1369510Y887113D01*
X1369760Y887780D01*
X1369843Y888530D01*
X1369760Y889280D01*
X1369510Y889947D01*
X1369177Y890447D01*
X1368677Y890863D01*
X1368010Y891030D01*
G01X1373610Y885863D02*
X1373443Y885947D01*
Y886113D01*
X1373610Y886197D01*
X1373777Y886113D01*
Y885947D01*
X1373610Y885863D01*
G01X1379043Y886030D02*
X1379210Y887113D01*
X1379460Y888030D01*
X1379793Y888863D01*
X1380210Y889780D01*
X1380877Y891030D01*
X1377543D01*
G01X1382977Y886780D02*
X1383477Y886363D01*
X1384060Y886113D01*
X1384810Y886030D01*
X1385560Y886197D01*
X1386143Y886530D01*
X1386560Y887113D01*
X1386643Y887780D01*
X1386477Y888447D01*
X1386060Y888863D01*
X1385477Y889197D01*
X1384893Y889280D01*
X1384310Y889197D01*
X1383560Y888863D01*
X1383810Y891030D01*
X1386060D01*
G01X1388910Y885863D02*
X1391910Y891030D01*
G01X1388910D02*
X1388410Y890863D01*
X1388160Y890613D01*
X1387993Y890113D01*
X1388160Y889613D01*
X1388410Y889363D01*
X1388910Y889197D01*
X1389410Y889363D01*
X1389660Y889613D01*
X1389827Y890113D01*
X1389660Y890613D01*
X1389410Y890863D01*
X1388910Y891030D01*
G01X1391910Y887697D02*
X1391410Y887530D01*
X1391160Y887280D01*
X1390993Y886780D01*
X1391160Y886280D01*
X1391410Y886030D01*
X1391910Y885863D01*
X1392410Y886030D01*
X1392660Y886280D01*
X1392827Y886780D01*
X1392660Y887280D01*
X1392410Y887530D01*
X1391910Y887697D01*
G01X1348140Y939300D02*
Y870800D01*
G01X1354683Y930467D02*
X1356683D01*
G01X1355600Y931550D02*
Y929383D01*
G01X1359700Y928633D02*
X1362700Y933800D01*
G01X1365717Y930467D02*
X1367883D01*
G01X1370567Y929550D02*
X1371067Y929133D01*
X1371650Y928883D01*
X1372400Y928800D01*
X1373150Y928967D01*
X1373733Y929300D01*
X1374150Y929883D01*
X1374233Y930550D01*
X1374067Y931217D01*
X1373650Y931633D01*
X1373067Y931967D01*
X1372483Y932050D01*
X1371900Y931967D01*
X1371150Y931633D01*
X1371400Y933800D01*
X1373650D01*
G01X1375500Y928800D02*
Y932133D01*
G01Y931217D02*
X1375750Y931633D01*
X1376167Y931967D01*
X1376750Y932133D01*
X1377333Y931967D01*
X1377750Y931633D01*
X1378000Y931217D01*
Y928800D01*
G01Y931217D02*
X1378250Y931633D01*
X1378667Y931967D01*
X1379250Y932133D01*
X1379833Y931967D01*
X1380250Y931633D01*
X1380500Y931133D01*
Y928800D01*
G01X1383600Y932133D02*
Y928800D01*
G01Y933467D02*
X1383433Y933550D01*
Y933717D01*
X1383600Y933800D01*
X1383767Y933717D01*
Y933550D01*
X1383600Y933467D01*
G01X1389200Y928800D02*
Y933800D01*
G01X1354683Y915467D02*
X1356683D01*
G01X1355600Y916550D02*
Y914383D01*
G01X1359700Y913633D02*
X1362700Y918800D01*
G01X1365717Y915467D02*
X1367883D01*
G01X1370567Y914550D02*
X1371067Y914133D01*
X1371650Y913883D01*
X1372400Y913800D01*
X1373150Y913967D01*
X1373733Y914300D01*
X1374150Y914883D01*
X1374233Y915550D01*
X1374067Y916217D01*
X1373650Y916633D01*
X1373067Y916967D01*
X1372483Y917050D01*
X1371900Y916967D01*
X1371150Y916633D01*
X1371400Y918800D01*
X1373650D01*
G01X1375500Y913800D02*
Y917133D01*
G01Y916217D02*
X1375750Y916633D01*
X1376167Y916967D01*
X1376750Y917133D01*
X1377333Y916967D01*
X1377750Y916633D01*
X1378000Y916217D01*
Y913800D01*
G01Y916217D02*
X1378250Y916633D01*
X1378667Y916967D01*
X1379250Y917133D01*
X1379833Y916967D01*
X1380250Y916633D01*
X1380500Y916133D01*
Y913800D01*
G01X1383600Y917133D02*
Y913800D01*
G01Y918467D02*
X1383433Y918550D01*
Y918717D01*
X1383600Y918800D01*
X1383767Y918717D01*
Y918550D01*
X1383600Y918467D01*
G01X1389200Y913800D02*
Y918800D01*
G01X1354683Y900467D02*
X1356683D01*
G01X1355600Y901550D02*
Y899383D01*
G01X1359700Y898633D02*
X1362700Y903800D01*
G01X1365717Y900467D02*
X1367883D01*
G01X1370817Y902967D02*
X1371317Y903467D01*
X1371900Y903717D01*
X1372567Y903800D01*
X1373400Y903633D01*
X1373983Y903217D01*
X1374150Y902717D01*
X1374067Y902217D01*
X1373733Y901800D01*
X1372067Y900967D01*
X1371317Y900383D01*
X1370817Y899550D01*
X1370650Y898800D01*
X1374150D01*
G01X1375500D02*
Y902133D01*
G01Y901217D02*
X1375750Y901633D01*
X1376167Y901967D01*
X1376750Y902133D01*
X1377333Y901967D01*
X1377750Y901633D01*
X1378000Y901217D01*
Y898800D01*
G01Y901217D02*
X1378250Y901633D01*
X1378667Y901967D01*
X1379250Y902133D01*
X1379833Y901967D01*
X1380250Y901633D01*
X1380500Y901133D01*
Y898800D01*
G01X1383600Y902133D02*
Y898800D01*
G01Y903467D02*
X1383433Y903550D01*
Y903717D01*
X1383600Y903800D01*
X1383767Y903717D01*
Y903550D01*
X1383600Y903467D01*
G01X1389200Y898800D02*
Y903800D01*
G01X1456600Y939410D02*
Y870910D01*
G54D12*
G01X979452Y801154D02*
Y724154D01*
G01X986327Y717279D02*
Y810779D01*
G01X971202Y717279D02*
X986327D01*
G01X971202Y724154D02*
Y717279D01*
G01X979452Y724154D02*
X957452D01*
G01D02*
Y801154D01*
G01X971202Y810779D02*
Y803904D01*
G01X986327Y810779D02*
X971202D01*
G01X957452Y801154D02*
X979452D01*
G01X1012452D02*
Y724154D01*
G01D02*
X1056452D01*
G01X1020702Y717279D02*
Y724154D01*
G01X1005577Y717279D02*
X1020702D01*
G01X1005577Y810779D02*
Y717279D01*
G01X1056452Y801154D02*
X1012452D01*
G01X1020702Y803904D02*
Y810779D01*
G01D02*
X1005577D01*
G01X1082577Y717279D02*
X1097702D01*
G01X1082577Y810779D02*
Y717279D01*
G01X1063327D02*
Y810779D01*
G01X1048202Y717279D02*
X1063327D01*
G01X1048202Y724154D02*
Y717279D01*
G01X1056452Y724154D02*
Y801154D01*
G01X1097702Y810779D02*
X1082577D01*
G01X1048202D02*
Y803904D01*
G01X1063327Y810779D02*
X1048202D01*
G01X1133452Y724154D02*
Y801154D01*
G01X1125202Y717279D02*
X1140327D01*
G01X1125202Y724154D02*
Y717279D01*
G01X1097702D02*
Y724154D01*
G01X1089452Y801154D02*
Y724154D01*
G01D02*
X1133452D01*
G01X1125202Y808029D02*
Y801154D01*
G01X1140327Y808029D02*
X1125202D01*
G01X1097702Y803904D02*
Y810779D01*
G01X1133452Y801154D02*
X1089452D01*
G01X1174702Y717279D02*
Y724154D01*
G01X1159577Y717279D02*
X1174702D01*
G01X1159577Y808029D02*
Y717279D01*
G01X1166452Y801154D02*
Y724154D01*
G01D02*
X1210452D01*
G01X1140327Y717279D02*
Y808029D01*
G01X1174702D02*
X1159577D01*
G01X1174702Y801154D02*
Y808029D01*
G01X1210452Y801154D02*
X1166452D01*
G01X1210452Y724154D02*
Y801154D01*
G01X1202202Y717279D02*
X1236577D01*
G01X1202202Y724154D02*
Y717279D01*
G01X1251702Y808029D02*
X1217327D01*
G01X1202202D02*
Y801154D01*
G01X1217327Y808029D02*
X1202202D01*
G01X1279202Y717279D02*
X1294327D01*
G01X1279202Y724154D02*
Y717279D01*
G01X1243452Y801154D02*
Y724154D01*
G01D02*
X1287452D01*
G01X1251702Y717279D02*
Y724154D01*
G01X1236577Y717279D02*
X1251702D01*
G01X1279202Y808029D02*
Y801154D01*
G01X1294327Y808029D02*
X1279202D01*
G01X1287452Y801154D02*
X1243452D01*
G01X1251702D02*
Y808029D01*
G01X1328702Y717279D02*
Y724154D01*
G01X1320452Y801154D02*
Y724154D01*
G01D02*
X1364452D01*
G01X1313577Y717279D02*
X1328702D01*
G01X1313577Y808029D02*
Y717279D01*
G01X1294327D02*
Y808029D01*
G01X1287452Y724154D02*
Y801154D01*
G01X1328702D02*
Y808029D01*
G01X1364452Y801154D02*
X1320452D01*
G01X1328702Y808029D02*
X1313577D01*
G01X1364452Y724154D02*
Y801154D01*
G54D13*
G01X405690Y429630D02*
Y446630D01*
G01X455190Y408630D02*
Y392630D01*
G01X416690Y408630D02*
Y392630D01*
G01X459280Y416480D02*
G02X463962Y408660I-4190J-7820D01*
G01X461790Y410580D01*
X465020Y410750D01*
X464060Y408650D01*
G01X466190Y429630D02*
Y446630D01*
G01X470082Y418953D02*
X466052Y413463D01*
X470252Y413443D01*
G01X553162Y390343D02*
X549132Y384853D01*
X553332Y384833D01*
G54D14*
G01X1005302Y778146D02*
X986602Y796846D01*
G01X1005302Y775812D02*
X986602Y794511D01*
G01X1005302Y773478D02*
X986602Y792178D01*
G01X1005302Y771145D02*
X986602Y789845D01*
G01X1005302Y768812D02*
X986602Y787511D01*
G01Y779705D02*
X1005302Y798404D01*
G01X986602Y782038D02*
X1005302Y800738D01*
G01X986602Y784372D02*
X1005302Y803072D01*
G01X986602Y786706D02*
X1005302Y805405D01*
G01X986602Y789039D02*
X1005302Y807739D01*
G01X986602Y791372D02*
X1009858Y814629D01*
G01X1005302Y766478D02*
X986602Y785178D01*
G01X1000798Y768648D02*
X986602Y782845D01*
G01X997303Y769810D02*
X986602Y780511D01*
G01X994930Y769849D02*
X986602Y778177D01*
G01X992992Y769453D02*
X986602Y775844D01*
G01X991338Y768774D02*
X986602Y773511D01*
G01X989910Y767869D02*
X986602Y771177D01*
G01X988680Y766766D02*
X986602Y768844D01*
G01X987645Y765468D02*
X986602Y766511D01*
G01X986815Y763963D02*
X986602Y764177D01*
G01Y765705D02*
X1005302Y784403D01*
G01X986602Y768038D02*
X1005302Y786738D01*
G01X986602Y770371D02*
X1005302Y789071D01*
G01X986602Y772705D02*
X1005302Y791404D01*
G01X986602Y775038D02*
X1005302Y793738D01*
G01X986602Y777371D02*
X1005302Y796071D01*
G01X986602Y763444D02*
Y808029D01*
G01Y763445D02*
Y763444D01*
G01X1005301Y763445D02*
G03X986603I-9349J-3541D01*
G01X969940Y814629D02*
X986525D01*
G01X1005302Y794479D02*
X990153Y809629D01*
G01X987927Y811854D02*
X985152Y814629D01*
G01X1005302Y792146D02*
X982819Y814629D01*
G01X1005302Y789813D02*
X980486Y814629D01*
G01X1005302Y787479D02*
X986602Y806179D01*
G01X984752Y808029D02*
X978152Y814629D01*
G01X1005302Y785146D02*
X986602Y803846D01*
G01X982419Y808029D02*
X975819Y814629D01*
G01X1005302Y782813D02*
X986602Y801512D01*
G01X980085Y808029D02*
X973485Y814629D01*
G01X1005302Y780479D02*
X986602Y799179D01*
G01X977751Y808029D02*
X971151Y814629D01*
G01X975418Y808029D02*
X969379Y814067D01*
G01X973085Y808029D02*
X968213Y812901D01*
G01X970927Y807853D02*
X967352Y811428D01*
G01X970927Y805520D02*
X967352Y809095D01*
G01X970927Y803187D02*
X967352Y806761D01*
G01X970350Y801429D02*
X967352Y804428D01*
G01X968017Y801429D02*
X967352Y802095D01*
G01X986602Y793706D02*
X1007525Y814629D01*
G01X986602Y796039D02*
X998706Y808144D01*
G01X986602Y798372D02*
X995982Y807752D01*
G01X986602Y800707D02*
X993870Y807974D01*
G01X986602Y803040D02*
X992096Y808534D01*
G01X986602Y805373D02*
X990571Y809342D01*
G01X986602Y807707D02*
X989255Y810360D01*
G01X984591Y808029D02*
X988136Y811575D01*
G01X982258Y808029D02*
X987218Y812989D01*
G01X979924Y808029D02*
X986524Y814629D01*
G01X977591Y808029D02*
X984191Y814629D01*
G01X968658Y801429D02*
X970927Y803699D01*
G01X975258Y808029D02*
X981858Y814629D01*
G01X967352Y802457D02*
X970927Y806032D01*
G01X972923Y808029D02*
X979523Y814629D01*
G01X967352Y804791D02*
X977190Y814629D01*
G01X967352Y807124D02*
X974857Y814629D01*
G01X967352Y809457D02*
X972523Y814629D01*
G01X967352Y811791D02*
X970190Y814629D01*
G01X986525D02*
G03X1005379I9427J3024D01*
G01X967352Y812040D02*
X969940Y814629D01*
G01X967352Y801429D02*
Y812040D01*
G01X970927Y801429D02*
X967352D01*
G01X970927Y808304D02*
Y801429D01*
G01X971202Y808029D02*
X970927Y808304D01*
G01X986602Y808029D02*
X971202D01*
G01X1005302Y764145D02*
X1004696Y764751D01*
G01X1004557Y764993D02*
X1005302Y765736D01*
G01X1003588Y766357D02*
X1005302Y768070D01*
G01X1002423Y767525D02*
X1005302Y770404D01*
G01X1001062Y768497D02*
X1005302Y772737D01*
G01X999487Y769255D02*
X1005302Y775070D01*
G01X997654Y769756D02*
X1005302Y777404D01*
G01X995454Y769889D02*
X1005302Y779737D01*
G01Y763444D02*
X1005301Y763445D01*
G01X1005302Y808029D02*
Y763444D01*
G01X992529Y769297D02*
X1005302Y782070D01*
G01X1047927Y805525D02*
X1038822Y814629D01*
G01X1047927Y803190D02*
X1036488Y814629D01*
G01X1047355Y801429D02*
X1034155Y814629D01*
G01X1045022Y801429D02*
X1031822Y814629D01*
G01X1042688Y801429D02*
X1029488Y814629D01*
G01X1040354Y801429D02*
X1027154Y814629D01*
G01X1038662Y801429D02*
X1051860Y814629D01*
G01X1036327Y801429D02*
X1049527Y814629D01*
G01X1033994Y801429D02*
X1047194Y814629D01*
G01X1031661Y801429D02*
X1044860Y814629D01*
G01X1029327Y801429D02*
X1042527Y814629D01*
G01X1026994Y801429D02*
X1040193Y814628D01*
G01X1038020Y801429D02*
X1024821Y814629D01*
G01X1005379D02*
X1063525D01*
G01X1035687Y801429D02*
X1022487Y814629D01*
G01X1033354Y801429D02*
X1020154Y814629D01*
G01X1031020Y801429D02*
X1017821Y814629D01*
G01X1028687Y801429D02*
X1015487Y814629D01*
G01X1026354Y801429D02*
X1020977Y806806D01*
G01X1019440Y808343D02*
X1013154Y814629D01*
G01X1024021Y801429D02*
X1020977Y804473D01*
G01X1017107Y808343D02*
X1010821Y814629D01*
G01X1021686Y801429D02*
X1020977Y802139D01*
G01X1014773Y808343D02*
X1008486Y814629D01*
G01X1012440Y808343D02*
X1006153Y814629D01*
G01X1010107Y808343D02*
X1004942Y813507D01*
G01X1007772Y808343D02*
X1004094Y812021D01*
G01X1005527Y808255D02*
X1003040Y810742D01*
G01X1005302Y806147D02*
X1001791Y809657D01*
G01X1005302Y803814D02*
X1000338Y808777D01*
G01X1005302Y801480D02*
X998653Y808128D01*
G01X1005302Y799147D02*
X996670Y807778D01*
G01X1005302Y796814D02*
X994207Y807907D01*
G01X1024661Y801429D02*
X1037860Y814629D01*
G01X1022327Y801429D02*
X1035527Y814629D01*
G01X1020977Y802413D02*
X1033192Y814628D01*
G01X1020977Y804746D02*
X1030859Y814629D01*
G01X1020977Y807080D02*
X1028526Y814629D01*
G01X1019907Y808343D02*
X1026192Y814628D01*
G01X1017572Y808343D02*
X1023859Y814629D01*
G01X1015239Y808343D02*
X1021526Y814629D01*
G01X1012906Y808343D02*
X1019193Y814629D01*
G01X1010572Y808343D02*
X1016858Y814629D01*
G01X1008239Y808343D02*
X1014525Y814629D01*
G01X1005906Y808343D02*
X1012192Y814629D01*
G01X1005615Y808343D02*
X1005302Y808029D01*
G01X1020757Y808343D02*
X1005615D01*
G01X1020977Y808304D02*
X1020757Y808343D01*
G01X1020977Y801429D02*
Y808304D01*
G01X1047927Y801429D02*
X1020977D01*
G01X1082302Y743148D02*
X1063602Y761848D01*
G01X1082302Y740814D02*
X1063602Y759514D01*
G01X1082302Y738481D02*
X1063602Y757181D01*
G01X1082302Y736148D02*
X1063602Y754848D01*
G01X1082302Y733813D02*
X1063602Y752513D01*
G01X1082302Y731480D02*
X1063602Y750180D01*
G01X1082302Y729147D02*
X1063602Y747847D01*
G01X1082302Y726814D02*
X1063602Y745513D01*
G01X1082302Y724480D02*
X1063602Y743180D01*
G01X1082302Y722147D02*
X1063602Y740847D01*
G01X1082302Y719814D02*
X1063602Y738513D01*
G01X1082302Y717479D02*
X1063602Y736179D01*
G01Y719032D02*
X1082302Y737732D01*
G01X1063602Y721365D02*
X1082302Y740065D01*
G01X1063602Y723698D02*
X1082302Y742398D01*
G01X1063602Y726032D02*
X1082302Y744731D01*
G01X1063602Y728365D02*
X1082302Y747065D01*
G01X1063602Y730698D02*
X1082302Y749398D01*
G01X1063602Y733032D02*
X1082302Y751731D01*
G01X1063602Y735365D02*
X1082302Y754065D01*
G01X1063602Y737699D02*
X1082302Y756399D01*
G01X1063602Y740033D02*
X1082302Y758732D01*
G01X1063602Y742366D02*
X1082302Y761066D01*
G01Y717004D02*
X1097977D01*
G01X1082302Y808304D02*
Y717004D01*
G01X1063602D02*
Y808304D01*
G01X1091019Y713429D02*
X1087444Y717004D01*
G01X1088685Y713429D02*
X1085111Y717004D01*
G01X1086352Y713429D02*
X1082777Y717004D01*
G01X1084019Y713429D02*
X1063602Y733846D01*
G01X1081686Y713429D02*
X1063602Y731512D01*
G01X1079352Y713429D02*
X1063602Y729179D01*
G01X1077019Y713429D02*
X1063602Y726846D01*
G01X1074685Y713429D02*
X1063602Y724512D01*
G01X1072351Y713429D02*
X1063602Y722179D01*
G01X1070018Y713429D02*
X1063602Y719846D01*
G01X1067685Y713429D02*
X1063602Y717511D01*
G01X1065351Y713429D02*
X1061776Y717004D01*
G01X1086001Y713429D02*
X1089576Y717004D01*
G01X1083668Y713429D02*
X1087243Y717004D01*
G01X1081334Y713429D02*
X1084909Y717004D01*
G01X1079001Y713429D02*
X1082576Y717004D01*
G01X1076668Y713429D02*
X1082302Y719063D01*
G01X1074333Y713429D02*
X1082302Y721397D01*
G01X1072000Y713429D02*
X1082302Y723731D01*
G01X1069667Y713429D02*
X1082302Y726064D01*
G01X1067333Y713429D02*
X1082302Y728397D01*
G01X1065000Y713429D02*
X1082302Y730731D01*
G01X1062667Y713429D02*
X1082302Y733064D01*
G01X1060333Y713429D02*
X1082302Y735397D01*
G01X1063018Y713429D02*
X1059443Y717004D01*
G01X1060685Y713429D02*
X1057110Y717004D01*
G01X1047927Y723853D02*
X1047900Y723879D01*
G01X1047927Y721520D02*
X1045567Y723879D01*
G01X1047927Y719187D02*
X1044352Y722761D01*
G01X1046637Y713733D02*
X1049907Y717004D01*
G01X1045469Y714900D02*
X1047927Y717356D01*
G01X1044352Y716115D02*
X1047927Y719690D01*
G01X1044352Y718449D02*
X1047927Y722024D01*
G01X1044352Y720783D02*
X1047448Y723879D01*
G01X1044352Y723116D02*
X1045115Y723879D01*
G01X1047927Y717004D02*
X1063602D01*
G01X1047927Y723879D02*
Y717004D01*
G01X1044352Y723879D02*
X1047927D01*
G01X1044352Y716018D02*
Y723879D01*
G01X1058350Y713429D02*
X1054775Y717004D01*
G01X1056017Y713429D02*
X1052442Y717004D01*
G01X1053684Y713429D02*
X1050109Y717004D01*
G01X1051350Y713429D02*
X1044352Y720427D01*
G01X1049017Y713429D02*
X1044352Y718094D01*
G01X1058000Y713429D02*
X1061575Y717004D01*
G01X1055666Y713429D02*
X1059240Y717003D01*
G01X1053333Y713429D02*
X1056907Y717004D01*
G01X1050999Y713429D02*
X1054574Y717003D01*
G01X1048666Y713429D02*
X1052240Y717003D01*
G01X1098962Y713429D02*
X1046940D01*
G01D02*
X1044352Y716018D01*
G01X1082302Y787483D02*
X1063602Y806183D01*
G01X1082302Y785150D02*
X1063602Y803849D01*
G01X1082302Y782816D02*
X1063602Y801516D01*
G01X1082302Y780483D02*
X1063602Y799183D01*
G01Y779701D02*
X1082302Y798401D01*
G01X1063602Y782034D02*
X1082302Y800734D01*
G01X1063602Y784368D02*
X1082302Y803067D01*
G01X1063602Y786701D02*
X1082302Y805401D01*
G01X1063602Y789034D02*
X1082302Y807734D01*
G01X1063602Y791369D02*
X1086862Y814628D01*
G01X1082302Y778150D02*
X1063602Y796849D01*
G01X1082302Y775816D02*
X1063602Y794516D01*
G01X1082302Y773483D02*
X1063602Y792183D01*
G01X1082302Y771150D02*
X1063602Y789848D01*
G01X1082302Y768815D02*
X1063602Y787515D01*
G01X1082302Y766482D02*
X1063602Y785182D01*
G01X1082302Y764149D02*
X1063602Y782848D01*
G01X1082302Y761815D02*
X1063602Y780515D01*
G01X1082302Y759482D02*
X1063602Y778182D01*
G01X1082302Y757149D02*
X1063602Y775848D01*
G01X1082302Y754815D02*
X1063602Y773515D01*
G01X1082302Y752481D02*
X1063602Y771181D01*
G01X1082302Y750148D02*
X1063602Y768847D01*
G01X1082302Y747814D02*
X1063602Y766514D01*
G01Y747033D02*
X1082302Y765732D01*
G01X1063602Y749366D02*
X1082302Y768066D01*
G01X1063602Y751699D02*
X1082302Y770399D01*
G01X1063602Y754034D02*
X1082302Y772732D01*
G01X1063602Y756367D02*
X1082302Y775067D01*
G01X1063602Y758700D02*
X1082302Y777400D01*
G01X1063602Y761034D02*
X1082302Y779733D01*
G01X1063602Y763367D02*
X1082302Y782067D01*
G01X1063602Y765700D02*
X1082302Y784400D01*
G01X1063602Y768033D02*
X1082302Y786733D01*
G01X1063602Y770367D02*
X1082302Y789067D01*
G01X1063602Y772701D02*
X1082302Y791401D01*
G01X1063602Y775034D02*
X1082302Y793734D01*
G01X1063602Y777368D02*
X1082302Y796068D01*
G01Y745481D02*
X1063602Y764181D01*
G01Y744699D02*
X1082302Y763399D01*
G01Y792150D02*
X1059822Y814629D01*
G01X1082302Y789817D02*
X1057489Y814629D01*
G01X1082379D02*
X1098962D01*
G01X1094149Y808304D02*
X1087824Y814629D01*
G01X1091816Y808304D02*
X1085491Y814629D01*
G01X1089483Y808304D02*
X1083158Y814629D01*
G01X1087148Y808304D02*
X1081943Y813509D01*
G01X1084815Y808304D02*
X1081096Y812023D01*
G01X1082482Y808304D02*
X1080042Y810743D01*
G01X1082302Y806150D02*
X1078793Y809659D01*
G01X1082302Y803817D02*
X1077341Y808778D01*
G01X1082302Y801484D02*
X1075657Y808129D01*
G01X1082302Y799150D02*
X1073673Y807778D01*
G01X1082302Y796817D02*
X1071213Y807906D01*
G01X1082302Y794484D02*
X1067167Y809619D01*
G01X1064917Y811867D02*
X1062156Y814629D01*
G01X1087538Y808304D02*
X1093863Y814629D01*
G01X1085205Y808304D02*
X1091530Y814629D01*
G01X1082871Y808304D02*
X1089196Y814629D01*
G01X1063602Y793702D02*
X1084529Y814629D01*
G01X1063602Y796035D02*
X1075712Y808145D01*
G01X1063602Y798369D02*
X1072986Y807752D01*
G01X1063602Y800702D02*
X1070873Y807973D01*
G01X1063602Y803035D02*
X1069099Y808533D01*
G01X1063602Y805369D02*
X1067574Y809340D01*
G01X1063602Y807703D02*
X1066257Y810358D01*
G01X1061869Y808304D02*
X1065139Y811572D01*
G01X1097977Y808304D02*
X1082302D01*
G01X1063525Y814629D02*
G03X1082379I9427J3024D01*
G01X1061481Y808304D02*
X1055156Y814629D01*
G01X1059148Y808304D02*
X1052823Y814629D01*
G01X1056814Y808304D02*
X1050489Y814629D01*
G01X1054481Y808304D02*
X1048156Y814629D01*
G01X1052146Y808304D02*
X1045823Y814629D01*
G01X1049813Y808304D02*
X1043488Y814629D01*
G01X1047927Y807858D02*
X1041155Y814629D01*
G01X1059536Y808304D02*
X1064219Y812987D01*
G01X1057203Y808304D02*
X1063525Y814626D01*
G01X1054870Y808304D02*
X1061195Y814629D01*
G01X1045661Y801429D02*
X1047927Y803694D01*
G01X1052536Y808304D02*
X1058861Y814629D01*
G01X1043328Y801429D02*
X1047927Y806028D01*
G01X1050203Y808304D02*
X1056528Y814629D01*
G01X1040995Y801429D02*
X1054195Y814629D01*
G01X1047927Y808304D02*
Y801429D01*
G01X1063602Y808304D02*
X1047927D01*
G01X1101552Y721564D02*
X1099237Y723878D01*
G01X1101552Y719231D02*
X1097977Y722806D01*
G01X1101552Y716898D02*
X1097977Y720473D01*
G01X1100825Y715290D02*
X1097977Y718138D01*
G01X1099658Y714124D02*
X1096778Y717004D01*
G01X1097977Y718405D02*
X1101552Y721980D01*
G01X1097977Y720738D02*
X1101117Y723879D01*
G01X1097977Y723072D02*
X1098784Y723879D01*
G01X1101552D02*
Y716018D01*
G01X1097977Y723879D02*
X1101552D01*
G01X1097977Y717004D02*
Y723879D01*
G01X1098020Y713429D02*
X1094445Y717004D01*
G01X1097669Y713429D02*
X1101552Y717312D01*
G01X1095335Y713429D02*
X1101552Y719645D01*
G01X1093002Y713429D02*
X1096577Y717004D01*
G01X1101552Y716018D02*
X1098962Y713429D01*
G01X1095686D02*
X1092112Y717004D01*
G01X1093352Y713429D02*
X1089777Y717004D01*
G01X1090668Y713429D02*
X1094242Y717004D01*
G01X1088334Y713429D02*
X1091909Y717004D01*
G01X1101552Y810236D02*
X1097158Y814629D01*
G01X1101552Y807902D02*
X1094824Y814629D01*
G01X1101552Y803235D02*
X1097977Y806809D01*
G01X1101024Y801429D02*
X1097977Y804476D01*
G01X1098691Y801429D02*
X1097977Y802143D01*
G01X1099331Y801429D02*
X1101552Y803650D01*
G01X1097977Y802408D02*
X1101552Y805983D01*
G01X1097977Y804742D02*
X1101552Y808317D01*
G01X1097977Y807076D02*
X1101552Y810651D01*
G01X1096871Y808304D02*
X1101080Y812512D01*
G01X1094538Y808304D02*
X1099913Y813679D01*
G01X1097977Y801429D02*
Y808304D01*
G01X1101552Y801429D02*
X1097977D01*
G01X1101552Y812040D02*
Y801429D01*
G01X1098962Y814629D02*
X1101552Y812040D01*
G01Y805569D02*
X1092491Y814629D01*
G01X1096483Y808304D02*
X1090158Y814629D01*
G01X1092205Y808304D02*
X1098530Y814629D01*
G01X1089871Y808304D02*
X1096196Y814629D01*
G01X1231925Y721679D02*
X1236302Y726056D01*
G01X1229591Y721679D02*
X1236302Y728389D01*
G01X1227258Y721679D02*
X1236302Y730722D01*
G01X1224925Y721679D02*
X1236302Y733057D01*
G01Y740823D02*
X1217602Y759521D01*
G01X1236302Y738488D02*
X1217602Y757188D01*
G01X1236302Y736155D02*
X1217602Y754855D01*
G01X1222590Y721679D02*
X1236302Y735390D01*
G01X1220257Y721679D02*
X1236302Y737723D01*
G01X1217924Y721679D02*
X1236302Y740057D01*
G01X1217602Y723690D02*
X1236302Y742390D01*
G01X1217602Y726024D02*
X1236302Y744723D01*
G01X1217602Y728357D02*
X1236302Y747057D01*
G01X1217602Y730690D02*
X1236302Y749390D01*
G01X1217602Y733025D02*
X1236302Y751724D01*
G01X1217602Y735358D02*
X1236302Y754058D01*
G01X1217602Y737691D02*
X1236302Y756391D01*
G01X1217602Y740025D02*
X1236302Y758724D01*
G01X1217602Y742358D02*
X1236302Y761058D01*
G01Y733822D02*
X1217602Y752521D01*
G01X1236302Y731488D02*
X1217602Y750188D01*
G01X1236302Y729155D02*
X1217602Y747855D01*
G01X1236302Y726822D02*
X1217602Y745521D01*
G01X1236302Y724488D02*
X1217602Y743188D01*
G01X1236302Y722154D02*
X1217602Y740854D01*
G01X1234444Y721679D02*
X1217602Y738520D01*
G01X1232110Y721679D02*
X1217602Y736187D01*
G01X1229777Y721679D02*
X1217602Y733854D01*
G01X1227444Y721679D02*
X1217602Y731520D01*
G01X1225109Y721679D02*
X1217602Y729187D01*
G01X1222776Y721679D02*
X1217602Y726854D01*
G01X1220443Y721679D02*
X1217602Y724521D01*
G01X1218109Y721679D02*
X1217602Y722186D01*
G01X1236302Y721679D02*
X1217602D01*
G01D02*
Y803629D01*
G01Y779693D02*
X1236302Y798393D01*
G01X1217602Y782026D02*
X1236302Y800726D01*
G01X1217602Y784361D02*
X1236302Y803059D01*
G01X1217602Y786694D02*
X1234537Y803629D01*
G01X1217602Y789027D02*
X1232204Y803629D01*
G01X1217602Y791361D02*
X1229870Y803629D01*
G01X1236302Y787491D02*
X1220164Y803629D01*
G01X1236302Y785158D02*
X1217831Y803629D01*
G01X1236302Y782824D02*
X1217602Y801524D01*
G01X1236302Y780491D02*
X1217602Y799191D01*
G01X1236302Y778158D02*
X1217602Y796857D01*
G01X1236302Y775823D02*
X1217602Y794523D01*
G01X1236302Y773490D02*
X1217602Y792190D01*
G01X1236302Y771157D02*
X1217602Y789856D01*
G01X1236302Y768823D02*
X1217602Y787523D01*
G01Y747024D02*
X1236302Y765724D01*
G01X1217602Y749359D02*
X1236302Y768059D01*
G01X1217602Y751692D02*
X1236302Y770392D01*
G01X1217602Y754025D02*
X1236302Y772725D01*
G01X1217602Y756359D02*
X1236302Y775058D01*
G01X1217602Y758692D02*
X1236302Y777392D01*
G01X1217602Y761025D02*
X1236302Y779725D01*
G01X1217602Y763359D02*
X1236302Y782058D01*
G01X1217602Y765692D02*
X1236302Y784392D01*
G01X1217602Y768026D02*
X1236302Y786726D01*
G01X1217602Y770360D02*
X1236302Y789059D01*
G01X1217602Y772693D02*
X1236302Y791393D01*
G01X1217602Y775026D02*
X1236302Y793726D01*
G01X1217602Y777360D02*
X1236302Y796059D01*
G01Y766490D02*
X1217602Y785190D01*
G01X1236302Y764157D02*
X1217602Y782857D01*
G01X1236302Y761823D02*
X1217602Y780523D01*
G01X1236302Y759490D02*
X1217602Y778190D01*
G01X1236302Y757156D02*
X1217602Y775856D01*
G01X1236302Y754822D02*
X1217602Y773522D01*
G01X1236302Y752489D02*
X1217602Y771189D01*
G01X1236302Y750156D02*
X1217602Y768856D01*
G01X1236302Y747823D02*
X1217602Y766522D01*
G01X1236302Y745489D02*
X1217602Y764189D01*
G01X1236302Y743156D02*
X1217602Y761856D01*
G01Y744691D02*
X1236302Y763391D01*
G01Y799159D02*
X1231831Y803629D01*
G01X1236302Y796825D02*
X1229497Y803629D01*
G01X1236302Y794492D02*
X1227164Y803629D01*
G01X1217602Y793694D02*
X1227537Y803629D01*
G01X1217602Y796027D02*
X1225204Y803629D01*
G01X1217602Y798361D02*
X1222870Y803629D01*
G01X1217602Y800694D02*
X1220537Y803629D01*
G01X1217602Y803028D02*
X1218204Y803629D01*
G01X1236302Y792158D02*
X1224831Y803629D01*
G01X1236302Y789824D02*
X1222497Y803629D01*
G01X1217602D02*
X1236302D01*
G01X1234258Y721679D02*
X1236302Y723722D01*
G01Y803629D02*
Y721679D01*
G01Y801492D02*
X1234165Y803629D01*
G01X1311262Y721679D02*
X1313302Y723719D01*
G01X1308928Y721679D02*
X1313302Y726052D01*
G01X1306595Y721679D02*
X1313302Y728386D01*
G01X1304262Y721679D02*
X1313302Y730719D01*
G01X1301928Y721679D02*
X1313302Y733052D01*
G01X1299595Y721679D02*
X1313302Y735385D01*
G01X1297262Y721679D02*
X1313302Y737719D01*
G01X1294927Y721679D02*
X1313302Y740053D01*
G01X1294602Y723687D02*
X1313302Y742386D01*
G01X1294602Y726020D02*
X1313302Y744720D01*
G01X1294602Y728353D02*
X1313302Y747053D01*
G01X1294602Y730687D02*
X1313302Y749386D01*
G01X1294602Y733020D02*
X1313302Y751720D01*
G01X1294602Y735353D02*
X1313302Y754053D01*
G01X1294602Y737688D02*
X1313302Y756386D01*
G01X1294602Y740021D02*
X1313302Y758721D01*
G01X1294602Y742354D02*
X1313302Y761054D01*
G01Y743159D02*
X1294602Y761859D01*
G01X1313302Y740826D02*
X1294602Y759526D01*
G01X1313302Y738493D02*
X1294602Y757193D01*
G01X1313302Y736160D02*
X1294602Y754859D01*
G01X1313302Y733825D02*
X1294602Y752525D01*
G01X1313302Y731492D02*
X1294602Y750192D01*
G01X1313302Y729159D02*
X1294602Y747858D01*
G01X1313302Y726825D02*
X1294602Y745525D01*
G01X1313302Y724492D02*
X1294602Y743192D01*
G01X1313302Y722159D02*
X1294602Y740858D01*
G01X1311447Y721679D02*
X1294602Y738525D01*
G01X1309114Y721679D02*
X1294602Y736192D01*
G01X1306781Y721679D02*
X1294602Y733857D01*
G01X1304447Y721679D02*
X1294602Y731524D01*
G01X1302114Y721679D02*
X1294602Y729191D01*
G01X1299781Y721679D02*
X1294602Y726857D01*
G01X1297446Y721679D02*
X1294602Y724524D01*
G01X1295113Y721679D02*
X1294602Y722191D01*
G01X1313302Y721679D02*
X1294602D01*
G01X1313302Y803629D02*
Y721679D01*
G01X1294602D02*
Y803629D01*
G01Y779689D02*
X1313302Y798389D01*
G01X1294602Y782023D02*
X1313302Y800722D01*
G01X1294602Y784356D02*
X1313302Y803056D01*
G01X1294602Y786689D02*
X1311541Y803629D01*
G01X1294602Y789023D02*
X1309208Y803629D01*
G01X1294602Y791357D02*
X1306875Y803629D01*
G01X1313302Y792162D02*
X1301834Y803629D01*
G01X1313302Y789829D02*
X1299501Y803629D01*
G01X1313302Y787496D02*
X1297168Y803629D01*
G01X1313302Y785161D02*
X1294834Y803629D01*
G01X1313302Y782828D02*
X1294602Y801528D01*
G01X1313302Y780495D02*
X1294602Y799194D01*
G01Y747021D02*
X1313302Y765721D01*
G01X1294602Y749354D02*
X1313302Y768054D01*
G01X1294602Y751688D02*
X1313302Y770387D01*
G01X1294602Y754021D02*
X1313302Y772721D01*
G01X1294602Y756355D02*
X1313302Y775055D01*
G01X1294602Y758688D02*
X1313302Y777388D01*
G01X1294602Y761022D02*
X1313302Y779722D01*
G01X1294602Y763355D02*
X1313302Y782055D01*
G01X1294602Y765688D02*
X1313302Y784388D01*
G01X1294602Y768022D02*
X1313302Y786722D01*
G01X1294602Y770355D02*
X1313302Y789055D01*
G01X1294602Y772688D02*
X1313302Y791388D01*
G01X1294602Y775023D02*
X1313302Y793722D01*
G01X1294602Y777356D02*
X1313302Y796056D01*
G01Y778161D02*
X1294602Y796861D01*
G01X1313302Y775828D02*
X1294602Y794528D01*
G01X1313302Y773495D02*
X1294602Y792194D01*
G01X1313302Y771161D02*
X1294602Y789861D01*
G01X1313302Y768827D02*
X1294602Y787527D01*
G01X1313302Y766494D02*
X1294602Y785193D01*
G01X1313302Y764160D02*
X1294602Y782860D01*
G01X1313302Y761827D02*
X1294602Y780527D01*
G01X1313302Y759494D02*
X1294602Y778193D01*
G01X1313302Y757160D02*
X1294602Y775860D01*
G01X1313302Y754827D02*
X1294602Y773527D01*
G01X1313302Y752494D02*
X1294602Y771192D01*
G01X1313302Y750159D02*
X1294602Y768859D01*
G01X1313302Y747826D02*
X1294602Y766526D01*
G01Y744688D02*
X1313302Y763387D01*
G01Y745493D02*
X1294602Y764193D01*
G01Y793690D02*
X1304540Y803629D01*
G01X1294602Y796024D02*
X1302207Y803629D01*
G01X1294602Y798357D02*
X1299874Y803629D01*
G01X1294602Y800690D02*
X1297540Y803629D01*
G01X1294602Y803024D02*
X1295207Y803629D01*
G01X1313302Y801495D02*
X1311168Y803629D01*
G01X1313302Y799162D02*
X1308835Y803629D01*
G01X1313302Y796829D02*
X1306502Y803629D01*
G01X1313302Y794496D02*
X1304169Y803629D01*
G01X1294602D02*
X1313302D01*
M02*
